G04 ================== begin FILE IDENTIFICATION RECORD ==================*
G04 Layout Name:  t6m_pdb_d_0928_1400_274.brd*
G04 Film Name:    fab.art*
G04 File Format:  Gerber RS274X*
G04 File Origin:  Cadence Allegro 16.3-S048*
G04 Origin Date:  Tue Nov 26 11:01:52 2013*
G04 *
G04 Layer:  MANUFACTURING/NCDRILL_LEGEND*
G04 Layer:  MANUFACTURING/NCDRILL_FIGURE*
G04 Layer:  MANUFACTURING/NCLEGEND-1-8*
G04 Layer:  MANUFACTURING/PHOTOPLOT_OUTLINE*
G04 Layer:  MANUFACTURING/DIMENSION*
G04 Layer:  MANUFACTURING/DETAILS*
G04 Layer:  DRAWING FORMAT/TITLE_BLOCK*
G04 Layer:  DRAWING FORMAT/TITLE_DATA_FAB*
G04 Layer:  BOARD GEOMETRY/OUTLINE*
G04 *
G04 Offset:    (0.00 0.00)*
G04 Mirror:    No*
G04 Mode:      Positive*
G04 Rotation:  0*
G04 FullContactRelief:  No*
G04 UndefLineWidth:     6.00*
G04 ================== end FILE IDENTIFICATION RECORD ====================*
%FSLAX25Y25*MOIN*%
%IR0*IPPOS*OFA0.00000B0.00000*MIA0B0*SFA1.00000B1.00000*%
%AMMACRO17*
1,1,.006,.014497,-.035*
20,1,.006,.014497,-.035,-.014497,-.035,0.0*
1,1,.006,-.014497,-.035*
20,1,.006,-.014497,-.035,-.035,-.014497,0.0*
1,1,.006,-.035,-.014497*
20,1,.006,-.035,-.014497,-.035,.014497,0.0*
1,1,.006,-.035,.014497*
20,1,.006,-.035,.014497,-.014497,.035,0.0*
1,1,.006,-.014497,.035*
20,1,.006,-.014497,.035,.014497,.035,0.0*
1,1,.006,.014497,.035*
20,1,.006,.014497,.035,.035,.014497,0.0*
1,1,.006,.035,.014497*
20,1,.006,.035,.014497,.035,-.014497,0.0*
1,1,.006,.035,-.014497*
20,1,.006,.035,-.014497,.014497,-.035,0.0*
1,1,.006,.014497,-.035*
1,1,.006,-.0385,-.0175*
20,1,.006,-.0385,-.0175,-.0385,.01225,0.0*
1,1,.006,-.0385,.01225*
20,1,.006,-.0385,.01225,-.03733,.01517,0.0*
1,1,.006,-.03733,.01517*
20,1,.006,-.03733,.01517,-.035,.01692,0.0*
1,1,.006,-.035,.01692*
20,1,.006,-.035,.01692,-.0315,.0175,0.0*
1,1,.006,-.0315,.0175*
20,1,.006,-.0315,.0175,-.028,.01633,0.0*
1,1,.006,-.028,.01633*
20,1,.006,-.028,.01633,-.02625,.01342,0.0*
1,1,.006,-.02625,.01342*
1,1,.006,-.03325,.0035*
20,1,.006,-.03325,.0035,-.04492,.0035,0.0*
1,1,.006,-.04492,.0035*
1,1,.006,.00001,.00583*
20,1,.006,.00001,.00583,.00001,-.0175,0.0*
1,1,.006,.00001,-.0175*
1,1,.006,.00001,.01517*
20,1,.006,.00001,.01517,-.00116,.01575,0.0*
1,1,.006,-.00116,.01575*
20,1,.006,-.00116,.01575,-.00116,.01692,0.0*
1,1,.006,-.00116,.01692*
20,1,.006,-.00116,.01692,.00001,.0175,0.0*
1,1,.006,.00001,.0175*
20,1,.006,.00001,.0175,.00118,.01692,0.0*
1,1,.006,.00118,.01692*
20,1,.006,.00118,.01692,.00118,.01575,0.0*
1,1,.006,.00118,.01575*
20,1,.006,.00118,.01575,.00001,.01517,0.0*
1,1,.006,.00001,.01517*
1,1,.006,.03502,.0175*
20,1,.006,.03502,.0175,.03502,-.0175,0.0*
1,1,.006,.03502,-.0175*
1,1,.006,.02685,.00583*
20,1,.006,.02685,.00583,.04319,.00583,0.0*
1,1,.006,.04319,.00583*
%
%ADD17MACRO17*%
%AMMACRO28*
1,1,.006,.1575,0.0*
20,1,.006,.1575,0.0,-.1575,0.0,0.0*
1,1,.006,-.1575,0.0*
1,1,.006,0.0,.1575*
20,1,.006,0.0,.1575,0.0,-.1575,0.0*
1,1,.006,0.0,-.1575*
1,1,.006,.03938,.07087*
20,1,.006,.03938,.07087,.12338,.07087,0.0*
1,1,.006,.12338,.07087*
20,1,.006,.12338,.07087,.1155,.08925,0.0*
1,1,.006,.1155,.08925*
20,1,.006,.1155,.08925,.10238,.09975,0.0*
1,1,.006,.10238,.09975*
20,1,.006,.10238,.09975,.084,.105,0.0*
1,1,.006,.084,.105*
20,1,.006,.084,.105,.06563,.10237,0.0*
1,1,.006,.06563,.10237*
20,1,.006,.06563,.10237,.04987,.0945,0.0*
1,1,.006,.04987,.0945*
20,1,.006,.04987,.0945,.03938,.07612,0.0*
1,1,.006,.03938,.07612*
20,1,.006,.03938,.07612,.03412,.06037,0.0*
1,1,.006,.03412,.06037*
20,1,.006,.03412,.06037,.03412,.04463,0.0*
1,1,.006,.03412,.04463*
20,1,.006,.03412,.04463,.03938,.02887,0.0*
1,1,.006,.03938,.02887*
20,1,.006,.03938,.02887,.0525,.01312,0.0*
1,1,.006,.0525,.01312*
20,1,.006,.0525,.01312,.06825,.00262,0.0*
1,1,.006,.06825,.00262*
20,1,.006,.06825,.00262,.08663,0.0,0.0*
1,1,.006,.08663,0.0*
20,1,.006,.08663,0.0,.105,.00525,0.0*
1,1,.006,.105,.00525*
20,1,.006,.105,.00525,.12338,.021,0.0*
1,1,.006,.12338,.021*
1,1,.006,.28351,-.0525*
20,1,.006,.28351,-.0525,.28351,.105,0.0*
1,1,.006,.28351,.105*
1,1,.006,.28351,.08138*
20,1,.006,.28351,.08138,.27038,.0945,0.0*
1,1,.006,.27038,.0945*
20,1,.006,.27038,.0945,.25463,.10237,0.0*
1,1,.006,.25463,.10237*
20,1,.006,.25463,.10237,.23626,.105,0.0*
1,1,.006,.23626,.105*
20,1,.006,.23626,.105,.22051,.10237,0.0*
1,1,.006,.22051,.10237*
20,1,.006,.22051,.10237,.20214,.08925,0.0*
1,1,.006,.20214,.08925*
20,1,.006,.20214,.08925,.19163,.07087,0.0*
1,1,.006,.19163,.07087*
20,1,.006,.19163,.07087,.18901,.0525,0.0*
1,1,.006,.18901,.0525*
20,1,.006,.18901,.0525,.19163,.03412,0.0*
1,1,.006,.19163,.03412*
20,1,.006,.19163,.03412,.20214,.01575,0.0*
1,1,.006,.20214,.01575*
20,1,.006,.20214,.01575,.22051,.00262,0.0*
1,1,.006,.22051,.00262*
20,1,.006,.22051,.00262,.23626,0.0,0.0*
1,1,.006,.23626,0.0*
20,1,.006,.23626,0.0,.25463,.00262,0.0*
1,1,.006,.25463,.00262*
20,1,.006,.25463,.00262,.27038,.0105,0.0*
1,1,.006,.27038,.0105*
20,1,.006,.27038,.0105,.28351,.02362,0.0*
1,1,.006,.28351,.02362*
1,1,.006,.39377,.1575*
20,1,.006,.39377,.1575,.39377,0.0,0.0*
1,1,.006,.39377,0.0*
1,1,.006,.35702,.105*
20,1,.006,.35702,.105,.43052,.105,0.0*
1,1,.006,.43052,.105*
%
%ADD28MACRO28*%
%AMMACRO26*
1,1,.006,.042457,-.1025*
20,1,.006,.042457,-.1025,-.042457,-.1025,0.0*
1,1,.006,-.042457,-.1025*
20,1,.006,-.042457,-.1025,-.1025,-.042457,0.0*
1,1,.006,-.1025,-.042457*
20,1,.006,-.1025,-.042457,-.1025,.042457,0.0*
1,1,.006,-.1025,.042457*
20,1,.006,-.1025,.042457,-.042457,.1025,0.0*
1,1,.006,-.042457,.1025*
20,1,.006,-.042457,.1025,.042457,.1025,0.0*
1,1,.006,.042457,.1025*
20,1,.006,.042457,.1025,.1025,.042457,0.0*
1,1,.006,.1025,.042457*
20,1,.006,.1025,.042457,.1025,-.042457,0.0*
1,1,.006,.1025,-.042457*
20,1,.006,.1025,-.042457,.042457,-.1025,0.0*
1,1,.006,.042457,-.1025*
1,1,.006,-.14521,.01708*
20,1,.006,-.14521,.01708,-.12471,-.05125,0.0*
1,1,.006,-.12471,-.05125*
20,1,.006,-.12471,-.05125,-.1025,.01708,0.0*
1,1,.006,-.1025,.01708*
20,1,.006,-.1025,.01708,-.08029,-.05125,0.0*
1,1,.006,-.08029,-.05125*
20,1,.006,-.08029,-.05125,-.05979,.01708,0.0*
1,1,.006,-.05979,.01708*
1,1,.006,-.03074,-.08542*
20,1,.006,-.03074,-.08542,-.03074,.01708,0.0*
1,1,.006,-.03074,.01708*
1,1,.006,-.03074,.00171*
20,1,.006,-.03074,.00171,-.0222,.01025,0.0*
1,1,.006,-.0222,.01025*
20,1,.006,-.0222,.01025,-.01366,.01537,0.0*
1,1,.006,-.01366,.01537*
20,1,.006,-.01366,.01537,.00001,.01708,0.0*
1,1,.006,.00001,.01708*
20,1,.006,.00001,.01708,.01197,.01537,0.0*
1,1,.006,.01197,.01537*
20,1,.006,.01197,.01537,.02393,.00683,0.0*
1,1,.006,.02393,.00683*
20,1,.006,.02393,.00683,.02905,-.00513,0.0*
1,1,.006,.02905,-.00513*
20,1,.006,.02905,-.00513,.03076,-.01708,0.0*
1,1,.006,.03076,-.01708*
20,1,.006,.03076,-.01708,.02905,-.02904,0.0*
1,1,.006,.02905,-.02904*
20,1,.006,.02905,-.02904,.02393,-.041,0.0*
1,1,.006,.02393,-.041*
20,1,.006,.02393,-.041,.01368,-.04783,0.0*
1,1,.006,.01368,-.04783*
20,1,.006,.01368,-.04783,.00001,-.05125,0.0*
1,1,.006,.00001,-.05125*
20,1,.006,.00001,-.05125,-.01195,-.04954,0.0*
1,1,.006,-.01195,-.04954*
20,1,.006,-.01195,-.04954,-.02391,-.04442,0.0*
1,1,.006,-.02391,-.04442*
20,1,.006,-.02391,-.04442,-.03074,-.03759,0.0*
1,1,.006,-.03074,-.03759*
1,1,.006,.10252,.05125*
20,1,.006,.10252,.05125,.10252,-.05125,0.0*
1,1,.006,.10252,-.05125*
1,1,.006,.0786,.01708*
20,1,.006,.0786,.01708,.12644,.01708,0.0*
1,1,.006,.12644,.01708*
%
%ADD26MACRO26*%
%AMMACRO21*
1,1,.006,.035,.035*
20,1,.006,.035,.035,.035,-.035,0.0*
1,1,.006,.035,-.035*
20,1,.006,.035,-.035,-.035,-.035,0.0*
1,1,.006,-.035,-.035*
20,1,.006,-.035,-.035,-.035,.035,0.0*
1,1,.006,-.035,.035*
20,1,.006,-.035,.035,.035,.035,0.0*
1,1,.006,.035,.035*
1,1,.006,-.035,.0175*
20,1,.006,-.035,.0175,-.03967,.01633,0.0*
1,1,.006,-.03967,.01633*
20,1,.006,-.03967,.01633,-.04317,.01342,0.0*
1,1,.006,-.04317,.01342*
20,1,.006,-.04317,.01342,-.0455,.00992,0.0*
1,1,.006,-.0455,.00992*
20,1,.006,-.0455,.00992,-.04725,.00525,0.0*
1,1,.006,-.04725,.00525*
20,1,.006,-.04725,.00525,-.04783,0.0,0.0*
1,1,.006,-.04783,0.0*
20,1,.006,-.04783,0.0,-.04725,-.00525,0.0*
1,1,.006,-.04725,-.00525*
20,1,.006,-.04725,-.00525,-.0455,-.00992,0.0*
1,1,.006,-.0455,-.00992*
20,1,.006,-.0455,-.00992,-.04317,-.01342,0.0*
1,1,.006,-.04317,-.01342*
20,1,.006,-.04317,-.01342,-.03967,-.01633,0.0*
1,1,.006,-.03967,-.01633*
20,1,.006,-.03967,-.01633,-.035,-.0175,0.0*
1,1,.006,-.035,-.0175*
20,1,.006,-.035,-.0175,-.03033,-.01633,0.0*
1,1,.006,-.03033,-.01633*
20,1,.006,-.03033,-.01633,-.02683,-.01342,0.0*
1,1,.006,-.02683,-.01342*
20,1,.006,-.02683,-.01342,-.0245,-.00992,0.0*
1,1,.006,-.0245,-.00992*
20,1,.006,-.0245,-.00992,-.02275,-.00525,0.0*
1,1,.006,-.02275,-.00525*
20,1,.006,-.02275,-.00525,-.02217,0.0,0.0*
1,1,.006,-.02217,0.0*
20,1,.006,-.02217,0.0,-.02275,.00525,0.0*
1,1,.006,-.02275,.00525*
20,1,.006,-.02275,.00525,-.0245,.00992,0.0*
1,1,.006,-.0245,.00992*
20,1,.006,-.0245,.00992,-.02683,.01342,0.0*
1,1,.006,-.02683,.01342*
20,1,.006,-.02683,.01342,-.03033,.01633,0.0*
1,1,.006,-.03033,.01633*
20,1,.006,-.03033,.01633,-.035,.0175,0.0*
1,1,.006,-.035,.0175*
1,1,.006,-.01107,.01167*
20,1,.006,-.01107,.01167,-.00757,.01517,0.0*
1,1,.006,-.00757,.01517*
20,1,.006,-.00757,.01517,-.00349,.01692,0.0*
1,1,.006,-.00349,.01692*
20,1,.006,-.00349,.01692,.00118,.0175,0.0*
1,1,.006,.00118,.0175*
20,1,.006,.00118,.0175,.00701,.01633,0.0*
1,1,.006,.00701,.01633*
20,1,.006,.00701,.01633,.01109,.01342,0.0*
1,1,.006,.01109,.01342*
20,1,.006,.01109,.01342,.01226,.00992,0.0*
1,1,.006,.01226,.00992*
20,1,.006,.01226,.00992,.01168,.00642,0.0*
1,1,.006,.01168,.00642*
20,1,.006,.01168,.00642,.00934,.0035,0.0*
1,1,.006,.00934,.0035*
20,1,.006,.00934,.0035,-.00232,-.00233,0.0*
1,1,.006,-.00232,-.00233*
20,1,.006,-.00232,-.00233,-.00757,-.00642,0.0*
1,1,.006,-.00757,-.00642*
20,1,.006,-.00757,-.00642,-.01107,-.01225,0.0*
1,1,.006,-.01107,-.01225*
20,1,.006,-.01107,-.01225,-.01224,-.0175,0.0*
1,1,.006,-.01224,-.0175*
20,1,.006,-.01224,-.0175,.01226,-.0175,0.0*
1,1,.006,.01226,-.0175*
1,1,.006,.02394,.01167*
20,1,.006,.02394,.01167,.02744,.01517,0.0*
1,1,.006,.02744,.01517*
20,1,.006,.02744,.01517,.03152,.01692,0.0*
1,1,.006,.03152,.01692*
20,1,.006,.03152,.01692,.03619,.0175,0.0*
1,1,.006,.03619,.0175*
20,1,.006,.03619,.0175,.04202,.01633,0.0*
1,1,.006,.04202,.01633*
20,1,.006,.04202,.01633,.0461,.01342,0.0*
1,1,.006,.0461,.01342*
20,1,.006,.0461,.01342,.04727,.00992,0.0*
1,1,.006,.04727,.00992*
20,1,.006,.04727,.00992,.04669,.00642,0.0*
1,1,.006,.04669,.00642*
20,1,.006,.04669,.00642,.04435,.0035,0.0*
1,1,.006,.04435,.0035*
20,1,.006,.04435,.0035,.03269,-.00233,0.0*
1,1,.006,.03269,-.00233*
20,1,.006,.03269,-.00233,.02744,-.00642,0.0*
1,1,.006,.02744,-.00642*
20,1,.006,.02744,-.00642,.02394,-.01225,0.0*
1,1,.006,.02394,-.01225*
20,1,.006,.02394,-.01225,.02277,-.0175,0.0*
1,1,.006,.02277,-.0175*
20,1,.006,.02277,-.0175,.04727,-.0175,0.0*
1,1,.006,.04727,-.0175*
%
%ADD21MACRO21*%
%AMMACRO16*
1,1,.006,.035,.035*
20,1,.006,.035,.035,.035,-.035,0.0*
1,1,.006,.035,-.035*
20,1,.006,.035,-.035,-.035,-.035,0.0*
1,1,.006,-.035,-.035*
20,1,.006,-.035,-.035,-.035,.035,0.0*
1,1,.006,-.035,.035*
20,1,.006,-.035,.035,.035,.035,0.0*
1,1,.006,.035,.035*
1,1,.006,-.035,.0175*
20,1,.006,-.035,.0175,-.03967,.01633,0.0*
1,1,.006,-.03967,.01633*
20,1,.006,-.03967,.01633,-.04317,.01342,0.0*
1,1,.006,-.04317,.01342*
20,1,.006,-.04317,.01342,-.0455,.00992,0.0*
1,1,.006,-.0455,.00992*
20,1,.006,-.0455,.00992,-.04725,.00525,0.0*
1,1,.006,-.04725,.00525*
20,1,.006,-.04725,.00525,-.04783,0.0,0.0*
1,1,.006,-.04783,0.0*
20,1,.006,-.04783,0.0,-.04725,-.00525,0.0*
1,1,.006,-.04725,-.00525*
20,1,.006,-.04725,-.00525,-.0455,-.00992,0.0*
1,1,.006,-.0455,-.00992*
20,1,.006,-.0455,-.00992,-.04317,-.01342,0.0*
1,1,.006,-.04317,-.01342*
20,1,.006,-.04317,-.01342,-.03967,-.01633,0.0*
1,1,.006,-.03967,-.01633*
20,1,.006,-.03967,-.01633,-.035,-.0175,0.0*
1,1,.006,-.035,-.0175*
20,1,.006,-.035,-.0175,-.03033,-.01633,0.0*
1,1,.006,-.03033,-.01633*
20,1,.006,-.03033,-.01633,-.02683,-.01342,0.0*
1,1,.006,-.02683,-.01342*
20,1,.006,-.02683,-.01342,-.0245,-.00992,0.0*
1,1,.006,-.0245,-.00992*
20,1,.006,-.0245,-.00992,-.02275,-.00525,0.0*
1,1,.006,-.02275,-.00525*
20,1,.006,-.02275,-.00525,-.02217,0.0,0.0*
1,1,.006,-.02217,0.0*
20,1,.006,-.02217,0.0,-.02275,.00525,0.0*
1,1,.006,-.02275,.00525*
20,1,.006,-.02275,.00525,-.0245,.00992,0.0*
1,1,.006,-.0245,.00992*
20,1,.006,-.0245,.00992,-.02683,.01342,0.0*
1,1,.006,-.02683,.01342*
20,1,.006,-.02683,.01342,-.03033,.01633,0.0*
1,1,.006,-.03033,.01633*
20,1,.006,-.03033,.01633,-.035,.0175,0.0*
1,1,.006,-.035,.0175*
1,1,.006,.00701,-.0175*
20,1,.006,.00701,-.0175,.00701,.0175,0.0*
1,1,.006,.00701,.0175*
20,1,.006,.00701,.0175,-.01457,-.00758,0.0*
1,1,.006,-.01457,-.00758*
20,1,.006,-.01457,-.00758,.01459,-.00758,0.0*
1,1,.006,.01459,-.00758*
1,1,.006,.03502,.0175*
20,1,.006,.03502,.0175,.03035,.01633,0.0*
1,1,.006,.03035,.01633*
20,1,.006,.03035,.01633,.02685,.01342,0.0*
1,1,.006,.02685,.01342*
20,1,.006,.02685,.01342,.02452,.00992,0.0*
1,1,.006,.02452,.00992*
20,1,.006,.02452,.00992,.02277,.00525,0.0*
1,1,.006,.02277,.00525*
20,1,.006,.02277,.00525,.02219,0.0,0.0*
1,1,.006,.02219,0.0*
20,1,.006,.02219,0.0,.02277,-.00525,0.0*
1,1,.006,.02277,-.00525*
20,1,.006,.02277,-.00525,.02452,-.00992,0.0*
1,1,.006,.02452,-.00992*
20,1,.006,.02452,-.00992,.02685,-.01342,0.0*
1,1,.006,.02685,-.01342*
20,1,.006,.02685,-.01342,.03035,-.01633,0.0*
1,1,.006,.03035,-.01633*
20,1,.006,.03035,-.01633,.03502,-.0175,0.0*
1,1,.006,.03502,-.0175*
20,1,.006,.03502,-.0175,.03969,-.01633,0.0*
1,1,.006,.03969,-.01633*
20,1,.006,.03969,-.01633,.04319,-.01342,0.0*
1,1,.006,.04319,-.01342*
20,1,.006,.04319,-.01342,.04552,-.00992,0.0*
1,1,.006,.04552,-.00992*
20,1,.006,.04552,-.00992,.04727,-.00525,0.0*
1,1,.006,.04727,-.00525*
20,1,.006,.04727,-.00525,.04785,0.0,0.0*
1,1,.006,.04785,0.0*
20,1,.006,.04785,0.0,.04727,.00525,0.0*
1,1,.006,.04727,.00525*
20,1,.006,.04727,.00525,.04552,.00992,0.0*
1,1,.006,.04552,.00992*
20,1,.006,.04552,.00992,.04319,.01342,0.0*
1,1,.006,.04319,.01342*
20,1,.006,.04319,.01342,.03969,.01633,0.0*
1,1,.006,.03969,.01633*
20,1,.006,.03969,.01633,.03502,.0175,0.0*
1,1,.006,.03502,.0175*
%
%ADD16MACRO16*%
%AMMACRO18*
1,1,.006,.0475,0.0*
20,1,.006,.0475,0.0,0.0,-.0475,0.0*
1,1,.006,0.0,-.0475*
20,1,.006,0.0,-.0475,-.0475,0.0,0.0*
1,1,.006,-.0475,0.0*
20,1,.006,-.0475,0.0,0.0,.0475,0.0*
1,1,.006,0.0,.0475*
20,1,.006,0.0,.0475,.0475,0.0,0.0*
1,1,.006,.0475,0.0*
1,1,.006,-.06175,-.03958*
20,1,.006,-.06175,-.03958,-.06175,.00792,0.0*
1,1,.006,-.06175,.00792*
1,1,.006,-.06175,.00079*
20,1,.006,-.06175,.00079,-.05779,.00475,0.0*
1,1,.006,-.05779,.00475*
20,1,.006,-.05779,.00475,-.05383,.00712,0.0*
1,1,.006,-.05383,.00712*
20,1,.006,-.05383,.00712,-.0475,.00792,0.0*
1,1,.006,-.0475,.00792*
20,1,.006,-.0475,.00792,-.04196,.00712,0.0*
1,1,.006,-.04196,.00712*
20,1,.006,-.04196,.00712,-.03642,.00317,0.0*
1,1,.006,-.03642,.00317*
20,1,.006,-.03642,.00317,-.03404,-.00238,0.0*
1,1,.006,-.03404,-.00238*
20,1,.006,-.03404,-.00238,-.03325,-.00792,0.0*
1,1,.006,-.03325,-.00792*
20,1,.006,-.03325,-.00792,-.03404,-.01346,0.0*
1,1,.006,-.03404,-.01346*
20,1,.006,-.03404,-.01346,-.03642,-.019,0.0*
1,1,.006,-.03642,-.019*
20,1,.006,-.03642,-.019,-.04117,-.02217,0.0*
1,1,.006,-.04117,-.02217*
20,1,.006,-.04117,-.02217,-.0475,-.02375,0.0*
1,1,.006,-.0475,-.02375*
20,1,.006,-.0475,-.02375,-.05304,-.02296,0.0*
1,1,.006,-.05304,-.02296*
20,1,.006,-.05304,-.02296,-.05858,-.02058,0.0*
1,1,.006,-.05858,-.02058*
20,1,.006,-.05858,-.02058,-.06175,-.01742,0.0*
1,1,.006,-.06175,-.01742*
1,1,.006,.00001,-.02375*
20,1,.006,.00001,-.02375,-.00474,-.02296,0.0*
1,1,.006,-.00474,-.02296*
20,1,.006,-.00474,-.02296,-.00949,-.01979,0.0*
1,1,.006,-.00949,-.01979*
20,1,.006,-.00949,-.01979,-.01266,-.01425,0.0*
1,1,.006,-.01266,-.01425*
20,1,.006,-.01266,-.01425,-.01424,-.00792,0.0*
1,1,.006,-.01424,-.00792*
20,1,.006,-.01424,-.00792,-.01266,-.00158,0.0*
1,1,.006,-.01266,-.00158*
20,1,.006,-.01266,-.00158,-.00949,.00396,0.0*
1,1,.006,-.00949,.00396*
20,1,.006,-.00949,.00396,-.00474,.00712,0.0*
1,1,.006,-.00474,.00712*
20,1,.006,-.00474,.00712,.00001,.00792,0.0*
1,1,.006,.00001,.00792*
20,1,.006,.00001,.00792,.00476,.00712,0.0*
1,1,.006,.00476,.00712*
20,1,.006,.00476,.00712,.00951,.00396,0.0*
1,1,.006,.00951,.00396*
20,1,.006,.00951,.00396,.01268,-.00158,0.0*
1,1,.006,.01268,-.00158*
20,1,.006,.01268,-.00158,.01347,-.00792,0.0*
1,1,.006,.01347,-.00792*
20,1,.006,.01347,-.00792,.01268,-.01425,0.0*
1,1,.006,.01268,-.01425*
20,1,.006,.01268,-.01425,.00951,-.01979,0.0*
1,1,.006,.00951,-.01979*
20,1,.006,.00951,-.01979,.00476,-.02296,0.0*
1,1,.006,.00476,-.02296*
20,1,.006,.00476,-.02296,.00001,-.02375,0.0*
1,1,.006,.00001,-.02375*
1,1,.006,.04752,.02375*
20,1,.006,.04752,.02375,.04752,-.02375,0.0*
1,1,.006,.04752,-.02375*
1,1,.006,.03644,.00792*
20,1,.006,.03644,.00792,.0586,.00792,0.0*
1,1,.006,.0586,.00792*
%
%ADD18MACRO18*%
%AMMACRO13*
1,1,.006,.035,.035*
20,1,.006,.035,.035,.035,-.035,0.0*
1,1,.006,.035,-.035*
20,1,.006,.035,-.035,-.035,-.035,0.0*
1,1,.006,-.035,-.035*
20,1,.006,-.035,-.035,-.035,.035,0.0*
1,1,.006,-.035,.035*
20,1,.006,-.035,.035,.035,.035,0.0*
1,1,.006,.035,.035*
1,1,.006,-.035,.0175*
20,1,.006,-.035,.0175,-.03967,.01633,0.0*
1,1,.006,-.03967,.01633*
20,1,.006,-.03967,.01633,-.04317,.01342,0.0*
1,1,.006,-.04317,.01342*
20,1,.006,-.04317,.01342,-.0455,.00992,0.0*
1,1,.006,-.0455,.00992*
20,1,.006,-.0455,.00992,-.04725,.00525,0.0*
1,1,.006,-.04725,.00525*
20,1,.006,-.04725,.00525,-.04783,0.0,0.0*
1,1,.006,-.04783,0.0*
20,1,.006,-.04783,0.0,-.04725,-.00525,0.0*
1,1,.006,-.04725,-.00525*
20,1,.006,-.04725,-.00525,-.0455,-.00992,0.0*
1,1,.006,-.0455,-.00992*
20,1,.006,-.0455,-.00992,-.04317,-.01342,0.0*
1,1,.006,-.04317,-.01342*
20,1,.006,-.04317,-.01342,-.03967,-.01633,0.0*
1,1,.006,-.03967,-.01633*
20,1,.006,-.03967,-.01633,-.035,-.0175,0.0*
1,1,.006,-.035,-.0175*
20,1,.006,-.035,-.0175,-.03033,-.01633,0.0*
1,1,.006,-.03033,-.01633*
20,1,.006,-.03033,-.01633,-.02683,-.01342,0.0*
1,1,.006,-.02683,-.01342*
20,1,.006,-.02683,-.01342,-.0245,-.00992,0.0*
1,1,.006,-.0245,-.00992*
20,1,.006,-.0245,-.00992,-.02275,-.00525,0.0*
1,1,.006,-.02275,-.00525*
20,1,.006,-.02275,-.00525,-.02217,0.0,0.0*
1,1,.006,-.02217,0.0*
20,1,.006,-.02217,0.0,-.02275,.00525,0.0*
1,1,.006,-.02275,.00525*
20,1,.006,-.02275,.00525,-.0245,.00992,0.0*
1,1,.006,-.0245,.00992*
20,1,.006,-.0245,.00992,-.02683,.01342,0.0*
1,1,.006,-.02683,.01342*
20,1,.006,-.02683,.01342,-.03033,.01633,0.0*
1,1,.006,-.03033,.01633*
20,1,.006,-.03033,.01633,-.035,.0175,0.0*
1,1,.006,-.035,.0175*
1,1,.006,-.01282,-.0105*
20,1,.006,-.01282,-.0105,-.00932,-.01458,0.0*
1,1,.006,-.00932,-.01458*
20,1,.006,-.00932,-.01458,-.00466,-.01692,0.0*
1,1,.006,-.00466,-.01692*
20,1,.006,-.00466,-.01692,.00059,-.0175,0.0*
1,1,.006,.00059,-.0175*
20,1,.006,.00059,-.0175,.00526,-.01692,0.0*
1,1,.006,.00526,-.01692*
20,1,.006,.00526,-.01692,.00993,-.014,0.0*
1,1,.006,.00993,-.014*
20,1,.006,.00993,-.014,.01284,-.0105,0.0*
1,1,.006,.01284,-.0105*
20,1,.006,.01284,-.0105,.01343,-.007,0.0*
1,1,.006,.01343,-.007*
20,1,.006,.01343,-.007,.01226,-.00292,0.0*
1,1,.006,.01226,-.00292*
20,1,.006,.01226,-.00292,.00818,0.0,0.0*
1,1,.006,.00818,0.0*
20,1,.006,.00818,0.0,.00409,.00117,0.0*
1,1,.006,.00409,.00117*
20,1,.006,.00409,.00117,-.00116,.00117,0.0*
1,1,.006,-.00116,.00117*
1,1,.006,.00409,.00117*
20,1,.006,.00409,.00117,.00759,.00292,0.0*
1,1,.006,.00759,.00292*
20,1,.006,.00759,.00292,.01051,.00583,0.0*
1,1,.006,.01051,.00583*
20,1,.006,.01051,.00583,.01168,.00933,0.0*
1,1,.006,.01168,.00933*
20,1,.006,.01168,.00933,.01051,.01283,0.0*
1,1,.006,.01051,.01283*
20,1,.006,.01051,.01283,.00759,.01575,0.0*
1,1,.006,.00759,.01575*
20,1,.006,.00759,.01575,.00234,.0175,0.0*
1,1,.006,.00234,.0175*
20,1,.006,.00234,.0175,-.00291,.01692,0.0*
1,1,.006,-.00291,.01692*
20,1,.006,-.00291,.01692,-.00816,.01458,0.0*
1,1,.006,-.00816,.01458*
1,1,.006,.02394,-.00292*
20,1,.006,.02394,-.00292,.02802,.00117,0.0*
1,1,.006,.02802,.00117*
20,1,.006,.02802,.00117,.03152,.0035,0.0*
1,1,.006,.03152,.0035*
20,1,.006,.03152,.0035,.03619,.00467,0.0*
1,1,.006,.03619,.00467*
20,1,.006,.03619,.00467,.04027,.0035,0.0*
1,1,.006,.04027,.0035*
20,1,.006,.04027,.0035,.04319,.00117,0.0*
1,1,.006,.04319,.00117*
20,1,.006,.04319,.00117,.04552,-.00233,0.0*
1,1,.006,.04552,-.00233*
20,1,.006,.04552,-.00233,.0461,-.00642,0.0*
1,1,.006,.0461,-.00642*
20,1,.006,.0461,-.00642,.04552,-.00992,0.0*
1,1,.006,.04552,-.00992*
20,1,.006,.04552,-.00992,.04319,-.01342,0.0*
1,1,.006,.04319,-.01342*
20,1,.006,.04319,-.01342,.03969,-.01633,0.0*
1,1,.006,.03969,-.01633*
20,1,.006,.03969,-.01633,.0356,-.0175,0.0*
1,1,.006,.0356,-.0175*
20,1,.006,.0356,-.0175,.03094,-.01633,0.0*
1,1,.006,.03094,-.01633*
20,1,.006,.03094,-.01633,.02685,-.01283,0.0*
1,1,.006,.02685,-.01283*
20,1,.006,.02685,-.01283,.02452,-.00758,0.0*
1,1,.006,.02452,-.00758*
20,1,.006,.02452,-.00758,.02394,-.00175,0.0*
1,1,.006,.02394,-.00175*
20,1,.006,.02394,-.00175,.0251,.00583,0.0*
1,1,.006,.0251,.00583*
20,1,.006,.0251,.00583,.02685,.00992,0.0*
1,1,.006,.02685,.00992*
20,1,.006,.02685,.00992,.02977,.014,0.0*
1,1,.006,.02977,.014*
20,1,.006,.02977,.014,.03385,.01692,0.0*
1,1,.006,.03385,.01692*
20,1,.006,.03385,.01692,.03794,.0175,0.0*
1,1,.006,.03794,.0175*
20,1,.006,.03794,.0175,.04202,.01633,0.0*
1,1,.006,.04202,.01633*
20,1,.006,.04202,.01633,.04494,.01342,0.0*
1,1,.006,.04494,.01342*
%
%ADD13MACRO13*%
%AMMACRO24*
1,1,.006,.0495,0.0*
20,1,.006,.0495,0.0,0.0,-.0495,0.0*
1,1,.006,0.0,-.0495*
20,1,.006,0.0,-.0495,-.0495,0.0,0.0*
1,1,.006,-.0495,0.0*
20,1,.006,-.0495,0.0,0.0,.0495,0.0*
1,1,.006,0.0,.0495*
20,1,.006,0.0,.0495,.0495,0.0,0.0*
1,1,.006,.0495,0.0*
1,1,.006,-.06435,-.04125*
20,1,.006,-.06435,-.04125,-.06435,.00825,0.0*
1,1,.006,-.06435,.00825*
1,1,.006,-.06435,.00083*
20,1,.006,-.06435,.00083,-.06022,.00495,0.0*
1,1,.006,-.06022,.00495*
20,1,.006,-.06022,.00495,-.0561,.00742,0.0*
1,1,.006,-.0561,.00742*
20,1,.006,-.0561,.00742,-.0495,.00825,0.0*
1,1,.006,-.0495,.00825*
20,1,.006,-.0495,.00825,-.04373,.00742,0.0*
1,1,.006,-.04373,.00742*
20,1,.006,-.04373,.00742,-.03795,.0033,0.0*
1,1,.006,-.03795,.0033*
20,1,.006,-.03795,.0033,-.03547,-.00248,0.0*
1,1,.006,-.03547,-.00248*
20,1,.006,-.03547,-.00248,-.03465,-.00825,0.0*
1,1,.006,-.03465,-.00825*
20,1,.006,-.03465,-.00825,-.03547,-.01403,0.0*
1,1,.006,-.03547,-.01403*
20,1,.006,-.03547,-.01403,-.03795,-.0198,0.0*
1,1,.006,-.03795,-.0198*
20,1,.006,-.03795,-.0198,-.0429,-.0231,0.0*
1,1,.006,-.0429,-.0231*
20,1,.006,-.0429,-.0231,-.0495,-.02475,0.0*
1,1,.006,-.0495,-.02475*
20,1,.006,-.0495,-.02475,-.05527,-.02393,0.0*
1,1,.006,-.05527,-.02393*
20,1,.006,-.05527,-.02393,-.06105,-.02145,0.0*
1,1,.006,-.06105,-.02145*
20,1,.006,-.06105,-.02145,-.06435,-.01815,0.0*
1,1,.006,-.06435,-.01815*
1,1,.006,.00001,-.02475*
20,1,.006,.00001,-.02475,-.00494,-.02393,0.0*
1,1,.006,-.00494,-.02393*
20,1,.006,-.00494,-.02393,-.00989,-.02063,0.0*
1,1,.006,-.00989,-.02063*
20,1,.006,-.00989,-.02063,-.01319,-.01485,0.0*
1,1,.006,-.01319,-.01485*
20,1,.006,-.01319,-.01485,-.01484,-.00825,0.0*
1,1,.006,-.01484,-.00825*
20,1,.006,-.01484,-.00825,-.01319,-.00165,0.0*
1,1,.006,-.01319,-.00165*
20,1,.006,-.01319,-.00165,-.00989,.00412,0.0*
1,1,.006,-.00989,.00412*
20,1,.006,-.00989,.00412,-.00494,.00742,0.0*
1,1,.006,-.00494,.00742*
20,1,.006,-.00494,.00742,.00001,.00825,0.0*
1,1,.006,.00001,.00825*
20,1,.006,.00001,.00825,.00496,.00742,0.0*
1,1,.006,.00496,.00742*
20,1,.006,.00496,.00742,.00991,.00412,0.0*
1,1,.006,.00991,.00412*
20,1,.006,.00991,.00412,.01321,-.00165,0.0*
1,1,.006,.01321,-.00165*
20,1,.006,.01321,-.00165,.01404,-.00825,0.0*
1,1,.006,.01404,-.00825*
20,1,.006,.01404,-.00825,.01321,-.01485,0.0*
1,1,.006,.01321,-.01485*
20,1,.006,.01321,-.01485,.00991,-.02063,0.0*
1,1,.006,.00991,-.02063*
20,1,.006,.00991,-.02063,.00496,-.02393,0.0*
1,1,.006,.00496,-.02393*
20,1,.006,.00496,-.02393,.00001,-.02475,0.0*
1,1,.006,.00001,-.02475*
1,1,.006,.04952,-.02475*
20,1,.006,.04952,-.02475,.04457,-.02393,0.0*
1,1,.006,.04457,-.02393*
20,1,.006,.04457,-.02393,.03962,-.02063,0.0*
1,1,.006,.03962,-.02063*
20,1,.006,.03962,-.02063,.03632,-.01485,0.0*
1,1,.006,.03632,-.01485*
20,1,.006,.03632,-.01485,.03467,-.00825,0.0*
1,1,.006,.03467,-.00825*
20,1,.006,.03467,-.00825,.03632,-.00165,0.0*
1,1,.006,.03632,-.00165*
20,1,.006,.03632,-.00165,.03962,.00412,0.0*
1,1,.006,.03962,.00412*
20,1,.006,.03962,.00412,.04457,.00742,0.0*
1,1,.006,.04457,.00742*
20,1,.006,.04457,.00742,.04952,.00825,0.0*
1,1,.006,.04952,.00825*
20,1,.006,.04952,.00825,.05447,.00742,0.0*
1,1,.006,.05447,.00742*
20,1,.006,.05447,.00742,.05942,.00412,0.0*
1,1,.006,.05942,.00412*
20,1,.006,.05942,.00412,.06272,-.00165,0.0*
1,1,.006,.06272,-.00165*
20,1,.006,.06272,-.00165,.06355,-.00825,0.0*
1,1,.006,.06355,-.00825*
20,1,.006,.06355,-.00825,.06272,-.01485,0.0*
1,1,.006,.06272,-.01485*
20,1,.006,.06272,-.01485,.05942,-.02063,0.0*
1,1,.006,.05942,-.02063*
20,1,.006,.05942,-.02063,.05447,-.02393,0.0*
1,1,.006,.05447,-.02393*
20,1,.006,.05447,-.02393,.04952,-.02475,0.0*
1,1,.006,.04952,-.02475*
%
%ADD24MACRO24*%
%AMMACRO10*
1,1,.006,.035,.035*
20,1,.006,.035,.035,.035,-.035,0.0*
1,1,.006,.035,-.035*
20,1,.006,.035,-.035,-.035,-.035,0.0*
1,1,.006,-.035,-.035*
20,1,.006,-.035,-.035,-.035,.035,0.0*
1,1,.006,-.035,.035*
20,1,.006,-.035,.035,.035,.035,0.0*
1,1,.006,.035,.035*
1,1,.006,-.035,.0175*
20,1,.006,-.035,.0175,-.03967,.01633,0.0*
1,1,.006,-.03967,.01633*
20,1,.006,-.03967,.01633,-.04317,.01342,0.0*
1,1,.006,-.04317,.01342*
20,1,.006,-.04317,.01342,-.0455,.00992,0.0*
1,1,.006,-.0455,.00992*
20,1,.006,-.0455,.00992,-.04725,.00525,0.0*
1,1,.006,-.04725,.00525*
20,1,.006,-.04725,.00525,-.04783,0.0,0.0*
1,1,.006,-.04783,0.0*
20,1,.006,-.04783,0.0,-.04725,-.00525,0.0*
1,1,.006,-.04725,-.00525*
20,1,.006,-.04725,-.00525,-.0455,-.00992,0.0*
1,1,.006,-.0455,-.00992*
20,1,.006,-.0455,-.00992,-.04317,-.01342,0.0*
1,1,.006,-.04317,-.01342*
20,1,.006,-.04317,-.01342,-.03967,-.01633,0.0*
1,1,.006,-.03967,-.01633*
20,1,.006,-.03967,-.01633,-.035,-.0175,0.0*
1,1,.006,-.035,-.0175*
20,1,.006,-.035,-.0175,-.03033,-.01633,0.0*
1,1,.006,-.03033,-.01633*
20,1,.006,-.03033,-.01633,-.02683,-.01342,0.0*
1,1,.006,-.02683,-.01342*
20,1,.006,-.02683,-.01342,-.0245,-.00992,0.0*
1,1,.006,-.0245,-.00992*
20,1,.006,-.0245,-.00992,-.02275,-.00525,0.0*
1,1,.006,-.02275,-.00525*
20,1,.006,-.02275,-.00525,-.02217,0.0,0.0*
1,1,.006,-.02217,0.0*
20,1,.006,-.02217,0.0,-.02275,.00525,0.0*
1,1,.006,-.02275,.00525*
20,1,.006,-.02275,.00525,-.0245,.00992,0.0*
1,1,.006,-.0245,.00992*
20,1,.006,-.0245,.00992,-.02683,.01342,0.0*
1,1,.006,-.02683,.01342*
20,1,.006,-.02683,.01342,-.03033,.01633,0.0*
1,1,.006,-.03033,.01633*
20,1,.006,-.03033,.01633,-.035,.0175,0.0*
1,1,.006,-.035,.0175*
1,1,.006,-.01282,-.0105*
20,1,.006,-.01282,-.0105,-.00932,-.01458,0.0*
1,1,.006,-.00932,-.01458*
20,1,.006,-.00932,-.01458,-.00466,-.01692,0.0*
1,1,.006,-.00466,-.01692*
20,1,.006,-.00466,-.01692,.00059,-.0175,0.0*
1,1,.006,.00059,-.0175*
20,1,.006,.00059,-.0175,.00526,-.01692,0.0*
1,1,.006,.00526,-.01692*
20,1,.006,.00526,-.01692,.00993,-.014,0.0*
1,1,.006,.00993,-.014*
20,1,.006,.00993,-.014,.01284,-.0105,0.0*
1,1,.006,.01284,-.0105*
20,1,.006,.01284,-.0105,.01343,-.007,0.0*
1,1,.006,.01343,-.007*
20,1,.006,.01343,-.007,.01226,-.00292,0.0*
1,1,.006,.01226,-.00292*
20,1,.006,.01226,-.00292,.00818,0.0,0.0*
1,1,.006,.00818,0.0*
20,1,.006,.00818,0.0,.00409,.00117,0.0*
1,1,.006,.00409,.00117*
20,1,.006,.00409,.00117,-.00116,.00117,0.0*
1,1,.006,-.00116,.00117*
1,1,.006,.00409,.00117*
20,1,.006,.00409,.00117,.00759,.00292,0.0*
1,1,.006,.00759,.00292*
20,1,.006,.00759,.00292,.01051,.00583,0.0*
1,1,.006,.01051,.00583*
20,1,.006,.01051,.00583,.01168,.00933,0.0*
1,1,.006,.01168,.00933*
20,1,.006,.01168,.00933,.01051,.01283,0.0*
1,1,.006,.01051,.01283*
20,1,.006,.01051,.01283,.00759,.01575,0.0*
1,1,.006,.00759,.01575*
20,1,.006,.00759,.01575,.00234,.0175,0.0*
1,1,.006,.00234,.0175*
20,1,.006,.00234,.0175,-.00291,.01692,0.0*
1,1,.006,-.00291,.01692*
20,1,.006,-.00291,.01692,-.00816,.01458,0.0*
1,1,.006,-.00816,.01458*
1,1,.006,.0251,-.01342*
20,1,.006,.0251,-.01342,.02919,-.01633,0.0*
1,1,.006,.02919,-.01633*
20,1,.006,.02919,-.01633,.03385,-.0175,0.0*
1,1,.006,.03385,-.0175*
20,1,.006,.03385,-.0175,.03852,-.01633,0.0*
1,1,.006,.03852,-.01633*
20,1,.006,.03852,-.01633,.0426,-.01283,0.0*
1,1,.006,.0426,-.01283*
20,1,.006,.0426,-.01283,.04552,-.00758,0.0*
1,1,.006,.04552,-.00758*
20,1,.006,.04552,-.00758,.04669,-.00233,0.0*
1,1,.006,.04669,-.00233*
20,1,.006,.04669,-.00233,.04669,.00408,0.0*
1,1,.006,.04669,.00408*
20,1,.006,.04669,.00408,.04552,.00933,0.0*
1,1,.006,.04552,.00933*
20,1,.006,.04552,.00933,.0426,.014,0.0*
1,1,.006,.0426,.014*
20,1,.006,.0426,.014,.0391,.01633,0.0*
1,1,.006,.0391,.01633*
20,1,.006,.0391,.01633,.03502,.0175,0.0*
1,1,.006,.03502,.0175*
20,1,.006,.03502,.0175,.03035,.01633,0.0*
1,1,.006,.03035,.01633*
20,1,.006,.03035,.01633,.02685,.014,0.0*
1,1,.006,.02685,.014*
20,1,.006,.02685,.014,.02452,.0105,0.0*
1,1,.006,.02452,.0105*
20,1,.006,.02452,.0105,.02335,.00583,0.0*
1,1,.006,.02335,.00583*
20,1,.006,.02335,.00583,.02452,.00175,0.0*
1,1,.006,.02452,.00175*
20,1,.006,.02452,.00175,.02744,-.00233,0.0*
1,1,.006,.02744,-.00233*
20,1,.006,.02744,-.00233,.03094,-.00467,0.0*
1,1,.006,.03094,-.00467*
20,1,.006,.03094,-.00467,.03502,-.00525,0.0*
1,1,.006,.03502,-.00525*
20,1,.006,.03502,-.00525,.03969,-.00408,0.0*
1,1,.006,.03969,-.00408*
20,1,.006,.03969,-.00408,.04319,-.00117,0.0*
1,1,.006,.04319,-.00117*
20,1,.006,.04319,-.00117,.04669,.00408,0.0*
1,1,.006,.04669,.00408*
%
%ADD10MACRO10*%
%AMMACRO12*
1,1,.006,.066,0.0*
20,1,.006,.066,0.0,.033,.057158,0.0*
1,1,.006,.033,.057158*
20,1,.006,.033,.057158,-.033,.057158,0.0*
1,1,.006,-.033,.057158*
20,1,.006,-.033,.057158,-.066,0.0,0.0*
1,1,.006,-.066,0.0*
20,1,.006,-.066,0.0,-.033,-.057158,0.0*
1,1,.006,-.033,-.057158*
20,1,.006,-.033,-.057158,.033,-.057158,0.0*
1,1,.006,.033,-.057158*
20,1,.006,.033,-.057158,.066,0.0,0.0*
1,1,.006,.066,0.0*
1,1,.006,-.0462,-.055*
20,1,.006,-.0462,-.055,-.0462,.011,0.0*
1,1,.006,-.0462,.011*
1,1,.006,-.0462,.0011*
20,1,.006,-.0462,.0011,-.0517,.0066,0.0*
1,1,.006,-.0517,.0066*
20,1,.006,-.0517,.0066,-.0583,.0099,0.0*
1,1,.006,-.0583,.0099*
20,1,.006,-.0583,.0099,-.066,.011,0.0*
1,1,.006,-.066,.011*
20,1,.006,-.066,.011,-.0726,.0099,0.0*
1,1,.006,-.0726,.0099*
20,1,.006,-.0726,.0099,-.0803,.0044,0.0*
1,1,.006,-.0803,.0044*
20,1,.006,-.0803,.0044,-.0847,-.0033,0.0*
1,1,.006,-.0847,-.0033*
20,1,.006,-.0847,-.0033,-.0858,-.011,0.0*
1,1,.006,-.0858,-.011*
20,1,.006,-.0858,-.011,-.0847,-.0187,0.0*
1,1,.006,-.0847,-.0187*
20,1,.006,-.0847,-.0187,-.0803,-.0264,0.0*
1,1,.006,-.0803,-.0264*
20,1,.006,-.0803,-.0264,-.0726,-.0319,0.0*
1,1,.006,-.0726,-.0319*
20,1,.006,-.0726,-.0319,-.066,-.033,0.0*
1,1,.006,-.066,-.033*
20,1,.006,-.066,-.033,-.0583,-.0319,0.0*
1,1,.006,-.0583,-.0319*
20,1,.006,-.0583,-.0319,-.0517,-.0286,0.0*
1,1,.006,-.0517,-.0286*
20,1,.006,-.0517,-.0286,-.0462,-.0231,0.0*
1,1,.006,-.0462,-.0231*
1,1,.006,-.01649,-.0033*
20,1,.006,-.01649,-.0033,.01871,-.0033,0.0*
1,1,.006,.01871,-.0033*
20,1,.006,.01871,-.0033,.01541,.0044,0.0*
1,1,.006,.01541,.0044*
20,1,.006,.01541,.0044,.00991,.0088,0.0*
1,1,.006,.00991,.0088*
20,1,.006,.00991,.0088,.00221,.011,0.0*
1,1,.006,.00221,.011*
20,1,.006,.00221,.011,-.00549,.0099,0.0*
1,1,.006,-.00549,.0099*
20,1,.006,-.00549,.0099,-.01209,.0066,0.0*
1,1,.006,-.01209,.0066*
20,1,.006,-.01209,.0066,-.01649,-.0011,0.0*
1,1,.006,-.01649,-.0011*
20,1,.006,-.01649,-.0011,-.01869,-.0077,0.0*
1,1,.006,-.01869,-.0077*
20,1,.006,-.01869,-.0077,-.01869,-.0143,0.0*
1,1,.006,-.01869,-.0143*
20,1,.006,-.01869,-.0143,-.01649,-.0209,0.0*
1,1,.006,-.01649,-.0209*
20,1,.006,-.01649,-.0209,-.01099,-.0275,0.0*
1,1,.006,-.01099,-.0275*
20,1,.006,-.01099,-.0275,-.00439,-.0319,0.0*
1,1,.006,-.00439,-.0319*
20,1,.006,-.00439,-.0319,.00331,-.033,0.0*
1,1,.006,.00331,-.033*
20,1,.006,.00331,-.033,.01101,-.0308,0.0*
1,1,.006,.01101,-.0308*
20,1,.006,.01101,-.0308,.01871,-.0242,0.0*
1,1,.006,.01871,-.0242*
1,1,.006,.03852,.011*
20,1,.006,.03852,.011,.05172,-.033,0.0*
1,1,.006,.05172,-.033*
20,1,.006,.05172,-.033,.06602,.011,0.0*
1,1,.006,.06602,.011*
20,1,.006,.06602,.011,.08032,-.033,0.0*
1,1,.006,.08032,-.033*
20,1,.006,.08032,-.033,.09352,.011,0.0*
1,1,.006,.09352,.011*
%
%ADD12MACRO12*%
%AMMACRO11*
1,1,.006,.035,0.0*
20,1,.006,.035,0.0,.034468,-.006078,0.0*
1,1,.006,.034468,-.006078*
20,1,.006,.034468,-.006078,.032889,-.011971,0.0*
1,1,.006,.032889,-.011971*
20,1,.006,.032889,-.011971,.030311,-.0175,0.0*
1,1,.006,.030311,-.0175*
20,1,.006,.030311,-.0175,.026812,-.022498,0.0*
1,1,.006,.026812,-.022498*
20,1,.006,.026812,-.022498,.022498,-.026812,0.0*
1,1,.006,.022498,-.026812*
20,1,.006,.022498,-.026812,.0175,-.030311,0.0*
1,1,.006,.0175,-.030311*
20,1,.006,.0175,-.030311,.011971,-.032889,0.0*
1,1,.006,.011971,-.032889*
20,1,.006,.011971,-.032889,.006078,-.034468,0.0*
1,1,.006,.006078,-.034468*
20,1,.006,.006078,-.034468,0.0,-.035,0.0*
1,1,.006,0.0,-.035*
20,1,.006,0.0,-.035,-.006078,-.034468,0.0*
1,1,.006,-.006078,-.034468*
20,1,.006,-.006078,-.034468,-.011971,-.032889,0.0*
1,1,.006,-.011971,-.032889*
20,1,.006,-.011971,-.032889,-.0175,-.030311,0.0*
1,1,.006,-.0175,-.030311*
20,1,.006,-.0175,-.030311,-.022498,-.026812,0.0*
1,1,.006,-.022498,-.026812*
20,1,.006,-.022498,-.026812,-.026812,-.022498,0.0*
1,1,.006,-.026812,-.022498*
20,1,.006,-.026812,-.022498,-.030311,-.0175,0.0*
1,1,.006,-.030311,-.0175*
20,1,.006,-.030311,-.0175,-.032889,-.011971,0.0*
1,1,.006,-.032889,-.011971*
20,1,.006,-.032889,-.011971,-.034468,-.006078,0.0*
1,1,.006,-.034468,-.006078*
20,1,.006,-.034468,-.006078,-.035,0.0,0.0*
1,1,.006,-.035,0.0*
20,1,.006,-.035,0.0,-.034468,.006078,0.0*
1,1,.006,-.034468,.006078*
20,1,.006,-.034468,.006078,-.032889,.011971,0.0*
1,1,.006,-.032889,.011971*
20,1,.006,-.032889,.011971,-.030311,.0175,0.0*
1,1,.006,-.030311,.0175*
20,1,.006,-.030311,.0175,-.026812,.022498,0.0*
1,1,.006,-.026812,.022498*
20,1,.006,-.026812,.022498,-.022498,.026812,0.0*
1,1,.006,-.022498,.026812*
20,1,.006,-.022498,.026812,-.0175,.030311,0.0*
1,1,.006,-.0175,.030311*
20,1,.006,-.0175,.030311,-.011971,.032889,0.0*
1,1,.006,-.011971,.032889*
20,1,.006,-.011971,.032889,-.006078,.034468,0.0*
1,1,.006,-.006078,.034468*
20,1,.006,-.006078,.034468,0.0,.035,0.0*
1,1,.006,0.0,.035*
20,1,.006,0.0,.035,.006078,.034468,0.0*
1,1,.006,.006078,.034468*
20,1,.006,.006078,.034468,.011971,.032889,0.0*
1,1,.006,.011971,.032889*
20,1,.006,.011971,.032889,.0175,.030311,0.0*
1,1,.006,.0175,.030311*
20,1,.006,.0175,.030311,.022498,.026812,0.0*
1,1,.006,.022498,.026812*
20,1,.006,.022498,.026812,.026812,.022498,0.0*
1,1,.006,.026812,.022498*
20,1,.006,.026812,.022498,.030311,.0175,0.0*
1,1,.006,.030311,.0175*
20,1,.006,.030311,.0175,.032889,.011971,0.0*
1,1,.006,.032889,.011971*
20,1,.006,.032889,.011971,.034468,.006078,0.0*
1,1,.006,.034468,.006078*
20,1,.006,.034468,.006078,.035,0.0,0.0*
1,1,.006,.035,0.0*
1,1,.006,-.04958,.0175*
20,1,.006,-.04958,.0175,-.035,-.0175,0.0*
1,1,.006,-.035,-.0175*
20,1,.006,-.035,-.0175,-.02042,.0175,0.0*
1,1,.006,-.02042,.0175*
1,1,.006,.00001,-.0175*
20,1,.006,.00001,-.0175,.00001,.0175,0.0*
1,1,.006,.00001,.0175*
20,1,.006,.00001,.0175,-.00699,.0105,0.0*
1,1,.006,-.00699,.0105*
1,1,.006,-.00699,-.0175*
20,1,.006,-.00699,-.0175,.00701,-.0175,0.0*
1,1,.006,.00701,-.0175*
1,1,.006,.03502,.0175*
20,1,.006,.03502,.0175,.03035,.01633,0.0*
1,1,.006,.03035,.01633*
20,1,.006,.03035,.01633,.02685,.01342,0.0*
1,1,.006,.02685,.01342*
20,1,.006,.02685,.01342,.02452,.00992,0.0*
1,1,.006,.02452,.00992*
20,1,.006,.02452,.00992,.02277,.00525,0.0*
1,1,.006,.02277,.00525*
20,1,.006,.02277,.00525,.02219,0.0,0.0*
1,1,.006,.02219,0.0*
20,1,.006,.02219,0.0,.02277,-.00525,0.0*
1,1,.006,.02277,-.00525*
20,1,.006,.02277,-.00525,.02452,-.00992,0.0*
1,1,.006,.02452,-.00992*
20,1,.006,.02452,-.00992,.02685,-.01342,0.0*
1,1,.006,.02685,-.01342*
20,1,.006,.02685,-.01342,.03035,-.01633,0.0*
1,1,.006,.03035,-.01633*
20,1,.006,.03035,-.01633,.03502,-.0175,0.0*
1,1,.006,.03502,-.0175*
20,1,.006,.03502,-.0175,.03969,-.01633,0.0*
1,1,.006,.03969,-.01633*
20,1,.006,.03969,-.01633,.04319,-.01342,0.0*
1,1,.006,.04319,-.01342*
20,1,.006,.04319,-.01342,.04552,-.00992,0.0*
1,1,.006,.04552,-.00992*
20,1,.006,.04552,-.00992,.04727,-.00525,0.0*
1,1,.006,.04727,-.00525*
20,1,.006,.04727,-.00525,.04785,0.0,0.0*
1,1,.006,.04785,0.0*
20,1,.006,.04785,0.0,.04727,.00525,0.0*
1,1,.006,.04727,.00525*
20,1,.006,.04727,.00525,.04552,.00992,0.0*
1,1,.006,.04552,.00992*
20,1,.006,.04552,.00992,.04319,.01342,0.0*
1,1,.006,.04319,.01342*
20,1,.006,.04319,.01342,.03969,.01633,0.0*
1,1,.006,.03969,.01633*
20,1,.006,.03969,.01633,.03502,.0175,0.0*
1,1,.006,.03502,.0175*
%
%ADD11MACRO11*%
%AMMACRO25*
1,1,.006,.035,0.0*
20,1,.006,.035,0.0,.034468,-.006078,0.0*
1,1,.006,.034468,-.006078*
20,1,.006,.034468,-.006078,.032889,-.011971,0.0*
1,1,.006,.032889,-.011971*
20,1,.006,.032889,-.011971,.030311,-.0175,0.0*
1,1,.006,.030311,-.0175*
20,1,.006,.030311,-.0175,.026812,-.022498,0.0*
1,1,.006,.026812,-.022498*
20,1,.006,.026812,-.022498,.022498,-.026812,0.0*
1,1,.006,.022498,-.026812*
20,1,.006,.022498,-.026812,.0175,-.030311,0.0*
1,1,.006,.0175,-.030311*
20,1,.006,.0175,-.030311,.011971,-.032889,0.0*
1,1,.006,.011971,-.032889*
20,1,.006,.011971,-.032889,.006078,-.034468,0.0*
1,1,.006,.006078,-.034468*
20,1,.006,.006078,-.034468,0.0,-.035,0.0*
1,1,.006,0.0,-.035*
20,1,.006,0.0,-.035,-.006078,-.034468,0.0*
1,1,.006,-.006078,-.034468*
20,1,.006,-.006078,-.034468,-.011971,-.032889,0.0*
1,1,.006,-.011971,-.032889*
20,1,.006,-.011971,-.032889,-.0175,-.030311,0.0*
1,1,.006,-.0175,-.030311*
20,1,.006,-.0175,-.030311,-.022498,-.026812,0.0*
1,1,.006,-.022498,-.026812*
20,1,.006,-.022498,-.026812,-.026812,-.022498,0.0*
1,1,.006,-.026812,-.022498*
20,1,.006,-.026812,-.022498,-.030311,-.0175,0.0*
1,1,.006,-.030311,-.0175*
20,1,.006,-.030311,-.0175,-.032889,-.011971,0.0*
1,1,.006,-.032889,-.011971*
20,1,.006,-.032889,-.011971,-.034468,-.006078,0.0*
1,1,.006,-.034468,-.006078*
20,1,.006,-.034468,-.006078,-.035,0.0,0.0*
1,1,.006,-.035,0.0*
20,1,.006,-.035,0.0,-.034468,.006078,0.0*
1,1,.006,-.034468,.006078*
20,1,.006,-.034468,.006078,-.032889,.011971,0.0*
1,1,.006,-.032889,.011971*
20,1,.006,-.032889,.011971,-.030311,.0175,0.0*
1,1,.006,-.030311,.0175*
20,1,.006,-.030311,.0175,-.026812,.022498,0.0*
1,1,.006,-.026812,.022498*
20,1,.006,-.026812,.022498,-.022498,.026812,0.0*
1,1,.006,-.022498,.026812*
20,1,.006,-.022498,.026812,-.0175,.030311,0.0*
1,1,.006,-.0175,.030311*
20,1,.006,-.0175,.030311,-.011971,.032889,0.0*
1,1,.006,-.011971,.032889*
20,1,.006,-.011971,.032889,-.006078,.034468,0.0*
1,1,.006,-.006078,.034468*
20,1,.006,-.006078,.034468,0.0,.035,0.0*
1,1,.006,0.0,.035*
20,1,.006,0.0,.035,.006078,.034468,0.0*
1,1,.006,.006078,.034468*
20,1,.006,.006078,.034468,.011971,.032889,0.0*
1,1,.006,.011971,.032889*
20,1,.006,.011971,.032889,.0175,.030311,0.0*
1,1,.006,.0175,.030311*
20,1,.006,.0175,.030311,.022498,.026812,0.0*
1,1,.006,.022498,.026812*
20,1,.006,.022498,.026812,.026812,.022498,0.0*
1,1,.006,.026812,.022498*
20,1,.006,.026812,.022498,.030311,.0175,0.0*
1,1,.006,.030311,.0175*
20,1,.006,.030311,.0175,.032889,.011971,0.0*
1,1,.006,.032889,.011971*
20,1,.006,.032889,.011971,.034468,.006078,0.0*
1,1,.006,.034468,.006078*
20,1,.006,.034468,.006078,.035,0.0,0.0*
1,1,.006,.035,0.0*
1,1,.006,-.04958,.0175*
20,1,.006,-.04958,.0175,-.035,-.0175,0.0*
1,1,.006,-.035,-.0175*
20,1,.006,-.035,-.0175,-.02042,.0175,0.0*
1,1,.006,-.02042,.0175*
1,1,.006,-.01107,.01167*
20,1,.006,-.01107,.01167,-.00757,.01517,0.0*
1,1,.006,-.00757,.01517*
20,1,.006,-.00757,.01517,-.00349,.01692,0.0*
1,1,.006,-.00349,.01692*
20,1,.006,-.00349,.01692,.00118,.0175,0.0*
1,1,.006,.00118,.0175*
20,1,.006,.00118,.0175,.00701,.01633,0.0*
1,1,.006,.00701,.01633*
20,1,.006,.00701,.01633,.01109,.01342,0.0*
1,1,.006,.01109,.01342*
20,1,.006,.01109,.01342,.01226,.00992,0.0*
1,1,.006,.01226,.00992*
20,1,.006,.01226,.00992,.01168,.00642,0.0*
1,1,.006,.01168,.00642*
20,1,.006,.01168,.00642,.00934,.0035,0.0*
1,1,.006,.00934,.0035*
20,1,.006,.00934,.0035,-.00232,-.00233,0.0*
1,1,.006,-.00232,-.00233*
20,1,.006,-.00232,-.00233,-.00757,-.00642,0.0*
1,1,.006,-.00757,-.00642*
20,1,.006,-.00757,-.00642,-.01107,-.01225,0.0*
1,1,.006,-.01107,-.01225*
20,1,.006,-.01107,-.01225,-.01224,-.0175,0.0*
1,1,.006,-.01224,-.0175*
20,1,.006,-.01224,-.0175,.01226,-.0175,0.0*
1,1,.006,.01226,-.0175*
1,1,.006,.03502,.0175*
20,1,.006,.03502,.0175,.03035,.01633,0.0*
1,1,.006,.03035,.01633*
20,1,.006,.03035,.01633,.02685,.01342,0.0*
1,1,.006,.02685,.01342*
20,1,.006,.02685,.01342,.02452,.00992,0.0*
1,1,.006,.02452,.00992*
20,1,.006,.02452,.00992,.02277,.00525,0.0*
1,1,.006,.02277,.00525*
20,1,.006,.02277,.00525,.02219,0.0,0.0*
1,1,.006,.02219,0.0*
20,1,.006,.02219,0.0,.02277,-.00525,0.0*
1,1,.006,.02277,-.00525*
20,1,.006,.02277,-.00525,.02452,-.00992,0.0*
1,1,.006,.02452,-.00992*
20,1,.006,.02452,-.00992,.02685,-.01342,0.0*
1,1,.006,.02685,-.01342*
20,1,.006,.02685,-.01342,.03035,-.01633,0.0*
1,1,.006,.03035,-.01633*
20,1,.006,.03035,-.01633,.03502,-.0175,0.0*
1,1,.006,.03502,-.0175*
20,1,.006,.03502,-.0175,.03969,-.01633,0.0*
1,1,.006,.03969,-.01633*
20,1,.006,.03969,-.01633,.04319,-.01342,0.0*
1,1,.006,.04319,-.01342*
20,1,.006,.04319,-.01342,.04552,-.00992,0.0*
1,1,.006,.04552,-.00992*
20,1,.006,.04552,-.00992,.04727,-.00525,0.0*
1,1,.006,.04727,-.00525*
20,1,.006,.04727,-.00525,.04785,0.0,0.0*
1,1,.006,.04785,0.0*
20,1,.006,.04785,0.0,.04727,.00525,0.0*
1,1,.006,.04727,.00525*
20,1,.006,.04727,.00525,.04552,.00992,0.0*
1,1,.006,.04552,.00992*
20,1,.006,.04552,.00992,.04319,.01342,0.0*
1,1,.006,.04319,.01342*
20,1,.006,.04319,.01342,.03969,.01633,0.0*
1,1,.006,.03969,.01633*
20,1,.006,.03969,.01633,.03502,.0175,0.0*
1,1,.006,.03502,.0175*
%
%ADD25MACRO25*%
%AMMACRO27*
1,1,.006,-.1025,-.0195*
20,1,.006,-.1025,-.0195,-.1025,.0195,0.0*
1,1,.006,-.1025,.0195*
20,1,.006,-.1025,.0195,-.100943,.037299,0.0*
1,1,.006,-.100943,.037299*
20,1,.006,-.100943,.037299,-.096318,.054557,0.0*
1,1,.006,-.096318,.054557*
20,1,.006,-.096318,.054557,-.088768,.07075,0.0*
1,1,.006,-.088768,.07075*
20,1,.006,-.088768,.07075,-.07852,.085386,0.0*
1,1,.006,-.07852,.085386*
20,1,.006,-.07852,.085386,-.065886,.09802,0.0*
1,1,.006,-.065886,.09802*
20,1,.006,-.065886,.09802,-.05125,.108268,0.0*
1,1,.006,-.05125,.108268*
20,1,.006,-.05125,.108268,-.035057,.115818,0.0*
1,1,.006,-.035057,.115818*
20,1,.006,-.035057,.115818,-.017799,.120443,0.0*
1,1,.006,-.017799,.120443*
20,1,.006,-.017799,.120443,0.0,.122,0.0*
1,1,.006,0.0,.122*
20,1,.006,0.0,.122,.017799,.120443,0.0*
1,1,.006,.017799,.120443*
20,1,.006,.017799,.120443,.035057,.115818,0.0*
1,1,.006,.035057,.115818*
20,1,.006,.035057,.115818,.05125,.108268,0.0*
1,1,.006,.05125,.108268*
20,1,.006,.05125,.108268,.065886,.09802,0.0*
1,1,.006,.065886,.09802*
20,1,.006,.065886,.09802,.07852,.085386,0.0*
1,1,.006,.07852,.085386*
20,1,.006,.07852,.085386,.088768,.07075,0.0*
1,1,.006,.088768,.07075*
20,1,.006,.088768,.07075,.096318,.054557,0.0*
1,1,.006,.096318,.054557*
20,1,.006,.096318,.054557,.100943,.037299,0.0*
1,1,.006,.100943,.037299*
20,1,.006,.100943,.037299,.1025,.0195,0.0*
1,1,.006,.1025,.0195*
20,1,.006,.1025,.0195,.1025,-.0195,0.0*
1,1,.006,.1025,-.0195*
20,1,.006,.1025,-.0195,.100943,-.037299,0.0*
1,1,.006,.100943,-.037299*
20,1,.006,.100943,-.037299,.096318,-.054557,0.0*
1,1,.006,.096318,-.054557*
20,1,.006,.096318,-.054557,.088768,-.07075,0.0*
1,1,.006,.088768,-.07075*
20,1,.006,.088768,-.07075,.07852,-.085386,0.0*
1,1,.006,.07852,-.085386*
20,1,.006,.07852,-.085386,.065886,-.09802,0.0*
1,1,.006,.065886,-.09802*
20,1,.006,.065886,-.09802,.05125,-.108268,0.0*
1,1,.006,.05125,-.108268*
20,1,.006,.05125,-.108268,.035057,-.115818,0.0*
1,1,.006,.035057,-.115818*
20,1,.006,.035057,-.115818,.017799,-.120443,0.0*
1,1,.006,.017799,-.120443*
20,1,.006,.017799,-.120443,0.0,-.122,0.0*
1,1,.006,0.0,-.122*
20,1,.006,0.0,-.122,-.017799,-.120443,0.0*
1,1,.006,-.017799,-.120443*
20,1,.006,-.017799,-.120443,-.035057,-.115818,0.0*
1,1,.006,-.035057,-.115818*
20,1,.006,-.035057,-.115818,-.05125,-.108268,0.0*
1,1,.006,-.05125,-.108268*
20,1,.006,-.05125,-.108268,-.065886,-.09802,0.0*
1,1,.006,-.065886,-.09802*
20,1,.006,-.065886,-.09802,-.07852,-.085386,0.0*
1,1,.006,-.07852,-.085386*
20,1,.006,-.07852,-.085386,-.088768,-.07075,0.0*
1,1,.006,-.088768,-.07075*
20,1,.006,-.088768,-.07075,-.096318,-.054557,0.0*
1,1,.006,-.096318,-.054557*
20,1,.006,-.096318,-.054557,-.100943,-.037299,0.0*
1,1,.006,-.100943,-.037299*
20,1,.006,-.100943,-.037299,-.1025,-.0195,0.0*
1,1,.006,-.1025,-.0195*
1,1,.006,-.13325,-.05467*
20,1,.006,-.13325,-.05467,-.07175,.05125,0.0*
1,1,.006,-.07175,.05125*
1,1,.006,-.13325,.05125*
20,1,.006,-.13325,.05125,-.1435,.04783,0.0*
1,1,.006,-.1435,.04783*
20,1,.006,-.1435,.04783,-.14863,.04271,0.0*
1,1,.006,-.14863,.04271*
20,1,.006,-.14863,.04271,-.15204,.03246,0.0*
1,1,.006,-.15204,.03246*
20,1,.006,-.15204,.03246,-.14863,.02221,0.0*
1,1,.006,-.14863,.02221*
20,1,.006,-.14863,.02221,-.1435,.01708,0.0*
1,1,.006,-.1435,.01708*
20,1,.006,-.1435,.01708,-.13325,.01367,0.0*
1,1,.006,-.13325,.01367*
20,1,.006,-.13325,.01367,-.123,.01708,0.0*
1,1,.006,-.123,.01708*
20,1,.006,-.123,.01708,-.11788,.02221,0.0*
1,1,.006,-.11788,.02221*
20,1,.006,-.11788,.02221,-.11446,.03246,0.0*
1,1,.006,-.11446,.03246*
20,1,.006,-.11446,.03246,-.11788,.04271,0.0*
1,1,.006,-.11788,.04271*
20,1,.006,-.11788,.04271,-.123,.04783,0.0*
1,1,.006,-.123,.04783*
20,1,.006,-.123,.04783,-.13325,.05125,0.0*
1,1,.006,-.13325,.05125*
1,1,.006,-.07175,-.01708*
20,1,.006,-.07175,-.01708,-.082,-.0205,0.0*
1,1,.006,-.082,-.0205*
20,1,.006,-.082,-.0205,-.08712,-.02562,0.0*
1,1,.006,-.08712,-.02562*
20,1,.006,-.08712,-.02562,-.09054,-.03588,0.0*
1,1,.006,-.09054,-.03588*
20,1,.006,-.09054,-.03588,-.08712,-.04613,0.0*
1,1,.006,-.08712,-.04613*
20,1,.006,-.08712,-.04613,-.082,-.05125,0.0*
1,1,.006,-.082,-.05125*
20,1,.006,-.082,-.05125,-.07175,-.05467,0.0*
1,1,.006,-.07175,-.05467*
20,1,.006,-.07175,-.05467,-.0615,-.05125,0.0*
1,1,.006,-.0615,-.05125*
20,1,.006,-.0615,-.05125,-.05637,-.04613,0.0*
1,1,.006,-.05637,-.04613*
20,1,.006,-.05637,-.04613,-.05296,-.03588,0.0*
1,1,.006,-.05296,-.03588*
20,1,.006,-.05296,-.03588,-.05637,-.02562,0.0*
1,1,.006,-.05637,-.02562*
20,1,.006,-.05637,-.02562,-.0615,-.0205,0.0*
1,1,.006,-.0615,-.0205*
20,1,.006,-.0615,-.0205,-.07175,-.01708,0.0*
1,1,.006,-.07175,-.01708*
1,1,.006,-.03245,-.05125*
20,1,.006,-.03245,-.05125,-.03245,.05125,0.0*
1,1,.006,-.03245,.05125*
20,1,.006,-.03245,.05125,.03247,.05125,0.0*
1,1,.006,.03247,.05125*
1,1,.006,.00855,.00171*
20,1,.006,.00855,.00171,-.03245,.00171,0.0*
1,1,.006,-.03245,.00171*
1,1,.006,.05127,-.041*
20,1,.006,.05127,-.041,.05127,-.05125,0.0*
1,1,.006,.05127,-.05125*
20,1,.006,.05127,-.05125,.06835,-.06833,0.0*
1,1,.006,.06835,-.06833*
20,1,.006,.06835,-.06833,.13669,-.06833,0.0*
1,1,.006,.13669,-.06833*
20,1,.006,.13669,-.06833,.15377,-.05125,0.0*
1,1,.006,.15377,-.05125*
20,1,.006,.15377,-.05125,.15377,-.03417,0.0*
1,1,.006,.15377,-.03417*
20,1,.006,.15377,-.03417,.13669,-.01708,0.0*
1,1,.006,.13669,-.01708*
20,1,.006,.13669,-.01708,.06835,-.01708,0.0*
1,1,.006,.06835,-.01708*
20,1,.006,.06835,-.01708,.05127,0.0,0.0*
1,1,.006,.05127,0.0*
20,1,.006,.05127,0.0,.05127,.01708,0.0*
1,1,.006,.05127,.01708*
20,1,.006,.05127,.01708,.06835,.03417,0.0*
1,1,.006,.06835,.03417*
20,1,.006,.06835,.03417,.13669,.03417,0.0*
1,1,.006,.13669,.03417*
20,1,.006,.13669,.03417,.15377,.01708,0.0*
1,1,.006,.15377,.01708*
20,1,.006,.15377,.01708,.15377,.00683,0.0*
1,1,.006,.15377,.00683*
1,1,.006,.1196,.05125*
20,1,.006,.1196,.05125,.1196,-.08542,0.0*
1,1,.006,.1196,-.08542*
1,1,.006,.08544,-.08542*
20,1,.006,.08544,-.08542,.08544,.05125,0.0*
1,1,.006,.08544,.05125*
%
%ADD27MACRO27*%
%AMMACRO22*
1,1,.006,.079,0.0*
20,1,.006,.079,0.0,.0395,.068416,0.0*
1,1,.006,.0395,.068416*
20,1,.006,.0395,.068416,-.0395,.068416,0.0*
1,1,.006,-.0395,.068416*
20,1,.006,-.0395,.068416,-.079,0.0,0.0*
1,1,.006,-.079,0.0*
20,1,.006,-.079,0.0,-.0395,-.068416,0.0*
1,1,.006,-.0395,-.068416*
20,1,.006,-.0395,-.068416,.0395,-.068416,0.0*
1,1,.006,.0395,-.068416*
20,1,.006,.0395,-.068416,.079,0.0,0.0*
1,1,.006,.079,0.0*
1,1,.006,-.0553,-.06583*
20,1,.006,-.0553,-.06583,-.0553,.01317,0.0*
1,1,.006,-.0553,.01317*
1,1,.006,-.0553,.00132*
20,1,.006,-.0553,.00132,-.06188,.0079,0.0*
1,1,.006,-.06188,.0079*
20,1,.006,-.06188,.0079,-.06978,.01185,0.0*
1,1,.006,-.06978,.01185*
20,1,.006,-.06978,.01185,-.079,.01317,0.0*
1,1,.006,-.079,.01317*
20,1,.006,-.079,.01317,-.0869,.01185,0.0*
1,1,.006,-.0869,.01185*
20,1,.006,-.0869,.01185,-.09612,.00527,0.0*
1,1,.006,-.09612,.00527*
20,1,.006,-.09612,.00527,-.10138,-.00395,0.0*
1,1,.006,-.10138,-.00395*
20,1,.006,-.10138,-.00395,-.1027,-.01317,0.0*
1,1,.006,-.1027,-.01317*
20,1,.006,-.1027,-.01317,-.10138,-.02238,0.0*
1,1,.006,-.10138,-.02238*
20,1,.006,-.10138,-.02238,-.09612,-.0316,0.0*
1,1,.006,-.09612,-.0316*
20,1,.006,-.09612,-.0316,-.0869,-.03818,0.0*
1,1,.006,-.0869,-.03818*
20,1,.006,-.0869,-.03818,-.079,-.0395,0.0*
1,1,.006,-.079,-.0395*
20,1,.006,-.079,-.0395,-.06978,-.03818,0.0*
1,1,.006,-.06978,-.03818*
20,1,.006,-.06978,-.03818,-.06188,-.03423,0.0*
1,1,.006,-.06188,-.03423*
20,1,.006,-.06188,-.03423,-.0553,-.02765,0.0*
1,1,.006,-.0553,-.02765*
1,1,.006,.00001,.0395*
20,1,.006,.00001,.0395,.00001,-.0395,0.0*
1,1,.006,.00001,-.0395*
1,1,.006,-.01842,.01317*
20,1,.006,-.01842,.01317,.01844,.01317,0.0*
1,1,.006,.01844,.01317*
1,1,.006,.07902,.01317*
20,1,.006,.07902,.01317,.07902,-.0395,0.0*
1,1,.006,.07902,-.0395*
1,1,.006,.07902,.03423*
20,1,.006,.07902,.03423,.07639,.03555,0.0*
1,1,.006,.07639,.03555*
20,1,.006,.07639,.03555,.07639,.03818,0.0*
1,1,.006,.07639,.03818*
20,1,.006,.07639,.03818,.07902,.0395,0.0*
1,1,.006,.07902,.0395*
20,1,.006,.07902,.0395,.08165,.03818,0.0*
1,1,.006,.08165,.03818*
20,1,.006,.08165,.03818,.08165,.03555,0.0*
1,1,.006,.08165,.03555*
20,1,.006,.08165,.03555,.07902,.03423,0.0*
1,1,.006,.07902,.03423*
%
%ADD22MACRO22*%
%AMMACRO14*
1,1,.006,.063,0.0*
20,1,.006,.063,0.0,.0315,.05456,0.0*
1,1,.006,.0315,.05456*
20,1,.006,.0315,.05456,-.0315,.05456,0.0*
1,1,.006,-.0315,.05456*
20,1,.006,-.0315,.05456,-.063,0.0,0.0*
1,1,.006,-.063,0.0*
20,1,.006,-.063,0.0,-.0315,-.05456,0.0*
1,1,.006,-.0315,-.05456*
20,1,.006,-.0315,-.05456,.0315,-.05456,0.0*
1,1,.006,.0315,-.05456*
20,1,.006,.0315,-.05456,.063,0.0,0.0*
1,1,.006,.063,0.0*
1,1,.006,-.0441,-.0525*
20,1,.006,-.0441,-.0525,-.0441,.0105,0.0*
1,1,.006,-.0441,.0105*
1,1,.006,-.0441,.00105*
20,1,.006,-.0441,.00105,-.04935,.0063,0.0*
1,1,.006,-.04935,.0063*
20,1,.006,-.04935,.0063,-.05565,.00945,0.0*
1,1,.006,-.05565,.00945*
20,1,.006,-.05565,.00945,-.063,.0105,0.0*
1,1,.006,-.063,.0105*
20,1,.006,-.063,.0105,-.0693,.00945,0.0*
1,1,.006,-.0693,.00945*
20,1,.006,-.0693,.00945,-.07665,.0042,0.0*
1,1,.006,-.07665,.0042*
20,1,.006,-.07665,.0042,-.08085,-.00315,0.0*
1,1,.006,-.08085,-.00315*
20,1,.006,-.08085,-.00315,-.0819,-.0105,0.0*
1,1,.006,-.0819,-.0105*
20,1,.006,-.0819,-.0105,-.08085,-.01785,0.0*
1,1,.006,-.08085,-.01785*
20,1,.006,-.08085,-.01785,-.07665,-.0252,0.0*
1,1,.006,-.07665,-.0252*
20,1,.006,-.07665,-.0252,-.0693,-.03045,0.0*
1,1,.006,-.0693,-.03045*
20,1,.006,-.0693,-.03045,-.063,-.0315,0.0*
1,1,.006,-.063,-.0315*
20,1,.006,-.063,-.0315,-.05565,-.03045,0.0*
1,1,.006,-.05565,-.03045*
20,1,.006,-.05565,-.03045,-.04935,-.0273,0.0*
1,1,.006,-.04935,-.0273*
20,1,.006,-.04935,-.0273,-.0441,-.02205,0.0*
1,1,.006,-.0441,-.02205*
1,1,.006,-.02624,.0105*
20,1,.006,-.02624,.0105,-.01364,-.0315,0.0*
1,1,.006,-.01364,-.0315*
20,1,.006,-.01364,-.0315,.00001,.0105,0.0*
1,1,.006,.00001,.0105*
20,1,.006,.00001,.0105,.01366,-.0315,0.0*
1,1,.006,.01366,-.0315*
20,1,.006,.01366,-.0315,.02626,.0105,0.0*
1,1,.006,.02626,.0105*
1,1,.006,.04097,-.0504*
20,1,.006,.04097,-.0504,.04727,-.0525,0.0*
1,1,.006,.04727,-.0525*
20,1,.006,.04727,-.0525,.05567,-.0504,0.0*
1,1,.006,.05567,-.0504*
20,1,.006,.05567,-.0504,.06092,-.0462,0.0*
1,1,.006,.06092,-.0462*
20,1,.006,.06092,-.0462,.06512,-.04095,0.0*
1,1,.006,.06512,-.04095*
20,1,.006,.06512,-.04095,.07142,-.02415,0.0*
1,1,.006,.07142,-.02415*
20,1,.006,.07142,-.02415,.08507,.0105,0.0*
1,1,.006,.08507,.0105*
1,1,.006,.05147,.0105*
20,1,.006,.05147,.0105,.07142,-.02415,0.0*
1,1,.006,.07142,-.02415*
%
%ADD14MACRO14*%
%AMMACRO23*
1,1,.006,0.0,.035*
20,1,.006,0.0,.035,.035,-.035,0.0*
1,1,.006,.035,-.035*
20,1,.006,.035,-.035,-.035,-.035,0.0*
1,1,.006,-.035,-.035*
20,1,.006,-.035,-.035,0.0,.035,0.0*
1,1,.006,0.0,.035*
1,1,.006,-.035,.0175*
20,1,.006,-.035,.0175,-.03967,.01633,0.0*
1,1,.006,-.03967,.01633*
20,1,.006,-.03967,.01633,-.04317,.01342,0.0*
1,1,.006,-.04317,.01342*
20,1,.006,-.04317,.01342,-.0455,.00992,0.0*
1,1,.006,-.0455,.00992*
20,1,.006,-.0455,.00992,-.04725,.00525,0.0*
1,1,.006,-.04725,.00525*
20,1,.006,-.04725,.00525,-.04783,0.0,0.0*
1,1,.006,-.04783,0.0*
20,1,.006,-.04783,0.0,-.04725,-.00525,0.0*
1,1,.006,-.04725,-.00525*
20,1,.006,-.04725,-.00525,-.0455,-.00992,0.0*
1,1,.006,-.0455,-.00992*
20,1,.006,-.0455,-.00992,-.04317,-.01342,0.0*
1,1,.006,-.04317,-.01342*
20,1,.006,-.04317,-.01342,-.03967,-.01633,0.0*
1,1,.006,-.03967,-.01633*
20,1,.006,-.03967,-.01633,-.035,-.0175,0.0*
1,1,.006,-.035,-.0175*
20,1,.006,-.035,-.0175,-.03033,-.01633,0.0*
1,1,.006,-.03033,-.01633*
20,1,.006,-.03033,-.01633,-.02683,-.01342,0.0*
1,1,.006,-.02683,-.01342*
20,1,.006,-.02683,-.01342,-.0245,-.00992,0.0*
1,1,.006,-.0245,-.00992*
20,1,.006,-.0245,-.00992,-.02275,-.00525,0.0*
1,1,.006,-.02275,-.00525*
20,1,.006,-.02275,-.00525,-.02217,0.0,0.0*
1,1,.006,-.02217,0.0*
20,1,.006,-.02217,0.0,-.02275,.00525,0.0*
1,1,.006,-.02275,.00525*
20,1,.006,-.02275,.00525,-.0245,.00992,0.0*
1,1,.006,-.0245,.00992*
20,1,.006,-.0245,.00992,-.02683,.01342,0.0*
1,1,.006,-.02683,.01342*
20,1,.006,-.02683,.01342,-.03033,.01633,0.0*
1,1,.006,-.03033,.01633*
20,1,.006,-.03033,.01633,-.035,.0175,0.0*
1,1,.006,-.035,.0175*
1,1,.006,.00701,-.0175*
20,1,.006,.00701,-.0175,.00701,.0175,0.0*
1,1,.006,.00701,.0175*
20,1,.006,.00701,.0175,-.01457,-.00758,0.0*
1,1,.006,-.01457,-.00758*
20,1,.006,-.01457,-.00758,.01459,-.00758,0.0*
1,1,.006,.01459,-.00758*
1,1,.006,.04202,-.0175*
20,1,.006,.04202,-.0175,.04202,.0175,0.0*
1,1,.006,.04202,.0175*
20,1,.006,.04202,.0175,.02044,-.00758,0.0*
1,1,.006,.02044,-.00758*
20,1,.006,.02044,-.00758,.0496,-.00758,0.0*
1,1,.006,.0496,-.00758*
%
%ADD23MACRO23*%
%AMMACRO15*
1,1,.006,0.0,.035*
20,1,.006,0.0,.035,.035,-.035,0.0*
1,1,.006,.035,-.035*
20,1,.006,.035,-.035,-.035,-.035,0.0*
1,1,.006,-.035,-.035*
20,1,.006,-.035,-.035,0.0,.035,0.0*
1,1,.006,0.0,.035*
1,1,.006,-.035,.0175*
20,1,.006,-.035,.0175,-.03967,.01633,0.0*
1,1,.006,-.03967,.01633*
20,1,.006,-.03967,.01633,-.04317,.01342,0.0*
1,1,.006,-.04317,.01342*
20,1,.006,-.04317,.01342,-.0455,.00992,0.0*
1,1,.006,-.0455,.00992*
20,1,.006,-.0455,.00992,-.04725,.00525,0.0*
1,1,.006,-.04725,.00525*
20,1,.006,-.04725,.00525,-.04783,0.0,0.0*
1,1,.006,-.04783,0.0*
20,1,.006,-.04783,0.0,-.04725,-.00525,0.0*
1,1,.006,-.04725,-.00525*
20,1,.006,-.04725,-.00525,-.0455,-.00992,0.0*
1,1,.006,-.0455,-.00992*
20,1,.006,-.0455,-.00992,-.04317,-.01342,0.0*
1,1,.006,-.04317,-.01342*
20,1,.006,-.04317,-.01342,-.03967,-.01633,0.0*
1,1,.006,-.03967,-.01633*
20,1,.006,-.03967,-.01633,-.035,-.0175,0.0*
1,1,.006,-.035,-.0175*
20,1,.006,-.035,-.0175,-.03033,-.01633,0.0*
1,1,.006,-.03033,-.01633*
20,1,.006,-.03033,-.01633,-.02683,-.01342,0.0*
1,1,.006,-.02683,-.01342*
20,1,.006,-.02683,-.01342,-.0245,-.00992,0.0*
1,1,.006,-.0245,-.00992*
20,1,.006,-.0245,-.00992,-.02275,-.00525,0.0*
1,1,.006,-.02275,-.00525*
20,1,.006,-.02275,-.00525,-.02217,0.0,0.0*
1,1,.006,-.02217,0.0*
20,1,.006,-.02217,0.0,-.02275,.00525,0.0*
1,1,.006,-.02275,.00525*
20,1,.006,-.02275,.00525,-.0245,.00992,0.0*
1,1,.006,-.0245,.00992*
20,1,.006,-.0245,.00992,-.02683,.01342,0.0*
1,1,.006,-.02683,.01342*
20,1,.006,-.02683,.01342,-.03033,.01633,0.0*
1,1,.006,-.03033,.01633*
20,1,.006,-.03033,.01633,-.035,.0175,0.0*
1,1,.006,-.035,.0175*
1,1,.006,-.01107,-.00292*
20,1,.006,-.01107,-.00292,-.00699,.00117,0.0*
1,1,.006,-.00699,.00117*
20,1,.006,-.00699,.00117,-.00349,.0035,0.0*
1,1,.006,-.00349,.0035*
20,1,.006,-.00349,.0035,.00118,.00467,0.0*
1,1,.006,.00118,.00467*
20,1,.006,.00118,.00467,.00526,.0035,0.0*
1,1,.006,.00526,.0035*
20,1,.006,.00526,.0035,.00818,.00117,0.0*
1,1,.006,.00818,.00117*
20,1,.006,.00818,.00117,.01051,-.00233,0.0*
1,1,.006,.01051,-.00233*
20,1,.006,.01051,-.00233,.01109,-.00642,0.0*
1,1,.006,.01109,-.00642*
20,1,.006,.01109,-.00642,.01051,-.00992,0.0*
1,1,.006,.01051,-.00992*
20,1,.006,.01051,-.00992,.00818,-.01342,0.0*
1,1,.006,.00818,-.01342*
20,1,.006,.00818,-.01342,.00468,-.01633,0.0*
1,1,.006,.00468,-.01633*
20,1,.006,.00468,-.01633,.00059,-.0175,0.0*
1,1,.006,.00059,-.0175*
20,1,.006,.00059,-.0175,-.00407,-.01633,0.0*
1,1,.006,-.00407,-.01633*
20,1,.006,-.00407,-.01633,-.00816,-.01283,0.0*
1,1,.006,-.00816,-.01283*
20,1,.006,-.00816,-.01283,-.01049,-.00758,0.0*
1,1,.006,-.01049,-.00758*
20,1,.006,-.01049,-.00758,-.01107,-.00175,0.0*
1,1,.006,-.01107,-.00175*
20,1,.006,-.01107,-.00175,-.00991,.00583,0.0*
1,1,.006,-.00991,.00583*
20,1,.006,-.00991,.00583,-.00816,.00992,0.0*
1,1,.006,-.00816,.00992*
20,1,.006,-.00816,.00992,-.00524,.014,0.0*
1,1,.006,-.00524,.014*
20,1,.006,-.00524,.014,-.00116,.01692,0.0*
1,1,.006,-.00116,.01692*
20,1,.006,-.00116,.01692,.00293,.0175,0.0*
1,1,.006,.00293,.0175*
20,1,.006,.00293,.0175,.00701,.01633,0.0*
1,1,.006,.00701,.01633*
20,1,.006,.00701,.01633,.00993,.01342,0.0*
1,1,.006,.00993,.01342*
1,1,.006,.02219,-.0105*
20,1,.006,.02219,-.0105,.02569,-.01458,0.0*
1,1,.006,.02569,-.01458*
20,1,.006,.02569,-.01458,.03035,-.01692,0.0*
1,1,.006,.03035,-.01692*
20,1,.006,.03035,-.01692,.0356,-.0175,0.0*
1,1,.006,.0356,-.0175*
20,1,.006,.0356,-.0175,.04027,-.01692,0.0*
1,1,.006,.04027,-.01692*
20,1,.006,.04027,-.01692,.04494,-.014,0.0*
1,1,.006,.04494,-.014*
20,1,.006,.04494,-.014,.04785,-.0105,0.0*
1,1,.006,.04785,-.0105*
20,1,.006,.04785,-.0105,.04844,-.007,0.0*
1,1,.006,.04844,-.007*
20,1,.006,.04844,-.007,.04727,-.00292,0.0*
1,1,.006,.04727,-.00292*
20,1,.006,.04727,-.00292,.04319,0.0,0.0*
1,1,.006,.04319,0.0*
20,1,.006,.04319,0.0,.0391,.00117,0.0*
1,1,.006,.0391,.00117*
20,1,.006,.0391,.00117,.03385,.00117,0.0*
1,1,.006,.03385,.00117*
1,1,.006,.0391,.00117*
20,1,.006,.0391,.00117,.0426,.00292,0.0*
1,1,.006,.0426,.00292*
20,1,.006,.0426,.00292,.04552,.00583,0.0*
1,1,.006,.04552,.00583*
20,1,.006,.04552,.00583,.04669,.00933,0.0*
1,1,.006,.04669,.00933*
20,1,.006,.04669,.00933,.04552,.01283,0.0*
1,1,.006,.04552,.01283*
20,1,.006,.04552,.01283,.0426,.01575,0.0*
1,1,.006,.0426,.01575*
20,1,.006,.0426,.01575,.03735,.0175,0.0*
1,1,.006,.03735,.0175*
20,1,.006,.03735,.0175,.0321,.01692,0.0*
1,1,.006,.0321,.01692*
20,1,.006,.0321,.01692,.02685,.01458,0.0*
1,1,.006,.02685,.01458*
%
%ADD15MACRO15*%
%AMMACRO19*
1,1,.006,0.0,.035*
20,1,.006,0.0,.035,.035,-.035,0.0*
1,1,.006,.035,-.035*
20,1,.006,.035,-.035,-.035,-.035,0.0*
1,1,.006,-.035,-.035*
20,1,.006,-.035,-.035,0.0,.035,0.0*
1,1,.006,0.0,.035*
1,1,.006,-.035,.0175*
20,1,.006,-.035,.0175,-.03967,.01633,0.0*
1,1,.006,-.03967,.01633*
20,1,.006,-.03967,.01633,-.04317,.01342,0.0*
1,1,.006,-.04317,.01342*
20,1,.006,-.04317,.01342,-.0455,.00992,0.0*
1,1,.006,-.0455,.00992*
20,1,.006,-.0455,.00992,-.04725,.00525,0.0*
1,1,.006,-.04725,.00525*
20,1,.006,-.04725,.00525,-.04783,0.0,0.0*
1,1,.006,-.04783,0.0*
20,1,.006,-.04783,0.0,-.04725,-.00525,0.0*
1,1,.006,-.04725,-.00525*
20,1,.006,-.04725,-.00525,-.0455,-.00992,0.0*
1,1,.006,-.0455,-.00992*
20,1,.006,-.0455,-.00992,-.04317,-.01342,0.0*
1,1,.006,-.04317,-.01342*
20,1,.006,-.04317,-.01342,-.03967,-.01633,0.0*
1,1,.006,-.03967,-.01633*
20,1,.006,-.03967,-.01633,-.035,-.0175,0.0*
1,1,.006,-.035,-.0175*
20,1,.006,-.035,-.0175,-.03033,-.01633,0.0*
1,1,.006,-.03033,-.01633*
20,1,.006,-.03033,-.01633,-.02683,-.01342,0.0*
1,1,.006,-.02683,-.01342*
20,1,.006,-.02683,-.01342,-.0245,-.00992,0.0*
1,1,.006,-.0245,-.00992*
20,1,.006,-.0245,-.00992,-.02275,-.00525,0.0*
1,1,.006,-.02275,-.00525*
20,1,.006,-.02275,-.00525,-.02217,0.0,0.0*
1,1,.006,-.02217,0.0*
20,1,.006,-.02217,0.0,-.02275,.00525,0.0*
1,1,.006,-.02275,.00525*
20,1,.006,-.02275,.00525,-.0245,.00992,0.0*
1,1,.006,-.0245,.00992*
20,1,.006,-.0245,.00992,-.02683,.01342,0.0*
1,1,.006,-.02683,.01342*
20,1,.006,-.02683,.01342,-.03033,.01633,0.0*
1,1,.006,-.03033,.01633*
20,1,.006,-.03033,.01633,-.035,.0175,0.0*
1,1,.006,-.035,.0175*
1,1,.006,-.01282,-.01225*
20,1,.006,-.01282,-.01225,-.00932,-.01517,0.0*
1,1,.006,-.00932,-.01517*
20,1,.006,-.00932,-.01517,-.00524,-.01692,0.0*
1,1,.006,-.00524,-.01692*
20,1,.006,-.00524,-.01692,.00001,-.0175,0.0*
1,1,.006,.00001,-.0175*
20,1,.006,.00001,-.0175,.00526,-.01633,0.0*
1,1,.006,.00526,-.01633*
20,1,.006,.00526,-.01633,.00934,-.014,0.0*
1,1,.006,.00934,-.014*
20,1,.006,.00934,-.014,.01226,-.00992,0.0*
1,1,.006,.01226,-.00992*
20,1,.006,.01226,-.00992,.01284,-.00525,0.0*
1,1,.006,.01284,-.00525*
20,1,.006,.01284,-.00525,.01168,-.00058,0.0*
1,1,.006,.01168,-.00058*
20,1,.006,.01168,-.00058,.00876,.00233,0.0*
1,1,.006,.00876,.00233*
20,1,.006,.00876,.00233,.00468,.00467,0.0*
1,1,.006,.00468,.00467*
20,1,.006,.00468,.00467,.00059,.00525,0.0*
1,1,.006,.00059,.00525*
20,1,.006,.00059,.00525,-.00349,.00467,0.0*
1,1,.006,-.00349,.00467*
20,1,.006,-.00349,.00467,-.00874,.00233,0.0*
1,1,.006,-.00874,.00233*
20,1,.006,-.00874,.00233,-.00699,.0175,0.0*
1,1,.006,-.00699,.0175*
20,1,.006,-.00699,.0175,.00876,.0175,0.0*
1,1,.006,.00876,.0175*
1,1,.006,.03385,-.0175*
20,1,.006,.03385,-.0175,.03502,-.00992,0.0*
1,1,.006,.03502,-.00992*
20,1,.006,.03502,-.00992,.03677,-.0035,0.0*
1,1,.006,.03677,-.0035*
20,1,.006,.03677,-.0035,.0391,.00233,0.0*
1,1,.006,.0391,.00233*
20,1,.006,.0391,.00233,.04202,.00875,0.0*
1,1,.006,.04202,.00875*
20,1,.006,.04202,.00875,.04669,.0175,0.0*
1,1,.006,.04669,.0175*
20,1,.006,.04669,.0175,.02335,.0175,0.0*
1,1,.006,.02335,.0175*
%
%ADD19MACRO19*%
%AMMACRO20*
1,1,.006,.035,0.0*
20,1,.006,.035,0.0,.034468,-.006078,0.0*
1,1,.006,.034468,-.006078*
20,1,.006,.034468,-.006078,.032889,-.011971,0.0*
1,1,.006,.032889,-.011971*
20,1,.006,.032889,-.011971,.030311,-.0175,0.0*
1,1,.006,.030311,-.0175*
20,1,.006,.030311,-.0175,.026812,-.022498,0.0*
1,1,.006,.026812,-.022498*
20,1,.006,.026812,-.022498,.022498,-.026812,0.0*
1,1,.006,.022498,-.026812*
20,1,.006,.022498,-.026812,.0175,-.030311,0.0*
1,1,.006,.0175,-.030311*
20,1,.006,.0175,-.030311,.011971,-.032889,0.0*
1,1,.006,.011971,-.032889*
20,1,.006,.011971,-.032889,.006078,-.034468,0.0*
1,1,.006,.006078,-.034468*
20,1,.006,.006078,-.034468,0.0,-.035,0.0*
1,1,.006,0.0,-.035*
20,1,.006,0.0,-.035,-.006078,-.034468,0.0*
1,1,.006,-.006078,-.034468*
20,1,.006,-.006078,-.034468,-.011971,-.032889,0.0*
1,1,.006,-.011971,-.032889*
20,1,.006,-.011971,-.032889,-.0175,-.030311,0.0*
1,1,.006,-.0175,-.030311*
20,1,.006,-.0175,-.030311,-.022498,-.026812,0.0*
1,1,.006,-.022498,-.026812*
20,1,.006,-.022498,-.026812,-.026812,-.022498,0.0*
1,1,.006,-.026812,-.022498*
20,1,.006,-.026812,-.022498,-.030311,-.0175,0.0*
1,1,.006,-.030311,-.0175*
20,1,.006,-.030311,-.0175,-.032889,-.011971,0.0*
1,1,.006,-.032889,-.011971*
20,1,.006,-.032889,-.011971,-.034468,-.006078,0.0*
1,1,.006,-.034468,-.006078*
20,1,.006,-.034468,-.006078,-.035,0.0,0.0*
1,1,.006,-.035,0.0*
20,1,.006,-.035,0.0,-.034468,.006078,0.0*
1,1,.006,-.034468,.006078*
20,1,.006,-.034468,.006078,-.032889,.011971,0.0*
1,1,.006,-.032889,.011971*
20,1,.006,-.032889,.011971,-.030311,.0175,0.0*
1,1,.006,-.030311,.0175*
20,1,.006,-.030311,.0175,-.026812,.022498,0.0*
1,1,.006,-.026812,.022498*
20,1,.006,-.026812,.022498,-.022498,.026812,0.0*
1,1,.006,-.022498,.026812*
20,1,.006,-.022498,.026812,-.0175,.030311,0.0*
1,1,.006,-.0175,.030311*
20,1,.006,-.0175,.030311,-.011971,.032889,0.0*
1,1,.006,-.011971,.032889*
20,1,.006,-.011971,.032889,-.006078,.034468,0.0*
1,1,.006,-.006078,.034468*
20,1,.006,-.006078,.034468,0.0,.035,0.0*
1,1,.006,0.0,.035*
20,1,.006,0.0,.035,.006078,.034468,0.0*
1,1,.006,.006078,.034468*
20,1,.006,.006078,.034468,.011971,.032889,0.0*
1,1,.006,.011971,.032889*
20,1,.006,.011971,.032889,.0175,.030311,0.0*
1,1,.006,.0175,.030311*
20,1,.006,.0175,.030311,.022498,.026812,0.0*
1,1,.006,.022498,.026812*
20,1,.006,.022498,.026812,.026812,.022498,0.0*
1,1,.006,.026812,.022498*
20,1,.006,.026812,.022498,.030311,.0175,0.0*
1,1,.006,.030311,.0175*
20,1,.006,.030311,.0175,.032889,.011971,0.0*
1,1,.006,.032889,.011971*
20,1,.006,.032889,.011971,.034468,.006078,0.0*
1,1,.006,.034468,.006078*
20,1,.006,.034468,.006078,.035,0.0,0.0*
1,1,.006,.035,0.0*
1,1,.006,-.0455,.00583*
20,1,.006,-.0455,.00583,-.035,-.0175,0.0*
1,1,.006,-.035,-.0175*
20,1,.006,-.035,-.0175,-.0245,.00583,0.0*
1,1,.006,-.0245,.00583*
1,1,.006,.00001,.00583*
20,1,.006,.00001,.00583,.00001,-.0175,0.0*
1,1,.006,.00001,-.0175*
1,1,.006,.00001,.01517*
20,1,.006,.00001,.01517,-.00116,.01575,0.0*
1,1,.006,-.00116,.01575*
20,1,.006,-.00116,.01575,-.00116,.01692,0.0*
1,1,.006,-.00116,.01692*
20,1,.006,-.00116,.01692,.00001,.0175,0.0*
1,1,.006,.00001,.0175*
20,1,.006,.00001,.0175,.00118,.01692,0.0*
1,1,.006,.00118,.01692*
20,1,.006,.00118,.01692,.00118,.01575,0.0*
1,1,.006,.00118,.01575*
20,1,.006,.00118,.01575,.00001,.01517,0.0*
1,1,.006,.00001,.01517*
1,1,.006,.04552,-.0175*
20,1,.006,.04552,-.0175,.04552,.00583,0.0*
1,1,.006,.04552,.00583*
1,1,.006,.04552,.00175*
20,1,.006,.04552,.00175,.04319,.00408,0.0*
1,1,.006,.04319,.00408*
20,1,.006,.04319,.00408,.03969,.00525,0.0*
1,1,.006,.03969,.00525*
20,1,.006,.03969,.00525,.0356,.00583,0.0*
1,1,.006,.0356,.00583*
20,1,.006,.0356,.00583,.03152,.00467,0.0*
1,1,.006,.03152,.00467*
20,1,.006,.03152,.00467,.02802,.00233,0.0*
1,1,.006,.02802,.00233*
20,1,.006,.02802,.00233,.02569,-.00117,0.0*
1,1,.006,.02569,-.00117*
20,1,.006,.02569,-.00117,.02452,-.00583,0.0*
1,1,.006,.02452,-.00583*
20,1,.006,.02452,-.00583,.02569,-.0105,0.0*
1,1,.006,.02569,-.0105*
20,1,.006,.02569,-.0105,.02802,-.014,0.0*
1,1,.006,.02802,-.014*
20,1,.006,.02802,-.014,.03152,-.01633,0.0*
1,1,.006,.03152,-.01633*
20,1,.006,.03152,-.01633,.0356,-.0175,0.0*
1,1,.006,.0356,-.0175*
20,1,.006,.0356,-.0175,.03969,-.01692,0.0*
1,1,.006,.03969,-.01692*
20,1,.006,.03969,-.01692,.04319,-.01517,0.0*
1,1,.006,.04319,-.01517*
20,1,.006,.04319,-.01517,.04552,-.01283,0.0*
1,1,.006,.04552,-.01283*
%
%ADD20MACRO20*%
%ADD29C,.006*%
G75*
%LPD*%
G75*
G54D10*
X17735Y24953D03*
X27735D03*
X22735Y34953D03*
Y216976D03*
X27735Y206976D03*
X17735D03*
Y233811D03*
X27735D03*
X22735Y243811D03*
X27735Y415834D03*
X17735D03*
X22735Y425834D03*
Y1957291D03*
X27735Y1947291D03*
X17735D03*
X22735Y2061661D03*
X27735Y2051661D03*
X17735D03*
X37735Y24953D03*
X47735D03*
X32735Y34953D03*
X42735D03*
Y216976D03*
X32735D03*
X47735Y206976D03*
X37735D03*
Y233811D03*
X47735D03*
X32735Y243811D03*
X42735D03*
X47735Y415834D03*
X37735D03*
X42735Y425834D03*
X32735D03*
X42735Y1957291D03*
X32735D03*
X47735Y1947291D03*
X37735D03*
X42735Y2061661D03*
X32735D03*
X47735Y2051661D03*
X37735D03*
X52735Y34953D03*
Y216976D03*
Y243811D03*
Y425834D03*
Y1957291D03*
Y2061661D03*
X553766Y629796D03*
G54D20*
X49441Y1238962D03*
X46980Y1335843D03*
Y1325843D03*
Y1315843D03*
Y1320843D03*
Y1330843D03*
Y1345843D03*
Y1340843D03*
X61888Y666012D03*
X57124Y675327D03*
X54483Y679810D03*
X59236Y670758D03*
X70865Y854278D03*
Y872278D03*
Y866278D03*
Y860278D03*
Y897750D03*
Y890116D03*
X61866Y1309190D03*
X67568Y1307829D03*
X54543Y1308995D03*
X61866Y1342104D03*
X95775Y751469D03*
X92216Y899865D03*
X90708Y878615D03*
X92633Y907404D03*
X92989Y927334D03*
X98139Y990959D03*
X82763Y1060051D03*
X96684Y1081791D03*
X96510Y1395382D03*
X106958Y26285D03*
X107405Y49898D03*
X107037Y34687D03*
X106836Y376461D03*
X106709Y391219D03*
X107025Y725368D03*
X106935Y745139D03*
X107173Y735219D03*
X100687Y999391D03*
X107351Y1093484D03*
X107235Y1081791D03*
X107215Y1072208D03*
X105152Y1118381D03*
X100719Y1312810D03*
Y1306810D03*
Y1330810D03*
Y1336810D03*
Y1324810D03*
Y1318810D03*
Y1346065D03*
X101626Y1397635D03*
X106962Y1434041D03*
X106921Y1419492D03*
X106763Y1444599D03*
X107006Y1452651D03*
X107355Y1770437D03*
X107220Y1791589D03*
X107373Y1780544D03*
X106819Y1802230D03*
X144878Y1738861D03*
X157558Y51426D03*
X156865Y401207D03*
X156610Y751063D03*
X156854Y1101031D03*
X158618Y1399448D03*
X164037Y1400226D03*
X170351Y1401324D03*
X159192Y1451105D03*
X150309Y1737009D03*
X168151Y1739208D03*
X156183Y1735240D03*
X165782Y1732903D03*
X163257Y1737619D03*
X156452Y1800821D03*
X175989Y944537D03*
X176011Y936829D03*
X175359Y963486D03*
X175561Y955964D03*
X175135Y972490D03*
X175022Y980281D03*
X175742Y989958D03*
X175449Y997660D03*
X175698Y1008730D03*
X175473Y1016296D03*
X175448Y1031766D03*
X175897Y1023997D03*
X176083Y1402321D03*
X173394Y1736051D03*
X256947Y128276D03*
X257125Y115559D03*
X265722Y463102D03*
X265737Y473680D03*
X255837Y823626D03*
X255687Y812192D03*
X283086Y162675D03*
X271547Y245353D03*
X281193Y241624D03*
X281074Y337688D03*
X289895D03*
X291002Y417844D03*
X281569Y421169D03*
X278405Y512341D03*
X269516D03*
X285348Y595540D03*
X270109Y687192D03*
X278955D03*
X273114Y770968D03*
X282737Y767643D03*
X272181Y862354D03*
X281305Y862237D03*
X275966Y944767D03*
X285874Y941442D03*
X281124Y1031162D03*
X290107D03*
X282958Y1119471D03*
X289082Y1206777D03*
X279559D03*
X283808Y1293959D03*
X279518Y1389543D03*
X270579Y1389626D03*
X270234Y1467760D03*
X279990Y1464435D03*
X285054Y1558211D03*
X284086Y1644883D03*
X274704Y1738196D03*
X284583Y1738465D03*
X281066Y1819569D03*
X291550Y1814846D03*
X280240Y1858668D03*
X279976Y1864565D03*
X282717Y1913327D03*
X273817D03*
X304151Y63778D03*
X313089D03*
X294483Y67732D03*
X291943Y162630D03*
X308057Y248863D03*
X306267Y241010D03*
X314914Y238162D03*
X314940Y252083D03*
X305867Y258589D03*
X295509Y592215D03*
X309678Y1053262D03*
X292698Y1116146D03*
X312527Y1162266D03*
X312698Y1172804D03*
X294133Y1290634D03*
X314183Y1403423D03*
X302267Y1524401D03*
X301734Y1513883D03*
X312077Y1575871D03*
X294392Y1558211D03*
X294090Y1641558D03*
X311539Y1753499D03*
X314562Y1994087D03*
X331403Y51409D03*
X333889Y56021D03*
X338227Y61559D03*
X322005Y63778D03*
X320372Y225979D03*
X318088Y231820D03*
X321899Y238137D03*
X329930Y245684D03*
X331046Y232021D03*
X320961Y250105D03*
X324709Y231580D03*
X335522Y404033D03*
X323313Y418313D03*
X326196Y413982D03*
X328950Y409216D03*
X320980Y423225D03*
X336617Y577978D03*
X319305Y582111D03*
X329636Y584715D03*
X317724Y588250D03*
X337387Y586230D03*
X320380Y576491D03*
X331867Y589810D03*
X333750Y595326D03*
X323751Y589155D03*
X319852Y593330D03*
X321742Y599041D03*
X331568Y752967D03*
X339012Y752859D03*
X329336Y762693D03*
X334010Y758588D03*
X327524Y758020D03*
X339615Y926357D03*
X329938Y948756D03*
X332527Y943746D03*
X324098Y946104D03*
X318557Y941178D03*
X323868Y929978D03*
X326646Y939788D03*
X333300Y928464D03*
X336160Y937262D03*
X328583Y933262D03*
X321425Y951577D03*
X324246Y1051786D03*
X335677Y1048904D03*
X317592Y1053050D03*
X331920Y1116088D03*
X337509Y1109598D03*
X328989Y1121090D03*
X326558Y1126368D03*
X327452Y1279447D03*
X321978Y1282086D03*
X338047Y1282599D03*
X333242Y1276809D03*
X329619Y1284016D03*
X327932Y1289221D03*
X319404Y1401346D03*
X325636Y1399114D03*
X334646Y1400804D03*
X323720Y1570924D03*
X329399Y1571939D03*
X317243Y1574832D03*
X333474Y1566686D03*
X335963Y1573797D03*
X329887Y1752081D03*
X321283Y1753466D03*
X335730Y1753270D03*
X338309Y1927623D03*
X332399Y1926787D03*
X324803Y1990272D03*
X359931Y52189D03*
X348289Y50863D03*
X345089Y56190D03*
X340373Y51579D03*
X342097Y401684D03*
X363825Y401768D03*
X342900Y580126D03*
X362577Y752783D03*
X344109Y751809D03*
X343656Y933725D03*
X345578Y1047844D03*
X344099Y1106798D03*
X349855Y1104302D03*
X344130Y1401670D03*
X350690Y1403243D03*
X348710Y1570187D03*
X361011Y1568890D03*
X343402Y1572080D03*
X348245Y1575241D03*
X355364Y1570990D03*
X345537Y1916558D03*
X344402Y1911123D03*
X363361Y1918313D03*
X358318Y1920680D03*
X363411Y1923459D03*
X340336Y1922409D03*
X347676Y1922165D03*
X372204Y56126D03*
X365720Y52336D03*
X379257Y52158D03*
X379572Y58441D03*
X387524Y76847D03*
X374442Y406857D03*
X380619Y410112D03*
X380878Y403999D03*
X374542Y401282D03*
X368907Y404308D03*
X376654Y754748D03*
X382892Y767710D03*
X386790Y774338D03*
X380186Y761742D03*
X379335Y1189778D03*
X383276Y1184136D03*
X386816Y1179841D03*
X376472Y1194999D03*
X373674Y1199967D03*
X371523Y1204725D03*
X367829Y1566108D03*
X374775Y1919243D03*
X379403Y1917261D03*
X369748Y1921795D03*
X391278Y765894D03*
X553766Y913296D03*
G54D11*
X25219Y18752D03*
X3001Y52034D03*
Y100034D03*
Y150034D03*
Y200034D03*
Y250034D03*
Y300034D03*
Y350034D03*
Y400034D03*
Y450034D03*
Y500034D03*
Y550034D03*
X11677Y578766D03*
X3001Y600034D03*
Y650034D03*
Y700034D03*
Y750034D03*
Y800034D03*
Y850034D03*
Y900034D03*
Y950034D03*
Y1000034D03*
Y1050034D03*
Y1100034D03*
Y1150034D03*
Y1200034D03*
Y1250034D03*
Y1300034D03*
Y1350034D03*
Y1400034D03*
Y1450034D03*
Y1500034D03*
Y1550034D03*
X16484Y1552159D03*
X11085Y1552589D03*
X3006Y1594602D03*
X3012Y1610165D03*
X3001Y1650034D03*
Y1700034D03*
Y1750034D03*
Y1800034D03*
Y1850034D03*
Y1900034D03*
Y1950034D03*
Y2000034D03*
Y2050034D03*
X48433Y866179D03*
X48467Y869278D03*
X26833Y2067866D03*
X58750Y579653D03*
X63820Y579654D03*
X60815Y1019026D03*
X63577Y1019115D03*
X59127Y1257647D03*
X57458Y1253378D03*
X58356Y1279812D03*
X58416Y1272383D03*
X54543Y1296513D03*
X63061Y1296312D03*
X67568Y1296654D03*
X54108Y1559138D03*
X75219Y18752D03*
X97417Y32853D03*
Y37438D03*
X97536Y376580D03*
X97457Y371909D03*
X97985Y391220D03*
X97643Y396024D03*
X93223Y417736D03*
X94347Y421562D03*
X98591Y720745D03*
X98564Y715937D03*
X97443Y739962D03*
X97534Y735248D03*
X98124Y745139D03*
X76446Y1014871D03*
X79499D03*
X96904Y1067515D03*
X96948Y1092036D03*
X96949Y1087095D03*
X96774Y1072226D03*
X75475Y1315303D03*
X97403Y1424340D03*
X97825Y1419492D03*
X96993Y1443743D03*
X96996Y1438980D03*
X97465Y1447919D03*
X95236Y1453321D03*
X76833Y2067866D03*
X106335Y22580D03*
X108082Y38899D03*
X102646Y49461D03*
X101430Y41803D03*
X104350Y62293D03*
X107263Y72244D03*
X109054Y58250D03*
X104116Y82557D03*
X107213Y85169D03*
X105451Y406795D03*
X114498Y396207D03*
X101990Y426104D03*
X109475Y434743D03*
X111017Y419566D03*
X105087Y754126D03*
X101244Y774100D03*
X112836Y769122D03*
X113697Y794293D03*
X105395Y972040D03*
X102611Y972220D03*
X98652Y1096403D03*
X108779Y1105760D03*
X112503Y1115860D03*
X105684Y1125919D03*
X108468Y1129286D03*
X105455Y1472894D03*
X108574Y1463389D03*
X113518Y1489571D03*
X99103Y1765722D03*
X99068Y1760827D03*
X99047Y1785571D03*
X98873Y1780542D03*
X99294Y1789947D03*
X107391Y1794460D03*
X105669Y1815227D03*
X108819Y1812118D03*
Y1824470D03*
X109991Y2083607D03*
X125219Y3002D03*
X162384Y56744D03*
X161742Y72497D03*
X162586Y68130D03*
X161339Y88108D03*
X159417Y91281D03*
X158901Y85017D03*
X161377Y407575D03*
X161517Y436119D03*
X161257Y420869D03*
X159019Y439268D03*
X158807Y432969D03*
X161826Y756757D03*
X161131Y774878D03*
X161644Y764231D03*
X158956Y780982D03*
X161479Y784141D03*
X159053Y787280D03*
X164539Y1116135D03*
X162140Y1106853D03*
X159382Y1136151D03*
X158456Y1129045D03*
X163099Y1457084D03*
X162524Y1462651D03*
X162242Y1471380D03*
X159216Y1477124D03*
X159526Y1483434D03*
X163250Y1815631D03*
X162140Y1807740D03*
X161844Y1828225D03*
X159822Y1831380D03*
X159075Y1825087D03*
X159991Y2083607D03*
X175219Y3002D03*
X184284Y948331D03*
X184196Y967371D03*
X184632Y983423D03*
X184353Y1001556D03*
X184118Y1019280D03*
X188385Y1020810D03*
X209991Y2083607D03*
X225219Y3002D03*
X267627Y115559D03*
X259991Y2083607D03*
X275219Y3002D03*
X287420Y162540D03*
X276617Y241400D03*
X285513Y337688D03*
X286665Y417844D03*
X274991Y463099D03*
X282776Y512341D03*
X273938D03*
X290984Y592215D03*
X274514Y687192D03*
X283340D03*
X278184Y767643D03*
X270070Y812192D03*
X276686Y862488D03*
X285788Y862237D03*
X281194Y941442D03*
X285666Y1031162D03*
X288188Y1116146D03*
X284194Y1206777D03*
X289210Y1290634D03*
X284240Y1389544D03*
X275052Y1389715D03*
X275521Y1464435D03*
X289675Y1558211D03*
X289421Y1641558D03*
X279703Y1738398D03*
X289499Y1738735D03*
X286623Y1814400D03*
X287121Y1913327D03*
X278262D03*
X299687Y63778D03*
X308651D03*
X296523Y162585D03*
X294506Y337688D03*
X294617Y1031162D03*
X293807Y1206777D03*
X313894Y1513883D03*
X298870Y1558211D03*
X292614Y1864565D03*
X293606Y1858668D03*
X309991Y2083607D03*
X325219Y3002D03*
X317567Y63778D03*
X325796Y1162266D03*
X323403Y1172804D03*
X320045Y1990215D03*
X359991Y2083607D03*
X375219Y3002D03*
X402512Y17108D03*
Y67108D03*
Y117108D03*
Y167108D03*
Y217108D03*
Y267108D03*
Y317108D03*
Y367108D03*
Y417108D03*
Y467108D03*
Y517108D03*
Y567108D03*
Y617108D03*
Y667108D03*
Y717108D03*
Y767108D03*
Y817108D03*
Y867108D03*
Y917108D03*
Y967108D03*
Y1017108D03*
Y1067108D03*
Y1117108D03*
Y1167108D03*
Y1217108D03*
Y1267108D03*
Y1317108D03*
Y1367108D03*
Y1417108D03*
Y1467108D03*
Y1517108D03*
Y1567108D03*
Y1617108D03*
Y1667108D03*
Y1717108D03*
Y1767108D03*
Y1817108D03*
Y1867108D03*
Y1917108D03*
Y1967108D03*
Y2017108D03*
Y2067108D03*
X553766Y960546D03*
G54D12*
X12735Y59953D03*
Y181976D03*
Y268811D03*
Y390834D03*
Y1922291D03*
Y2026661D03*
X57735Y59953D03*
Y181976D03*
Y268811D03*
Y390834D03*
Y1922291D03*
Y2026661D03*
X553766Y251796D03*
G54D21*
X65354Y101180D03*
X55511Y105117D03*
X51574Y114960D03*
X55511Y124803D03*
X65354Y128740D03*
Y451180D03*
X55511Y455117D03*
X51574Y464960D03*
X55511Y474803D03*
X65354Y478740D03*
Y801180D03*
X55511Y805117D03*
X51574Y814960D03*
X55511Y824803D03*
X65354Y828740D03*
Y1151180D03*
X55511Y1155117D03*
X51574Y1164960D03*
X55511Y1174803D03*
X65354Y1178740D03*
Y1501180D03*
X55511Y1505117D03*
X51574Y1514960D03*
X55511Y1524803D03*
X65354Y1528740D03*
Y1851180D03*
X55511Y1855117D03*
X51574Y1864960D03*
X55511Y1874803D03*
X65354Y1878740D03*
X75197Y105117D03*
Y124803D03*
X79134Y114960D03*
Y464960D03*
X75197Y455117D03*
Y474803D03*
Y805117D03*
Y824803D03*
X79134Y814960D03*
Y1164960D03*
X75197Y1155117D03*
Y1174803D03*
Y1505117D03*
Y1524803D03*
X79134Y1514960D03*
Y1864960D03*
X75197Y1855117D03*
Y1874803D03*
X307086Y113385D03*
X297243Y117322D03*
X293306Y127165D03*
X297243Y137008D03*
X307086Y140945D03*
Y463385D03*
X297243Y467322D03*
X293306Y477165D03*
X297243Y487008D03*
X307086Y490945D03*
Y813385D03*
X297243Y817322D03*
X293306Y827165D03*
X297243Y837008D03*
X307086Y840945D03*
Y1329724D03*
X297243Y1333661D03*
X293306Y1343504D03*
X297243Y1353347D03*
X307086Y1357284D03*
Y1679724D03*
X297243Y1683661D03*
X293306Y1693504D03*
X297243Y1703347D03*
X307086Y1707284D03*
X307087Y2029723D03*
X297244Y2033660D03*
X293307Y2043503D03*
X297244Y2053346D03*
X307087Y2057283D03*
X320866Y127165D03*
X316929Y117322D03*
Y137008D03*
Y467322D03*
Y487008D03*
X320866Y477165D03*
Y827165D03*
X316929Y817322D03*
Y837008D03*
Y1333661D03*
Y1353347D03*
X320866Y1343504D03*
Y1693504D03*
X316929Y1683661D03*
Y1703347D03*
X316930Y2033660D03*
Y2053346D03*
X320867Y2043503D03*
X553766Y818796D03*
G54D22*
X65354Y114960D03*
Y464960D03*
Y814960D03*
Y1164960D03*
Y1514960D03*
Y1864960D03*
X307086Y127165D03*
Y477165D03*
Y827165D03*
Y1343504D03*
Y1693504D03*
X307087Y2043503D03*
X553766Y204546D03*
G54D13*
X18995Y508701D03*
X23995Y518701D03*
X21495Y559882D03*
X11692D03*
X21495Y1571811D03*
X11692D03*
X23995Y1622992D03*
X18995Y1612992D03*
X28995Y508701D03*
X38995D03*
X48995D03*
X33995Y518701D03*
X43995D03*
X51495Y559882D03*
Y1571811D03*
X43995Y1622992D03*
X33995D03*
X48995Y1612992D03*
X38995D03*
X28995D03*
X53995Y518701D03*
X61298Y559882D03*
Y1571811D03*
X53995Y1622992D03*
X189762Y73105D03*
X190289Y152050D03*
X190357Y247568D03*
X190817Y331786D03*
X189761Y421732D03*
X190553Y506517D03*
X192888Y598130D03*
X190816Y681645D03*
X191846Y774526D03*
X191606Y856244D03*
X196311Y947202D03*
X195516Y1032544D03*
X191250Y1122856D03*
X191342Y1206233D03*
X191846Y1299104D03*
X190552Y1380966D03*
X189463Y1474162D03*
X191079Y1557277D03*
X192143Y1648177D03*
X191607Y1731351D03*
X191530Y1823227D03*
X190289Y1900420D03*
X192125Y1998730D03*
X191530Y2043388D03*
X203542Y73105D03*
X204069Y152050D03*
X204137Y247568D03*
X204597Y331786D03*
X203541Y421732D03*
X204333Y506517D03*
X206668Y598130D03*
X204596Y681645D03*
X205626Y774526D03*
X205386Y856244D03*
X210091Y947202D03*
X209296Y1032544D03*
X205030Y1122856D03*
X205122Y1206233D03*
X205626Y1299104D03*
X204332Y1380966D03*
X203243Y1474162D03*
X204859Y1557277D03*
X205923Y1648177D03*
X205387Y1731351D03*
X205310Y1823227D03*
X204069Y1900420D03*
X205905Y1998730D03*
X205310Y2043388D03*
X553766Y677046D03*
G54D23*
X119920Y18071D03*
Y28071D03*
Y38071D03*
Y48071D03*
Y58071D03*
Y68071D03*
Y78071D03*
Y88071D03*
Y98071D03*
Y108071D03*
Y118071D03*
Y128071D03*
Y138071D03*
Y148071D03*
Y158071D03*
Y168071D03*
Y178071D03*
Y188071D03*
Y198071D03*
Y208071D03*
Y218071D03*
Y228071D03*
Y238071D03*
Y248071D03*
Y258071D03*
Y268071D03*
Y278071D03*
Y288071D03*
Y298071D03*
Y308071D03*
Y318071D03*
Y328071D03*
Y366102D03*
Y376102D03*
Y386102D03*
Y396102D03*
Y406102D03*
Y416102D03*
Y426102D03*
Y436102D03*
Y446102D03*
Y456102D03*
Y466102D03*
Y476102D03*
Y486102D03*
Y496102D03*
Y506102D03*
Y516102D03*
Y526102D03*
Y536102D03*
Y546102D03*
Y556102D03*
Y566102D03*
Y576102D03*
Y586102D03*
Y596102D03*
Y606102D03*
Y616102D03*
Y626102D03*
Y636102D03*
Y646102D03*
Y656102D03*
Y666102D03*
Y676102D03*
Y714134D03*
Y724134D03*
Y734134D03*
Y744134D03*
Y754134D03*
Y764134D03*
Y774134D03*
Y784134D03*
Y794134D03*
Y804134D03*
Y814134D03*
Y824134D03*
Y834134D03*
Y844134D03*
Y854134D03*
Y864134D03*
Y874134D03*
Y884134D03*
Y894134D03*
Y904134D03*
Y914134D03*
Y924134D03*
Y934134D03*
Y944134D03*
Y954134D03*
Y964134D03*
Y974134D03*
Y984134D03*
Y994134D03*
Y1004134D03*
Y1014134D03*
Y1024134D03*
Y1062165D03*
Y1072165D03*
Y1082165D03*
Y1092165D03*
Y1102165D03*
Y1112165D03*
Y1122165D03*
Y1132165D03*
Y1142165D03*
Y1152165D03*
Y1162165D03*
Y1172165D03*
Y1182165D03*
Y1192165D03*
Y1202165D03*
Y1212165D03*
Y1222165D03*
Y1232165D03*
Y1242165D03*
Y1252165D03*
Y1262165D03*
Y1272165D03*
Y1282165D03*
Y1292165D03*
Y1302165D03*
Y1312165D03*
Y1322165D03*
Y1332165D03*
Y1342165D03*
Y1352165D03*
Y1362165D03*
Y1372165D03*
Y1410197D03*
Y1420197D03*
Y1430197D03*
Y1440197D03*
Y1450197D03*
Y1460197D03*
Y1470197D03*
Y1480197D03*
Y1490197D03*
Y1500197D03*
Y1510197D03*
Y1520197D03*
Y1530197D03*
Y1540197D03*
Y1550197D03*
Y1560197D03*
Y1570197D03*
Y1580197D03*
Y1590197D03*
Y1600197D03*
Y1610197D03*
Y1620197D03*
Y1630197D03*
Y1640197D03*
Y1650197D03*
Y1660197D03*
Y1670197D03*
Y1680197D03*
Y1690197D03*
Y1700197D03*
Y1710197D03*
Y1720197D03*
Y1758228D03*
Y1768228D03*
Y1778228D03*
Y1788228D03*
Y1798228D03*
Y1808228D03*
Y1818228D03*
Y1828228D03*
Y1838228D03*
Y1848228D03*
Y1858228D03*
Y1868228D03*
Y1878228D03*
Y1888228D03*
Y1898228D03*
Y1908228D03*
Y1918228D03*
Y1928228D03*
Y1938228D03*
Y1948228D03*
Y1958228D03*
Y1968228D03*
Y1978228D03*
Y1988228D03*
Y1998228D03*
Y2008228D03*
Y2018228D03*
Y2028228D03*
Y2038228D03*
Y2048228D03*
Y2058228D03*
Y2068228D03*
X139920Y28071D03*
Y18071D03*
Y58071D03*
Y48071D03*
Y38071D03*
Y78071D03*
Y68071D03*
Y98071D03*
Y88071D03*
Y128071D03*
Y118071D03*
Y108071D03*
Y148071D03*
Y138071D03*
Y178071D03*
Y168071D03*
Y158071D03*
Y198071D03*
Y188071D03*
Y228071D03*
Y218071D03*
Y208071D03*
Y248071D03*
Y238071D03*
Y268071D03*
Y258071D03*
Y298071D03*
Y288071D03*
Y278071D03*
Y318071D03*
Y308071D03*
Y328071D03*
Y366102D03*
Y396102D03*
Y386102D03*
Y376102D03*
Y416102D03*
Y406102D03*
Y436102D03*
Y426102D03*
Y466102D03*
Y456102D03*
Y446102D03*
Y486102D03*
Y476102D03*
Y516102D03*
Y506102D03*
Y496102D03*
Y536102D03*
Y526102D03*
Y566102D03*
Y556102D03*
Y546102D03*
Y586102D03*
Y576102D03*
Y606102D03*
Y596102D03*
Y636102D03*
Y626102D03*
Y616102D03*
Y656102D03*
Y646102D03*
Y676102D03*
Y666102D03*
Y734134D03*
Y724134D03*
Y714134D03*
Y754134D03*
Y744134D03*
Y774134D03*
Y764134D03*
Y804134D03*
Y794134D03*
Y784134D03*
Y824134D03*
Y814134D03*
Y854134D03*
Y844134D03*
Y834134D03*
Y874134D03*
Y864134D03*
Y904134D03*
Y894134D03*
Y884134D03*
Y924134D03*
Y914134D03*
Y944134D03*
Y934134D03*
Y974134D03*
Y964134D03*
Y954134D03*
Y994134D03*
Y984134D03*
Y1024134D03*
Y1014134D03*
Y1004134D03*
Y1072165D03*
Y1062165D03*
Y1092165D03*
Y1082165D03*
Y1122165D03*
Y1112165D03*
Y1102165D03*
Y1142165D03*
Y1132165D03*
Y1162165D03*
Y1152165D03*
Y1192165D03*
Y1182165D03*
Y1172165D03*
Y1212165D03*
Y1202165D03*
Y1242165D03*
Y1232165D03*
Y1222165D03*
Y1262165D03*
Y1252165D03*
Y1282165D03*
Y1272165D03*
Y1312165D03*
Y1302165D03*
Y1292165D03*
Y1332165D03*
Y1322165D03*
Y1362165D03*
Y1352165D03*
Y1342165D03*
Y1372165D03*
Y1410197D03*
Y1430197D03*
Y1420197D03*
Y1460197D03*
Y1450197D03*
Y1440197D03*
Y1480197D03*
Y1470197D03*
Y1500197D03*
Y1490197D03*
Y1530197D03*
Y1520197D03*
Y1510197D03*
Y1550197D03*
Y1540197D03*
Y1580197D03*
Y1570197D03*
Y1560197D03*
Y1600197D03*
Y1590197D03*
Y1620197D03*
Y1610197D03*
Y1650197D03*
Y1640197D03*
Y1630197D03*
Y1670197D03*
Y1660197D03*
Y1700197D03*
Y1690197D03*
Y1680197D03*
Y1720197D03*
Y1710197D03*
Y1768228D03*
Y1758228D03*
Y1798228D03*
Y1788228D03*
Y1778228D03*
Y1818228D03*
Y1808228D03*
Y1838228D03*
Y1828228D03*
Y1868228D03*
Y1858228D03*
Y1848228D03*
Y1888228D03*
Y1878228D03*
Y1918228D03*
Y1908228D03*
Y1898228D03*
Y1938228D03*
Y1928228D03*
Y1958228D03*
Y1948228D03*
Y1988228D03*
Y1978228D03*
Y1968228D03*
Y2008228D03*
Y1998228D03*
Y2038228D03*
Y2028228D03*
Y2018228D03*
Y2058228D03*
Y2048228D03*
Y2068228D03*
X553766Y535296D03*
G54D14*
X13995Y543701D03*
Y1587992D03*
X58995Y543701D03*
Y1587992D03*
X553766Y299046D03*
G54D15*
X5491Y528544D03*
Y1603149D03*
X67499Y528544D03*
Y1603149D03*
X553766Y440796D03*
G54D24*
X163385Y27205D03*
Y202205D03*
Y377205D03*
X163386Y552205D03*
Y727205D03*
X163385Y902205D03*
Y1077205D03*
Y1252205D03*
Y1427205D03*
Y1602205D03*
Y1777205D03*
Y1952205D03*
X373385Y32520D03*
Y207520D03*
Y382520D03*
X373386Y557520D03*
Y732520D03*
X373385Y907520D03*
Y1082520D03*
Y1257520D03*
Y1432520D03*
Y1607520D03*
Y1782520D03*
Y1957520D03*
X553766Y346296D03*
G54D25*
X166500Y126110D03*
Y118626D03*
Y111407D03*
X166329Y140623D03*
X166500Y132705D03*
X166329Y148066D03*
Y156102D03*
Y163621D03*
X165975Y265783D03*
Y296140D03*
Y286803D03*
Y276298D03*
Y312307D03*
Y303868D03*
X156430Y461714D03*
Y483012D03*
X156259Y490930D03*
X156430Y468933D03*
Y476417D03*
X156259Y513928D03*
Y498373D03*
Y506409D03*
X157272Y604773D03*
Y633416D03*
Y613574D03*
Y624079D03*
Y641144D03*
Y649583D03*
X155444Y822725D03*
X162872D03*
Y830209D03*
X155444D03*
X171524Y844722D03*
Y852165D03*
X162872Y836804D03*
X155444D03*
X162701Y844722D03*
X155273D03*
X162701Y852165D03*
X155273D03*
X171524Y860201D03*
Y867720D03*
X162701Y860201D03*
X155273D03*
X162701Y867720D03*
X155273D03*
X166699Y972924D03*
Y983439D03*
Y993944D03*
X166424Y1011298D03*
Y1003570D03*
Y1019737D03*
X169375Y1176256D03*
Y1190335D03*
Y1183740D03*
X153124Y1176256D03*
X160552D03*
Y1183740D03*
Y1190335D03*
X153124D03*
Y1183740D03*
X160552Y1169037D03*
X153124D03*
X169204Y1198253D03*
X160381D03*
X152953D03*
X155749Y1307733D03*
Y1328753D03*
Y1318248D03*
Y1354257D03*
Y1338090D03*
Y1345818D03*
X154109Y1499221D03*
X161537D03*
Y1506440D03*
X170360D03*
X154109D03*
X153938Y1528437D03*
X154109Y1513924D03*
Y1520519D03*
X170360Y1513924D03*
Y1520519D03*
X161537D03*
Y1513924D03*
X161366Y1528437D03*
X170189D03*
X153938Y1535880D03*
Y1543916D03*
Y1551435D03*
X170189Y1535880D03*
Y1543916D03*
X161366Y1535880D03*
Y1543916D03*
Y1551435D03*
X170189D03*
X158492Y1667763D03*
Y1657248D03*
Y1695333D03*
Y1687605D03*
Y1678268D03*
Y1703772D03*
X152091Y1866003D03*
X159519D03*
X152091Y1880706D03*
Y1887301D03*
X168342Y1880706D03*
Y1887301D03*
X159519D03*
Y1880706D03*
Y1873222D03*
X168342D03*
X152091D03*
X151920Y1902662D03*
Y1910698D03*
X168171Y1902662D03*
Y1910698D03*
X159348Y1902662D03*
Y1910698D03*
X151920Y1895219D03*
X159348D03*
X168171D03*
X151920Y1918217D03*
X159348D03*
X168171D03*
X173928Y126110D03*
Y118626D03*
Y111407D03*
X173757Y140623D03*
X173928Y132705D03*
X173757Y148066D03*
Y156102D03*
Y163621D03*
X175033Y261594D03*
Y268813D03*
Y282892D03*
X174862Y290810D03*
Y298253D03*
X175033Y276297D03*
X174862Y313808D03*
Y306289D03*
X179191Y822725D03*
Y830209D03*
X171695Y822725D03*
Y830209D03*
X179191Y836804D03*
X171695D03*
X179020Y844722D03*
Y852165D03*
Y860201D03*
Y867720D03*
X176871Y1176256D03*
Y1190335D03*
Y1183740D03*
X176700Y1198253D03*
X177856Y1506440D03*
Y1513924D03*
Y1520519D03*
X177685Y1528437D03*
Y1535880D03*
Y1543916D03*
Y1551435D03*
X175838Y1880706D03*
Y1887301D03*
Y1873222D03*
X175667Y1902662D03*
Y1910698D03*
Y1895219D03*
Y1918217D03*
X219214Y1287272D03*
Y1301975D03*
X219349Y1308924D03*
X219214Y1294491D03*
X219178Y1324285D03*
Y1332321D03*
Y1316842D03*
Y1339840D03*
X240955Y56999D03*
Y64483D03*
X240784Y78996D03*
X240955Y71078D03*
X240784Y94475D03*
Y101994D03*
Y86439D03*
X243741Y153964D03*
X222732D03*
X232700D03*
X243741Y170131D03*
Y161692D03*
X222732Y170131D03*
Y161692D03*
X232700Y170131D03*
Y161692D03*
X236537Y244995D03*
X227714Y237776D03*
Y244995D03*
X244033D03*
X236537Y259074D03*
X236366Y266992D03*
Y274435D03*
X227714Y259074D03*
X227543Y266992D03*
Y274435D03*
X244033Y259074D03*
X243862Y266992D03*
Y274435D03*
X236537Y252479D03*
X227714D03*
X244033D03*
X236366Y289990D03*
X227543D03*
X243862D03*
X236366Y282471D03*
X227543D03*
X243862D03*
X239746Y407393D03*
Y396878D03*
Y417898D03*
X232548Y461083D03*
X241371Y482381D03*
X241200Y490299D03*
X232548Y482381D03*
X232377Y490299D03*
X241371Y468302D03*
Y475786D03*
X232548Y468302D03*
Y475786D03*
X241200Y513297D03*
X232377D03*
X241200Y497742D03*
X232377D03*
X241200Y505778D03*
X232377D03*
X230963Y608108D03*
X238391D03*
X230963Y601513D03*
X238391D03*
Y594029D03*
X230963D03*
X230792Y631505D03*
X238220D03*
X230792Y623469D03*
X238220D03*
X230792Y616026D03*
X238220D03*
X230792Y639024D03*
X238220D03*
X243980Y754782D03*
X234012D03*
X243980Y762510D03*
Y770949D03*
X234012Y762510D03*
Y770949D03*
X231339Y959673D03*
X238767D03*
Y967157D03*
Y973752D03*
X231339D03*
Y967157D03*
X238767Y952454D03*
X231339D03*
X238596Y981670D03*
X231168D03*
X238596Y997149D03*
Y989113D03*
X231168Y997149D03*
Y989113D03*
X238596Y1004668D03*
X231168D03*
X238659Y1215296D03*
X231231D03*
X238659Y1207777D03*
Y1199741D03*
X231231Y1207777D03*
Y1199741D03*
X226642Y1287272D03*
Y1301975D03*
X235465D03*
X226777Y1308924D03*
X235600D03*
X242961Y1301975D03*
X243096Y1308924D03*
X226642Y1294491D03*
X235465D03*
X242961D03*
X226606Y1324285D03*
X235429D03*
X226606Y1332321D03*
X235429D03*
X242925Y1324285D03*
Y1332321D03*
X226606Y1316842D03*
X235429D03*
X242925D03*
X226606Y1339840D03*
X235429D03*
X242925D03*
X225131Y1663167D03*
X241382Y1670386D03*
X232559Y1663167D03*
Y1670386D03*
X225131D03*
X241211Y1699826D03*
X241382Y1677870D03*
X241211Y1692383D03*
X241382Y1684465D03*
X232559D03*
Y1677870D03*
X232388Y1692383D03*
Y1699826D03*
X225131Y1684465D03*
Y1677870D03*
X224960Y1692383D03*
Y1699826D03*
X241211Y1715381D03*
Y1707862D03*
X232388D03*
Y1715381D03*
X224960Y1707862D03*
Y1715381D03*
X224573Y2031480D03*
X234541D03*
X224573Y2020965D03*
X234541D03*
X224573Y2059050D03*
X234541Y2051322D03*
Y2059050D03*
X224573Y2041985D03*
Y2051322D03*
X234541Y2041985D03*
Y2067489D03*
X224573D03*
X256566Y54944D03*
X264104D03*
X256566Y45572D03*
X264104D03*
X248451Y56999D03*
X256566Y65449D03*
X264104D03*
X248451Y64483D03*
X248280Y78996D03*
X248451Y71078D03*
X248280Y94475D03*
Y101994D03*
Y86439D03*
X264861Y153964D03*
X253083D03*
X264861Y170131D03*
Y161692D03*
X253083Y170131D03*
Y161692D03*
X264596Y221664D03*
X252818D03*
X264596Y242684D03*
Y232179D03*
X252818Y242684D03*
Y232179D03*
X264596Y268188D03*
Y259749D03*
Y252021D03*
X252818Y268188D03*
Y252021D03*
Y259749D03*
X266040Y407146D03*
Y396631D03*
Y417651D03*
X257572Y396630D03*
Y407145D03*
X248714Y407536D03*
Y397021D03*
X257572Y417650D03*
X248714Y418041D03*
X248867Y482381D03*
X248696Y490299D03*
X248867Y468302D03*
Y475786D03*
X248696Y513297D03*
Y497742D03*
Y505778D03*
X267166Y581440D03*
Y572639D03*
Y609010D03*
Y601282D03*
Y591945D03*
X254710Y608108D03*
Y601513D03*
Y594029D03*
X247214Y608108D03*
Y601513D03*
Y594029D03*
X267166Y617449D03*
X254539Y631505D03*
Y623469D03*
Y616026D03*
X247043Y631505D03*
Y623469D03*
Y616026D03*
X267433Y624321D03*
X254539Y639024D03*
X247043D03*
X255021Y754782D03*
Y762510D03*
Y770949D03*
X263174Y855159D03*
Y862887D03*
X251396D03*
Y855159D03*
Y871326D03*
X263174D03*
X262766Y949344D03*
Y967106D03*
Y959859D03*
X262621Y974386D03*
X255086Y959673D03*
Y973752D03*
Y967157D03*
X247590Y959673D03*
Y973752D03*
Y967157D03*
X262621Y990553D03*
Y982114D03*
X254915Y981670D03*
Y997149D03*
Y989113D03*
X247419Y981670D03*
Y997149D03*
Y989113D03*
X254915Y1004668D03*
X247419D03*
X261219Y1124364D03*
Y1134879D03*
X251251Y1124364D03*
Y1134879D03*
X261219Y1145384D03*
X251251D03*
X254978Y1215296D03*
X247482D03*
X254978Y1207777D03*
Y1199741D03*
X247482Y1207777D03*
Y1199741D03*
X259581Y1272430D03*
Y1282945D03*
Y1293450D03*
Y1302787D03*
Y1310515D03*
Y1318954D03*
X263939Y1548010D03*
Y1534139D03*
Y1541055D03*
X261564Y1621823D03*
Y1642843D03*
Y1632338D03*
Y1668347D03*
Y1659908D03*
Y1652180D03*
X248878Y1670386D03*
X265759Y1697613D03*
X254718D03*
X265759Y1676593D03*
Y1687108D03*
X254718D03*
Y1676593D03*
X248707Y1699826D03*
X248878Y1677870D03*
Y1684465D03*
X248707Y1692383D03*
X254457Y1722140D03*
X265498D03*
X265759Y1714678D03*
X254718D03*
Y1706950D03*
X265759D03*
X248707Y1707862D03*
Y1715381D03*
X258639Y1819074D03*
Y1812119D03*
Y1805203D03*
X250468Y1819074D03*
Y1812119D03*
Y1805203D03*
X267396Y1819077D03*
Y1805206D03*
Y1812122D03*
X258459Y1826219D03*
X250288D03*
X267037Y1826222D03*
X258459Y1840090D03*
Y1833135D03*
X267037Y1833138D03*
Y1840093D03*
X250288Y1833135D03*
Y1840090D03*
X245582Y2031480D03*
Y2020965D03*
X258337D03*
Y2031480D03*
X245582Y2041985D03*
Y2051322D03*
Y2059050D03*
X258337Y2051322D03*
Y2059050D03*
Y2041985D03*
Y2067489D03*
X245582D03*
X288102Y54944D03*
Y45572D03*
X271572Y54944D03*
X279754D03*
X271572Y45572D03*
X279754D03*
X288102Y65449D03*
X271572D03*
X279754D03*
X274531Y407289D03*
Y396774D03*
Y417794D03*
X278944Y581440D03*
Y572639D03*
Y601282D03*
Y609010D03*
Y591945D03*
Y617449D03*
X279044Y624627D03*
X274544Y949344D03*
Y967106D03*
Y959859D03*
X274399Y974386D03*
Y990553D03*
Y982114D03*
X279015Y1124077D03*
X288363Y1123935D03*
X279015Y1134592D03*
X288363Y1134450D03*
X269975Y1134735D03*
Y1124220D03*
X288363Y1144955D03*
X279015Y1145097D03*
X269975Y1145240D03*
X286721Y1184312D03*
Y1192040D03*
X278182Y1184455D03*
Y1192183D03*
X286721Y1200479D03*
X278182Y1200622D03*
X270622Y1282945D03*
Y1272430D03*
Y1293450D03*
Y1302787D03*
Y1310515D03*
Y1318954D03*
X278400Y1548190D03*
X271534Y1548010D03*
X285995Y1548190D03*
X278400Y1534319D03*
Y1541235D03*
X271534Y1534139D03*
Y1541055D03*
X285995Y1534319D03*
Y1541235D03*
X273342Y1621823D03*
Y1642843D03*
Y1632338D03*
Y1668347D03*
Y1652180D03*
Y1659908D03*
X270115Y2031480D03*
Y2020965D03*
Y2051322D03*
Y2059050D03*
Y2041985D03*
Y2067489D03*
X300537Y516309D03*
X307966Y516419D03*
Y524147D03*
X300537Y524037D03*
Y532476D03*
X307966Y532586D03*
X292569Y524323D03*
Y516595D03*
Y532762D03*
X315187Y652457D03*
Y661258D03*
X304146D03*
Y652457D03*
Y681100D03*
X315187D03*
Y671763D03*
X304146D03*
X315187Y688828D03*
X304146D03*
Y697267D03*
X315187D03*
X307194Y1020657D03*
X307078Y1007303D03*
X307274Y1001286D03*
X307143Y1014094D03*
X307129Y1027081D03*
X306999Y1033718D03*
X303159Y1184526D03*
Y1192254D03*
X311936Y1192253D03*
Y1184525D03*
X294691Y1184526D03*
Y1192254D03*
X311936Y1200692D03*
X303159Y1200693D03*
X294691D03*
X309823Y1472957D03*
X309464Y1480102D03*
X309823Y1466002D03*
Y1459086D03*
X292715Y1480099D03*
X292895Y1472954D03*
X301066D03*
X300886Y1480099D03*
X292895Y1459083D03*
Y1465999D03*
X301066D03*
Y1459083D03*
X309464Y1493973D03*
Y1487018D03*
X292715Y1487015D03*
Y1493970D03*
X300886D03*
Y1487015D03*
X292754Y1917148D03*
X300349D03*
X292754Y1910232D03*
X300349D03*
X307215Y1910412D03*
X314810D03*
Y1917328D03*
X307215D03*
X292754Y1924103D03*
X300349D03*
X314810Y1924283D03*
X307215D03*
X332775Y318634D03*
X332693Y311980D03*
X332775Y335272D03*
Y342461D03*
Y325935D03*
X332685Y348655D03*
X325139Y516632D03*
Y524360D03*
X316791Y524432D03*
Y516704D03*
Y532871D03*
X325139Y532799D03*
X318235Y1020657D03*
X318315Y1001286D03*
X318119Y1007303D03*
X318184Y1014094D03*
X318170Y1027081D03*
X318040Y1033718D03*
X343816Y318634D03*
X343734Y311980D03*
X343816Y335272D03*
Y342461D03*
Y325935D03*
X343726Y348655D03*
X354391Y1329686D03*
Y1350706D03*
Y1360043D03*
Y1340201D03*
Y1376210D03*
Y1367771D03*
X366169Y1329686D03*
Y1350706D03*
Y1360043D03*
Y1340201D03*
Y1376210D03*
Y1367771D03*
X553766Y866046D03*
G54D16*
X17480Y599901D03*
X9606D03*
X17480Y627264D03*
X9606D03*
X17480Y1471949D03*
X9606D03*
X17480Y1499311D03*
X9606D03*
X553766Y582546D03*
G54D26*
X307086Y308267D03*
X553766Y157296D03*
G54D17*
X15547Y707364D03*
X25389D03*
X7673Y703427D03*
X15547Y715238D03*
Y723112D03*
Y730986D03*
X25389Y715238D03*
Y723112D03*
Y730986D03*
X7673Y711301D03*
Y719175D03*
Y727049D03*
X15547Y738860D03*
Y746734D03*
Y754608D03*
X25389Y738860D03*
Y746734D03*
Y754608D03*
X7673Y734923D03*
Y742797D03*
Y750671D03*
Y758545D03*
X15547Y762483D03*
Y770357D03*
Y778231D03*
X25389Y762483D03*
Y770357D03*
Y778231D03*
X7673Y766419D03*
Y774293D03*
Y782167D03*
X15547Y786105D03*
Y793979D03*
Y801853D03*
X25389Y786105D03*
Y793979D03*
Y801853D03*
X7673Y790041D03*
Y797915D03*
Y805790D03*
X15547Y809727D03*
Y817601D03*
Y825475D03*
X25389Y809727D03*
Y817601D03*
Y825475D03*
X7673Y813664D03*
Y821538D03*
Y829412D03*
X15547Y833349D03*
Y841223D03*
Y849097D03*
X25389Y833349D03*
Y841223D03*
Y849097D03*
X7673Y837286D03*
Y845160D03*
Y853034D03*
X15547Y856971D03*
Y864845D03*
Y872719D03*
X25389Y856971D03*
Y864845D03*
Y872719D03*
X7673Y860908D03*
Y868782D03*
Y876656D03*
X15547Y880593D03*
Y888467D03*
Y896341D03*
X25389Y880593D03*
Y888467D03*
Y896341D03*
X7673Y884530D03*
Y892404D03*
Y900278D03*
X15547Y904215D03*
Y912089D03*
Y919963D03*
X25389Y904215D03*
Y912089D03*
Y919963D03*
X7673Y908152D03*
Y916026D03*
Y923900D03*
X15547Y927837D03*
Y935711D03*
Y943585D03*
Y951459D03*
X25389Y927837D03*
Y935711D03*
Y943585D03*
Y951459D03*
X7673Y931774D03*
Y939648D03*
Y947522D03*
X15547Y959333D03*
Y967207D03*
Y975081D03*
X25389Y959333D03*
Y967207D03*
Y975081D03*
X7673Y955396D03*
Y963270D03*
Y971144D03*
Y979018D03*
Y994766D03*
X15547Y990829D03*
Y998703D03*
X25389Y990829D03*
Y998703D03*
X7673Y1002640D03*
Y1010514D03*
Y1018388D03*
X15547Y1006577D03*
Y1014451D03*
Y1022325D03*
X25389Y1006577D03*
Y1014451D03*
Y1022325D03*
X7673Y1026262D03*
X15547Y1030199D03*
X25389D03*
X15551Y1065629D03*
X25393D03*
X7677Y1061692D03*
Y1069566D03*
X15551Y1073503D03*
Y1081377D03*
Y1089251D03*
X25393Y1073503D03*
Y1081377D03*
Y1089251D03*
X7677Y1077440D03*
Y1085314D03*
Y1093188D03*
X15551Y1097125D03*
Y1104999D03*
Y1112873D03*
Y1120748D03*
X25393Y1097125D03*
Y1104999D03*
Y1112873D03*
Y1120748D03*
X7677Y1101062D03*
Y1108936D03*
Y1116810D03*
X15551Y1128622D03*
Y1136496D03*
Y1144370D03*
X25393Y1128622D03*
Y1136496D03*
Y1144370D03*
X7677Y1124684D03*
Y1132558D03*
Y1140432D03*
X15551Y1152244D03*
Y1160118D03*
Y1167992D03*
X25393Y1152244D03*
Y1160118D03*
Y1167992D03*
X7677Y1148306D03*
Y1156180D03*
Y1164055D03*
X15551Y1175866D03*
Y1183740D03*
Y1191614D03*
X25393Y1175866D03*
Y1183740D03*
Y1191614D03*
X7677Y1171929D03*
Y1179803D03*
Y1187677D03*
X15551Y1199488D03*
Y1207362D03*
Y1215236D03*
X25393Y1199488D03*
Y1207362D03*
Y1215236D03*
X7677Y1195551D03*
Y1203425D03*
Y1211299D03*
X15551Y1223110D03*
Y1230984D03*
Y1238858D03*
X25393Y1223110D03*
Y1230984D03*
Y1238858D03*
X7677Y1219173D03*
Y1227047D03*
Y1234921D03*
X15551Y1246732D03*
Y1254606D03*
Y1262480D03*
X25393Y1246732D03*
Y1254606D03*
Y1262480D03*
X7677Y1242795D03*
Y1250669D03*
Y1258543D03*
X15551Y1270354D03*
Y1278228D03*
Y1286102D03*
X25393Y1270354D03*
Y1278228D03*
Y1286102D03*
X7677Y1266417D03*
Y1274291D03*
Y1282165D03*
X15551Y1293976D03*
Y1301850D03*
Y1309724D03*
X25393Y1293976D03*
Y1301850D03*
Y1309724D03*
X7677Y1290039D03*
Y1297913D03*
Y1305787D03*
Y1313661D03*
X15551Y1317598D03*
Y1325472D03*
Y1333346D03*
X25393Y1317598D03*
Y1325472D03*
Y1333346D03*
X7677Y1321535D03*
Y1329409D03*
Y1337283D03*
Y1353031D03*
Y1360905D03*
X15551Y1349094D03*
Y1356968D03*
X25393Y1349094D03*
Y1356968D03*
X7677Y1368779D03*
Y1376653D03*
Y1384527D03*
X15551Y1364842D03*
Y1372716D03*
Y1380590D03*
X25393Y1364842D03*
Y1372716D03*
Y1380590D03*
X15551Y1388464D03*
X25393D03*
X33263Y703427D03*
Y711301D03*
Y719175D03*
Y727049D03*
Y734923D03*
Y742797D03*
Y750671D03*
Y758545D03*
Y766419D03*
Y774293D03*
Y782167D03*
Y790041D03*
Y797915D03*
Y805790D03*
Y813664D03*
Y821538D03*
Y829412D03*
Y837286D03*
Y845160D03*
Y853034D03*
Y860908D03*
Y868782D03*
Y876656D03*
Y884530D03*
Y892404D03*
Y900278D03*
Y908152D03*
Y916026D03*
Y923900D03*
Y931774D03*
Y939648D03*
Y947522D03*
Y955396D03*
Y963270D03*
Y971144D03*
Y979018D03*
Y994766D03*
Y1002640D03*
Y1010514D03*
Y1018388D03*
Y1026262D03*
X33267Y1061692D03*
Y1069566D03*
Y1077440D03*
Y1085314D03*
Y1093188D03*
Y1101062D03*
Y1108936D03*
Y1116810D03*
Y1124684D03*
Y1132558D03*
Y1140432D03*
Y1148306D03*
Y1156180D03*
Y1164055D03*
Y1171929D03*
Y1179803D03*
Y1187677D03*
Y1195551D03*
Y1203425D03*
Y1211299D03*
Y1219173D03*
Y1227047D03*
Y1234921D03*
Y1242795D03*
Y1250669D03*
Y1258543D03*
Y1266417D03*
Y1274291D03*
Y1282165D03*
Y1290039D03*
Y1297913D03*
Y1305787D03*
Y1313661D03*
Y1321535D03*
Y1329409D03*
Y1337283D03*
Y1353031D03*
Y1360905D03*
Y1368779D03*
Y1376653D03*
Y1384527D03*
X173385Y32520D03*
Y21890D03*
X183385Y32520D03*
Y21890D03*
X193385Y32520D03*
Y21890D03*
X173385Y196890D03*
X183385D03*
X193385D03*
X173385Y207520D03*
X183385D03*
X193385D03*
X173385Y371890D03*
X183385D03*
X193385D03*
X173385Y382520D03*
X183385D03*
X193385D03*
X173386Y557520D03*
Y546890D03*
X183386Y557520D03*
Y546890D03*
X193386Y557520D03*
Y546890D03*
X173386Y732520D03*
Y721890D03*
X183386Y732520D03*
Y721890D03*
X193386Y732520D03*
Y721890D03*
X173385Y896890D03*
X183385D03*
X193385D03*
X173385Y907520D03*
X183385D03*
X193385D03*
X173385Y1071890D03*
X183385D03*
X193385D03*
X173385Y1082520D03*
X183385D03*
X193385D03*
X173385Y1257520D03*
Y1246890D03*
X183385Y1257520D03*
Y1246890D03*
X193385Y1257520D03*
Y1246890D03*
X173385Y1432520D03*
Y1421890D03*
X183385Y1432520D03*
Y1421890D03*
X193385Y1432520D03*
Y1421890D03*
X173385Y1596890D03*
X183385D03*
X193385D03*
X173385Y1607520D03*
X183385D03*
X193385D03*
X173385Y1771890D03*
X183385D03*
X193385D03*
X173385Y1782520D03*
X183385D03*
X193385D03*
X173385Y1957520D03*
Y1946890D03*
X183385Y1957520D03*
Y1946890D03*
X193385Y1957520D03*
Y1946890D03*
X203385Y32520D03*
Y21890D03*
X213385Y32520D03*
Y21890D03*
X203385Y196890D03*
X213385D03*
X203385Y207520D03*
X213385D03*
X203385Y371890D03*
X213385D03*
X203385Y382520D03*
X213385D03*
X203386Y557520D03*
Y546890D03*
X213386Y557520D03*
Y546890D03*
X203386Y732520D03*
Y721890D03*
X213386Y732520D03*
Y721890D03*
X203385Y896890D03*
X213385D03*
X203385Y907520D03*
X213385D03*
X203385Y1071890D03*
X213385D03*
X203385Y1082520D03*
X213385D03*
X203385Y1257520D03*
Y1246890D03*
X213385Y1257520D03*
Y1246890D03*
X203385Y1432520D03*
Y1421890D03*
X213385Y1432520D03*
Y1421890D03*
X203385Y1596890D03*
X213385D03*
X203385Y1607520D03*
X213385D03*
X203385Y1771890D03*
X213385D03*
X203385Y1782520D03*
X213385D03*
X203385Y1957520D03*
Y1946890D03*
X213385Y1957520D03*
Y1946890D03*
X223385Y32520D03*
Y21890D03*
X233385Y32520D03*
Y21890D03*
X243385Y32520D03*
Y21890D03*
X223385Y196890D03*
X233385D03*
X243385D03*
X223385Y207520D03*
X233385D03*
X243385D03*
X223385Y371890D03*
X233385D03*
X243385D03*
X223385Y382520D03*
X233385D03*
X243385D03*
X223386Y557520D03*
Y546890D03*
X233386Y557520D03*
Y546890D03*
X243386Y557520D03*
Y546890D03*
X223386Y732520D03*
Y721890D03*
X233386Y732520D03*
Y721890D03*
X243386Y732520D03*
Y721890D03*
X223385Y896890D03*
X233385D03*
X243385D03*
X223385Y907520D03*
X233385D03*
X243385D03*
X223385Y1071890D03*
X233385D03*
X243385D03*
X223385Y1082520D03*
X233385D03*
X243385D03*
X223385Y1257520D03*
Y1246890D03*
X233385Y1257520D03*
Y1246890D03*
X243385Y1257520D03*
Y1246890D03*
X223385Y1432520D03*
Y1421890D03*
X233385Y1432520D03*
Y1421890D03*
X243385Y1432520D03*
Y1421890D03*
X223385Y1596890D03*
X233385D03*
X243385D03*
X223385Y1607520D03*
X233385D03*
X243385D03*
X223385Y1771890D03*
X233385D03*
X243385D03*
X223385Y1782520D03*
X233385D03*
X243385D03*
X223385Y1957520D03*
Y1946890D03*
X233385Y1957520D03*
Y1946890D03*
X243385Y1957520D03*
Y1946890D03*
X253385Y21890D03*
Y32520D03*
X263385Y21890D03*
Y32520D03*
X253385Y196890D03*
X263385D03*
X253385Y207520D03*
X263385D03*
X253385Y371890D03*
X263385D03*
X253385Y382520D03*
X263385D03*
X253386Y546890D03*
Y557520D03*
X263386Y546890D03*
Y557520D03*
X253386Y721890D03*
Y732520D03*
X263386Y721890D03*
Y732520D03*
X253385Y896890D03*
X263385D03*
X253385Y907520D03*
X263385D03*
X253385Y1071890D03*
X263385D03*
X253385Y1082520D03*
X263385D03*
X253385Y1246890D03*
Y1257520D03*
X263385Y1246890D03*
Y1257520D03*
X253385Y1421890D03*
Y1432520D03*
X263385Y1421890D03*
Y1432520D03*
X253385Y1596890D03*
X263385D03*
X253385Y1607520D03*
X263385D03*
X253385Y1771890D03*
X263385D03*
X253385Y1782520D03*
X263385D03*
X253385Y1946890D03*
Y1957520D03*
X263385Y1946890D03*
Y1957520D03*
X273385Y21890D03*
Y32520D03*
X283385Y21890D03*
Y32520D03*
X273385Y196890D03*
X283385D03*
X273385Y207520D03*
X283385D03*
X273385Y371890D03*
X283385D03*
X273385Y382520D03*
X283385D03*
X273386Y546890D03*
Y557520D03*
X283386Y546890D03*
Y557520D03*
X273386Y721890D03*
Y732520D03*
X283386Y721890D03*
Y732520D03*
X273385Y896890D03*
X283385D03*
X273385Y907520D03*
X283385D03*
X273385Y1071890D03*
X283385D03*
X273385Y1082520D03*
X283385D03*
X273385Y1246890D03*
Y1257520D03*
X283385Y1246890D03*
Y1257520D03*
X273385Y1421890D03*
Y1432520D03*
X283385Y1421890D03*
Y1432520D03*
X273385Y1596890D03*
X283385D03*
X273385Y1607520D03*
X283385D03*
X273385Y1771890D03*
X283385D03*
X273385Y1782520D03*
X283385D03*
X273385Y1946890D03*
Y1957520D03*
X283385Y1946890D03*
Y1957520D03*
X293385Y21890D03*
Y32520D03*
X303385Y21890D03*
Y32520D03*
X313385D03*
Y21890D03*
X293385Y196890D03*
X303385D03*
X313385D03*
X293385Y207520D03*
X303385D03*
X313385D03*
X293385Y371890D03*
X303385D03*
X313385D03*
X293385Y382520D03*
X303385D03*
X313385D03*
X293386Y546890D03*
Y557520D03*
X303386Y546890D03*
Y557520D03*
X313386D03*
Y546890D03*
X293386Y721890D03*
Y732520D03*
X303386Y721890D03*
Y732520D03*
X313386D03*
Y721890D03*
X293385Y896890D03*
X303385D03*
X313385D03*
X293385Y907520D03*
X303385D03*
X313385D03*
X293385Y1071890D03*
X303385D03*
X313385D03*
X293385Y1082520D03*
X303385D03*
X313385D03*
X293385Y1246890D03*
Y1257520D03*
X303385Y1246890D03*
Y1257520D03*
X313385D03*
Y1246890D03*
X293385Y1421890D03*
Y1432520D03*
X303385Y1421890D03*
Y1432520D03*
X313385D03*
Y1421890D03*
X293385Y1596890D03*
X303385D03*
X313385D03*
X293385Y1607520D03*
X303385D03*
X313385D03*
X293385Y1771890D03*
X303385D03*
X313385D03*
X293385Y1782520D03*
X303385D03*
X313385D03*
X293385Y1946890D03*
Y1957520D03*
X303385Y1946890D03*
Y1957520D03*
X313385D03*
Y1946890D03*
X337165Y24705D03*
X323385Y32520D03*
Y21890D03*
X337165Y34705D03*
Y199705D03*
X323385Y196890D03*
X337165Y209705D03*
X323385Y207520D03*
Y371890D03*
X337165Y374705D03*
Y384705D03*
X323385Y382520D03*
X337166Y549705D03*
Y559705D03*
X323386Y557520D03*
Y546890D03*
X337166Y724705D03*
X323386Y732520D03*
Y721890D03*
X337166Y734705D03*
X337165Y899705D03*
X323385Y896890D03*
X337165Y909705D03*
X323385Y907520D03*
Y1071890D03*
X337165Y1074705D03*
Y1084705D03*
X323385Y1082520D03*
X337165Y1249705D03*
Y1259705D03*
X323385Y1257520D03*
Y1246890D03*
X337165Y1424705D03*
Y1434705D03*
X323385Y1432520D03*
Y1421890D03*
X337165Y1599705D03*
X323385Y1596890D03*
X337165Y1609705D03*
X323385Y1607520D03*
Y1771890D03*
X337165Y1774705D03*
Y1784705D03*
X323385Y1782520D03*
X337165Y1949705D03*
Y1959705D03*
X323385Y1957520D03*
Y1946890D03*
X342165Y19705D03*
Y29705D03*
X347165Y24705D03*
X352165Y19705D03*
Y29705D03*
X357165Y24705D03*
X362165Y19705D03*
Y29705D03*
X347165Y34705D03*
X357165D03*
X342165Y194705D03*
X347165Y199705D03*
X352165Y194705D03*
X357165Y199705D03*
X362165Y194705D03*
X342165Y204705D03*
X347165Y209705D03*
X352165Y204705D03*
X357165Y209705D03*
X362165Y204705D03*
X342165Y369705D03*
X352165D03*
X362165D03*
X342165Y379705D03*
X347165Y374705D03*
Y384705D03*
X352165Y379705D03*
X357165Y374705D03*
Y384705D03*
X362165Y379705D03*
X342166Y544705D03*
Y554705D03*
X347166Y549705D03*
Y559705D03*
X352166Y544705D03*
Y554705D03*
X357166Y549705D03*
Y559705D03*
X362166Y544705D03*
Y554705D03*
X342166Y719705D03*
Y729705D03*
X347166Y724705D03*
X352166Y719705D03*
Y729705D03*
X357166Y724705D03*
X362166Y719705D03*
Y729705D03*
X347166Y734705D03*
X357166D03*
X342165Y894705D03*
X347165Y899705D03*
X352165Y894705D03*
X357165Y899705D03*
X362165Y894705D03*
X342165Y904705D03*
X347165Y909705D03*
X352165Y904705D03*
X357165Y909705D03*
X362165Y904705D03*
X342165Y1069705D03*
X352165D03*
X362165D03*
X342165Y1079705D03*
X347165Y1074705D03*
Y1084705D03*
X352165Y1079705D03*
X357165Y1074705D03*
Y1084705D03*
X362165Y1079705D03*
X342165Y1244705D03*
Y1254705D03*
X347165Y1249705D03*
Y1259705D03*
X352165Y1244705D03*
Y1254705D03*
X357165Y1249705D03*
Y1259705D03*
X362165Y1244705D03*
Y1254705D03*
X342165Y1419705D03*
Y1429705D03*
X347165Y1424705D03*
Y1434705D03*
X352165Y1419705D03*
Y1429705D03*
X357165Y1424705D03*
Y1434705D03*
X362165Y1419705D03*
Y1429705D03*
X342165Y1594705D03*
X347165Y1599705D03*
X352165Y1594705D03*
X357165Y1599705D03*
X362165Y1594705D03*
X342165Y1604705D03*
X347165Y1609705D03*
X352165Y1604705D03*
X357165Y1609705D03*
X362165Y1604705D03*
X342165Y1769705D03*
X352165D03*
X362165D03*
X342165Y1779705D03*
X347165Y1774705D03*
Y1784705D03*
X352165Y1779705D03*
X357165Y1774705D03*
Y1784705D03*
X362165Y1779705D03*
X342165Y1944705D03*
Y1954705D03*
X347165Y1949705D03*
Y1959705D03*
X352165Y1944705D03*
Y1954705D03*
X357165Y1949705D03*
Y1959705D03*
X362165Y1944705D03*
Y1954705D03*
X553766Y724296D03*
Y771546D03*
G54D27*
X307086Y1883071D03*
X553766Y62796D03*
G54D18*
X20468Y696341D03*
Y984333D03*
X20472Y1054606D03*
Y1342598D03*
X553766Y393546D03*
G54D19*
X23402Y1668874D03*
Y1685410D03*
Y1701945D03*
Y1718480D03*
Y1735016D03*
Y1751551D03*
Y1768087D03*
Y1784622D03*
Y1817693D03*
Y1801158D03*
X45056Y1668874D03*
Y1685410D03*
Y1701945D03*
Y1718480D03*
Y1735016D03*
Y1751551D03*
Y1768087D03*
Y1784622D03*
Y1817693D03*
Y1801158D03*
X553766Y488046D03*
G54D28*
X359842Y78780D03*
Y253780D03*
Y428779D03*
Y603779D03*
Y778780D03*
Y953780D03*
Y1128779D03*
Y1303780D03*
Y1478780D03*
Y1653780D03*
Y1828779D03*
Y2003780D03*
X553766Y110046D03*
G54D29*
G01X-723776Y2987387D02*
Y-376795D01*
Y-489221D01*
X1782976D01*
Y-376795D01*
Y2987387D01*
X-723776D01*
G01X-95126Y0D02*
X-226725D01*
G01X-223725Y1064812D02*
Y0D01*
G01X-224725Y5000D02*
X-223725Y0D01*
X-222725Y5000D01*
X-224725D01*
G01X-223725Y1123662D02*
Y2086614D01*
G01X-222725Y2081614D02*
X-223725Y2086614D01*
X-224725Y2081614D01*
X-222725D01*
G01X-95126Y2086614D02*
X-226725D01*
G01X-96280Y2392259D02*
X-108780D01*
X-106280Y2390399D01*
G01X-96280D02*
Y2394119D01*
G01X-108780Y2404659D02*
X-108363Y2403419D01*
X-107322Y2402489D01*
X-106072Y2401869D01*
X-104405Y2401404D01*
X-102530Y2401249D01*
X-100655Y2401404D01*
X-98988Y2401869D01*
X-97738Y2402489D01*
X-96697Y2403419D01*
X-96280Y2404659D01*
X-96697Y2405899D01*
X-97738Y2406829D01*
X-98988Y2407449D01*
X-100655Y2407914D01*
X-102530Y2408069D01*
X-104405Y2407914D01*
X-106072Y2407449D01*
X-107322Y2406829D01*
X-108363Y2405899D01*
X-108780Y2404659D01*
G01X-96280Y2413029D02*
X-108780D01*
X-98363Y2417059D01*
X-108780Y2421089D01*
X-96280D01*
G01Y2425429D02*
X-108780D01*
X-98363Y2429459D01*
X-108780Y2433489D01*
X-96280D01*
G01X7874Y0D02*
X-92126D01*
G01X3000D02*
X-85641D01*
G01X-92126Y2086614D02*
X7874D01*
G01X-87421Y2397079D02*
Y2365583D01*
G01D02*
Y2416764D01*
G01X-21191Y2397079D02*
X-95295D01*
G01X-87421Y2467945D02*
Y2416764D01*
G01Y2436449D02*
Y2467945D01*
G01X-22045Y2436449D02*
X-95295D01*
G01X-62751Y2483687D02*
X-75251D01*
X-66293Y2477952D01*
Y2485702D01*
G01X-62751Y2490197D02*
X-75251D01*
X-64834Y2494227D01*
X-75251Y2498257D01*
X-62751D01*
G01Y2502597D02*
X-75251D01*
X-64834Y2506627D01*
X-75251Y2510657D01*
X-62751D01*
G01X-69451Y2628627D02*
X-67451D01*
Y2626227D01*
X-68051Y2625427D01*
X-68751Y2624894D01*
X-69751Y2624627D01*
X-70751Y2624894D01*
X-71451Y2625427D01*
X-72051Y2626227D01*
X-72451Y2627160D01*
X-72651Y2628227D01*
Y2629160D01*
X-72451Y2629960D01*
X-72051Y2630894D01*
X-71451Y2631694D01*
X-70851Y2632227D01*
X-70051Y2632627D01*
X-69351D01*
X-68551Y2632360D01*
X-67951Y2631827D01*
G01X-64051Y2624627D02*
Y2632627D01*
X-61551D01*
X-60751Y2632227D01*
X-60251Y2631694D01*
X-60051Y2630627D01*
X-60251Y2629560D01*
X-60851Y2628894D01*
X-61551Y2628494D01*
X-64051D01*
G01X-61551D02*
X-60051Y2624627D01*
G01X-54051D02*
X-54851Y2624760D01*
X-55551Y2625294D01*
X-56151Y2626094D01*
X-56551Y2627027D01*
X-56751Y2628094D01*
Y2629160D01*
X-56551Y2630227D01*
X-56151Y2631160D01*
X-55551Y2631960D01*
X-54851Y2632494D01*
X-54051Y2632627D01*
X-53251Y2632494D01*
X-52551Y2631960D01*
X-51951Y2631160D01*
X-51551Y2630227D01*
X-51351Y2629160D01*
Y2628094D01*
X-51551Y2627027D01*
X-51951Y2626094D01*
X-52551Y2625294D01*
X-53251Y2624760D01*
X-54051Y2624627D01*
G01X-48251Y2632627D02*
Y2626894D01*
X-47851Y2625693D01*
X-47051Y2624894D01*
X-46051Y2624627D01*
X-45051Y2624894D01*
X-44251Y2625693D01*
X-43851Y2626894D01*
Y2632627D01*
G01X-40051Y2624627D02*
Y2632627D01*
X-37651D01*
X-36851Y2632227D01*
X-36251Y2631294D01*
X-36051Y2630227D01*
X-36251Y2629160D01*
X-36751Y2628360D01*
X-37651Y2627960D01*
X-40051D01*
G01X-32151Y2625693D02*
X-31351Y2625027D01*
X-30451Y2624627D01*
X-29651D01*
X-28851Y2625027D01*
X-28251Y2625693D01*
X-27951Y2626627D01*
X-28151Y2627560D01*
X-28651Y2628360D01*
X-29551Y2628894D01*
X-30751Y2629160D01*
X-31451Y2629694D01*
X-31751Y2630627D01*
X-31551Y2631560D01*
X-31051Y2632227D01*
X-30351Y2632627D01*
X-29651D01*
X-28951Y2632360D01*
X-28351Y2631694D01*
G01X-16551Y2624627D02*
X-14051Y2632627D01*
X-11551Y2624627D01*
G01X-12451Y2627427D02*
X-15651D01*
G01X-551Y2624627D02*
X1949Y2632627D01*
X4449Y2624627D01*
G01X3549Y2627427D02*
X349D01*
G01X7649Y2624627D02*
Y2632627D01*
X12249Y2624627D01*
Y2632627D01*
G01X15749Y2624627D02*
Y2632627D01*
X17749D01*
X18549Y2632227D01*
X19149Y2631694D01*
X19649Y2630894D01*
X20049Y2629960D01*
X20149Y2628627D01*
X20049Y2627294D01*
X19649Y2626360D01*
X19149Y2625560D01*
X18549Y2625027D01*
X17749Y2624627D01*
X15749D01*
G01X34749Y2628894D02*
X35149Y2629294D01*
X35449Y2629960D01*
X35649Y2630894D01*
X35449Y2631694D01*
X35049Y2632227D01*
X34349Y2632627D01*
X31649D01*
Y2624627D01*
X34949D01*
X35649Y2625160D01*
X36049Y2625960D01*
X36249Y2626894D01*
X36049Y2627827D01*
X35449Y2628627D01*
X34749Y2628894D01*
X31649D01*
G01X41749Y2623160D02*
X42149Y2624894D01*
G01X49949Y2632627D02*
Y2624627D01*
G01X47649Y2632627D02*
X52249D01*
G01X55849Y2624627D02*
Y2632627D01*
G01X60049D02*
Y2624627D01*
G01Y2628627D02*
X55849D01*
G01X67949Y2624627D02*
X63949D01*
Y2632627D01*
X67949D01*
G01X66349Y2628760D02*
X63949D01*
G01X71649Y2624627D02*
Y2632627D01*
X76249Y2624627D01*
Y2632627D01*
G01X90549Y2628627D02*
X92549D01*
Y2626227D01*
X91949Y2625427D01*
X91249Y2624894D01*
X90249Y2624627D01*
X89249Y2624894D01*
X88549Y2625427D01*
X87949Y2626227D01*
X87549Y2627160D01*
X87349Y2628227D01*
Y2629160D01*
X87549Y2629960D01*
X87949Y2630894D01*
X88549Y2631694D01*
X89149Y2632227D01*
X89949Y2632627D01*
X90649D01*
X91449Y2632360D01*
X92049Y2631827D01*
G01X95949Y2624627D02*
Y2632627D01*
X98449D01*
X99249Y2632227D01*
X99749Y2631694D01*
X99949Y2630627D01*
X99749Y2629560D01*
X99149Y2628894D01*
X98449Y2628494D01*
X95949D01*
G01X98449D02*
X99949Y2624627D01*
G01X105949D02*
X105149Y2624760D01*
X104449Y2625294D01*
X103849Y2626094D01*
X103449Y2627027D01*
X103249Y2628094D01*
Y2629160D01*
X103449Y2630227D01*
X103849Y2631160D01*
X104449Y2631960D01*
X105149Y2632494D01*
X105949Y2632627D01*
X106749Y2632494D01*
X107449Y2631960D01*
X108049Y2631160D01*
X108449Y2630227D01*
X108649Y2629160D01*
Y2628094D01*
X108449Y2627027D01*
X108049Y2626094D01*
X107449Y2625294D01*
X106749Y2624760D01*
X105949Y2624627D01*
G01X111749Y2632627D02*
Y2626894D01*
X112149Y2625693D01*
X112949Y2624894D01*
X113949Y2624627D01*
X114949Y2624894D01*
X115749Y2625693D01*
X116149Y2626894D01*
Y2632627D01*
G01X119949Y2624627D02*
Y2632627D01*
X122349D01*
X123149Y2632227D01*
X123749Y2631294D01*
X123949Y2630227D01*
X123749Y2629160D01*
X123249Y2628360D01*
X122349Y2627960D01*
X119949D01*
G01X135449Y2624627D02*
X137949Y2632627D01*
X140449Y2624627D01*
G01X139549Y2627427D02*
X136349D01*
G01X156149Y2631960D02*
X155549Y2632360D01*
X154849Y2632627D01*
X154049D01*
X153149Y2632227D01*
X152449Y2631560D01*
X151949Y2630760D01*
X151549Y2629427D01*
X151449Y2628227D01*
X151649Y2627027D01*
X151949Y2626227D01*
X152549Y2625427D01*
X153249Y2624894D01*
X153949Y2624627D01*
X154649D01*
X155349Y2624894D01*
X155949Y2625294D01*
X156449Y2625827D01*
G01X159449Y2624627D02*
X161949Y2632627D01*
X164449Y2624627D01*
G01X163549Y2627427D02*
X160349D01*
G01X167649Y2624627D02*
Y2632627D01*
X172249Y2624627D01*
Y2632627D01*
G01X186749Y2628894D02*
X187149Y2629294D01*
X187449Y2629960D01*
X187649Y2630894D01*
X187449Y2631694D01*
X187049Y2632227D01*
X186349Y2632627D01*
X183649D01*
Y2624627D01*
X186949D01*
X187649Y2625160D01*
X188049Y2625960D01*
X188249Y2626894D01*
X188049Y2627827D01*
X187449Y2628627D01*
X186749Y2628894D01*
X183649D01*
G01X195949Y2624627D02*
X191949D01*
Y2632627D01*
X195949D01*
G01X194349Y2628760D02*
X191949D01*
G01X207949Y2624627D02*
Y2632627D01*
X210349D01*
X211149Y2632227D01*
X211749Y2631294D01*
X211949Y2630227D01*
X211749Y2629160D01*
X211249Y2628360D01*
X210349Y2627960D01*
X207949D01*
G01X215949Y2632627D02*
Y2624627D01*
X219949D01*
G01X223449D02*
X225949Y2632627D01*
X228449Y2624627D01*
G01X227549Y2627427D02*
X224349D01*
G01X236149Y2631960D02*
X235549Y2632360D01*
X234849Y2632627D01*
X234049D01*
X233149Y2632227D01*
X232449Y2631560D01*
X231949Y2630760D01*
X231549Y2629427D01*
X231449Y2628227D01*
X231649Y2627027D01*
X231949Y2626227D01*
X232549Y2625427D01*
X233249Y2624894D01*
X233949Y2624627D01*
X234649D01*
X235349Y2624894D01*
X235949Y2625294D01*
X236449Y2625827D01*
G01X243949Y2624627D02*
X239949D01*
Y2632627D01*
X243949D01*
G01X242349Y2628760D02*
X239949D01*
G01X247749Y2624627D02*
Y2632627D01*
X249749D01*
X250549Y2632227D01*
X251149Y2631694D01*
X251649Y2630894D01*
X252049Y2629960D01*
X252149Y2628627D01*
X252049Y2627294D01*
X251649Y2626360D01*
X251149Y2625560D01*
X250549Y2625027D01*
X249749Y2624627D01*
X247749D01*
G01X263849Y2625693D02*
X264649Y2625027D01*
X265549Y2624627D01*
X266349D01*
X267149Y2625027D01*
X267749Y2625693D01*
X268049Y2626627D01*
X267849Y2627560D01*
X267349Y2628360D01*
X266449Y2628894D01*
X265249Y2629160D01*
X264549Y2629694D01*
X264249Y2630627D01*
X264449Y2631560D01*
X264949Y2632227D01*
X265649Y2632627D01*
X266349D01*
X267049Y2632360D01*
X267649Y2631694D01*
G01X275949Y2624627D02*
X271949D01*
Y2632627D01*
X275949D01*
G01X274349Y2628760D02*
X271949D01*
G01X279949Y2624627D02*
Y2632627D01*
X282349D01*
X283149Y2632227D01*
X283749Y2631294D01*
X283949Y2630227D01*
X283749Y2629160D01*
X283249Y2628360D01*
X282349Y2627960D01*
X279949D01*
G01X287449Y2624627D02*
X289949Y2632627D01*
X292449Y2624627D01*
G01X291549Y2627427D02*
X288349D01*
G01X295949Y2624627D02*
Y2632627D01*
X298449D01*
X299249Y2632227D01*
X299749Y2631694D01*
X299949Y2630627D01*
X299749Y2629560D01*
X299149Y2628894D01*
X298449Y2628494D01*
X295949D01*
G01X298449D02*
X299949Y2624627D01*
G01X303449D02*
X305949Y2632627D01*
X308449Y2624627D01*
G01X307549Y2627427D02*
X304349D01*
G01X313949Y2632627D02*
Y2624627D01*
G01X311649Y2632627D02*
X316249D01*
G01X323949Y2624627D02*
X319949D01*
Y2632627D01*
X323949D01*
G01X322349Y2628760D02*
X319949D01*
G01X327949Y2632627D02*
Y2624627D01*
X331949D01*
G01X337949D02*
Y2628227D01*
X335949Y2632627D01*
G01X339949D02*
X337949Y2628227D01*
G01X352049Y2624627D02*
Y2632627D01*
X355849D01*
G01X354449Y2628760D02*
X352049D01*
G01X359949Y2624627D02*
Y2632627D01*
X362449D01*
X363249Y2632227D01*
X363749Y2631694D01*
X363949Y2630627D01*
X363749Y2629560D01*
X363149Y2628894D01*
X362449Y2628494D01*
X359949D01*
G01X362449D02*
X363949Y2624627D01*
G01X369949D02*
X369149Y2624760D01*
X368449Y2625294D01*
X367849Y2626094D01*
X367449Y2627027D01*
X367249Y2628094D01*
Y2629160D01*
X367449Y2630227D01*
X367849Y2631160D01*
X368449Y2631960D01*
X369149Y2632494D01*
X369949Y2632627D01*
X370749Y2632494D01*
X371449Y2631960D01*
X372049Y2631160D01*
X372449Y2630227D01*
X372649Y2629160D01*
Y2628094D01*
X372449Y2627027D01*
X372049Y2626094D01*
X371449Y2625294D01*
X370749Y2624760D01*
X369949Y2624627D01*
G01X375349D02*
Y2632627D01*
X377949Y2625960D01*
X380549Y2632627D01*
Y2624627D01*
G01X394549Y2628627D02*
X396549D01*
Y2626227D01*
X395949Y2625427D01*
X395249Y2624894D01*
X394249Y2624627D01*
X393249Y2624894D01*
X392549Y2625427D01*
X391949Y2626227D01*
X391549Y2627160D01*
X391349Y2628227D01*
Y2629160D01*
X391549Y2629960D01*
X391949Y2630894D01*
X392549Y2631694D01*
X393149Y2632227D01*
X393949Y2632627D01*
X394649D01*
X395449Y2632360D01*
X396049Y2631827D01*
G01X399949Y2624627D02*
Y2632627D01*
X402449D01*
X403249Y2632227D01*
X403749Y2631694D01*
X403949Y2630627D01*
X403749Y2629560D01*
X403149Y2628894D01*
X402449Y2628494D01*
X399949D01*
G01X402449D02*
X403949Y2624627D01*
G01X409949D02*
X409149Y2624760D01*
X408449Y2625294D01*
X407849Y2626094D01*
X407449Y2627027D01*
X407249Y2628094D01*
Y2629160D01*
X407449Y2630227D01*
X407849Y2631160D01*
X408449Y2631960D01*
X409149Y2632494D01*
X409949Y2632627D01*
X410749Y2632494D01*
X411449Y2631960D01*
X412049Y2631160D01*
X412449Y2630227D01*
X412649Y2629160D01*
Y2628094D01*
X412449Y2627027D01*
X412049Y2626094D01*
X411449Y2625294D01*
X410749Y2624760D01*
X409949Y2624627D01*
G01X415749Y2632627D02*
Y2626894D01*
X416149Y2625693D01*
X416949Y2624894D01*
X417949Y2624627D01*
X418949Y2624894D01*
X419749Y2625693D01*
X420149Y2626894D01*
Y2632627D01*
G01X423949Y2624627D02*
Y2632627D01*
X426349D01*
X427149Y2632227D01*
X427749Y2631294D01*
X427949Y2630227D01*
X427749Y2629160D01*
X427249Y2628360D01*
X426349Y2627960D01*
X423949D01*
G01X442749Y2628894D02*
X443149Y2629294D01*
X443449Y2629960D01*
X443649Y2630894D01*
X443449Y2631694D01*
X443049Y2632227D01*
X442349Y2632627D01*
X439649D01*
Y2624627D01*
X442949D01*
X443649Y2625160D01*
X444049Y2625960D01*
X444249Y2626894D01*
X444049Y2627827D01*
X443449Y2628627D01*
X442749Y2628894D01*
X439649D01*
G01X449949Y2624360D02*
X449749Y2624494D01*
Y2624760D01*
X449949Y2624894D01*
X450149Y2624760D01*
Y2624494D01*
X449949Y2624360D01*
G01X-70051Y2647627D02*
Y2639627D01*
G01X-72351Y2647627D02*
X-67751D01*
G01X-62051Y2639627D02*
X-62851Y2639760D01*
X-63551Y2640294D01*
X-64151Y2641094D01*
X-64551Y2642027D01*
X-64751Y2643094D01*
Y2644160D01*
X-64551Y2645227D01*
X-64151Y2646160D01*
X-63551Y2646960D01*
X-62851Y2647494D01*
X-62051Y2647627D01*
X-61251Y2647494D01*
X-60551Y2646960D01*
X-59951Y2646160D01*
X-59551Y2645227D01*
X-59351Y2644160D01*
Y2643094D01*
X-59551Y2642027D01*
X-59951Y2641094D01*
X-60551Y2640294D01*
X-61251Y2639760D01*
X-62051Y2639627D01*
G01X-46051Y2647627D02*
Y2639627D01*
G01X-48351Y2647627D02*
X-43751D01*
G01X-40151Y2639627D02*
Y2647627D01*
G01X-35951D02*
Y2639627D01*
G01Y2643627D02*
X-40151D01*
G01X-28051Y2639627D02*
X-32051D01*
Y2647627D01*
X-28051D01*
G01X-29651Y2643760D02*
X-32051D01*
G01X-13251Y2643894D02*
X-12851Y2644294D01*
X-12551Y2644960D01*
X-12351Y2645894D01*
X-12551Y2646694D01*
X-12951Y2647227D01*
X-13651Y2647627D01*
X-16351D01*
Y2639627D01*
X-13051D01*
X-12351Y2640160D01*
X-11951Y2640960D01*
X-11751Y2641894D01*
X-11951Y2642827D01*
X-12551Y2643627D01*
X-13251Y2643894D01*
X-16351D01*
G01X-6051Y2639627D02*
X-6851Y2639760D01*
X-7551Y2640294D01*
X-8151Y2641094D01*
X-8551Y2642027D01*
X-8751Y2643094D01*
Y2644160D01*
X-8551Y2645227D01*
X-8151Y2646160D01*
X-7551Y2646960D01*
X-6851Y2647494D01*
X-6051Y2647627D01*
X-5251Y2647494D01*
X-4551Y2646960D01*
X-3951Y2646160D01*
X-3551Y2645227D01*
X-3351Y2644160D01*
Y2643094D01*
X-3551Y2642027D01*
X-3951Y2641094D01*
X-4551Y2640294D01*
X-5251Y2639760D01*
X-6051Y2639627D01*
G01X-551D02*
X1949Y2647627D01*
X4449Y2639627D01*
G01X3549Y2642427D02*
X349D01*
G01X7949Y2639627D02*
Y2647627D01*
X10449D01*
X11249Y2647227D01*
X11749Y2646694D01*
X11949Y2645627D01*
X11749Y2644560D01*
X11149Y2643894D01*
X10449Y2643494D01*
X7949D01*
G01X10449D02*
X11949Y2639627D01*
G01X15749D02*
Y2647627D01*
X17749D01*
X18549Y2647227D01*
X19149Y2646694D01*
X19649Y2645894D01*
X20049Y2644960D01*
X20149Y2643627D01*
X20049Y2642294D01*
X19649Y2641360D01*
X19149Y2640560D01*
X18549Y2640027D01*
X17749Y2639627D01*
X15749D01*
G01X36149Y2646960D02*
X35549Y2647360D01*
X34849Y2647627D01*
X34049D01*
X33149Y2647227D01*
X32449Y2646560D01*
X31949Y2645760D01*
X31549Y2644427D01*
X31449Y2643227D01*
X31649Y2642027D01*
X31949Y2641227D01*
X32549Y2640427D01*
X33249Y2639894D01*
X33949Y2639627D01*
X34649D01*
X35349Y2639894D01*
X35949Y2640294D01*
X36449Y2640827D01*
G01X41949Y2639627D02*
X41149Y2639760D01*
X40449Y2640294D01*
X39849Y2641094D01*
X39449Y2642027D01*
X39249Y2643094D01*
Y2644160D01*
X39449Y2645227D01*
X39849Y2646160D01*
X40449Y2646960D01*
X41149Y2647494D01*
X41949Y2647627D01*
X42749Y2647494D01*
X43449Y2646960D01*
X44049Y2646160D01*
X44449Y2645227D01*
X44649Y2644160D01*
Y2643094D01*
X44449Y2642027D01*
X44049Y2641094D01*
X43449Y2640294D01*
X42749Y2639760D01*
X41949Y2639627D01*
G01X47749Y2647627D02*
Y2641894D01*
X48149Y2640693D01*
X48949Y2639894D01*
X49949Y2639627D01*
X50949Y2639894D01*
X51749Y2640693D01*
X52149Y2641894D01*
Y2647627D01*
G01X55949Y2639627D02*
Y2647627D01*
X58349D01*
X59149Y2647227D01*
X59749Y2646294D01*
X59949Y2645227D01*
X59749Y2644160D01*
X59249Y2643360D01*
X58349Y2642960D01*
X55949D01*
G01X65949Y2639627D02*
X65149Y2639760D01*
X64449Y2640294D01*
X63849Y2641094D01*
X63449Y2642027D01*
X63249Y2643094D01*
Y2644160D01*
X63449Y2645227D01*
X63849Y2646160D01*
X64449Y2646960D01*
X65149Y2647494D01*
X65949Y2647627D01*
X66749Y2647494D01*
X67449Y2646960D01*
X68049Y2646160D01*
X68449Y2645227D01*
X68649Y2644160D01*
Y2643094D01*
X68449Y2642027D01*
X68049Y2641094D01*
X67449Y2640294D01*
X66749Y2639760D01*
X65949Y2639627D01*
G01X71649D02*
Y2647627D01*
X76249Y2639627D01*
Y2647627D01*
G01X79849Y2640693D02*
X80649Y2640027D01*
X81549Y2639627D01*
X82349D01*
X83149Y2640027D01*
X83749Y2640693D01*
X84049Y2641627D01*
X83849Y2642560D01*
X83349Y2643360D01*
X82449Y2643894D01*
X81249Y2644160D01*
X80549Y2644694D01*
X80249Y2645627D01*
X80449Y2646560D01*
X80949Y2647227D01*
X81649Y2647627D01*
X82349D01*
X83049Y2647360D01*
X83649Y2646694D01*
G01X89949Y2639360D02*
X89749Y2639494D01*
Y2639760D01*
X89949Y2639894D01*
X90149Y2639760D01*
Y2639494D01*
X89949Y2639360D01*
G01X96749Y2647627D02*
X99149D01*
G01X97949D02*
Y2639627D01*
G01X96749D02*
X99149D01*
G01X104049D02*
Y2647627D01*
X107849D01*
G01X106449Y2643760D02*
X104049D01*
G01X120749Y2647627D02*
X123149D01*
G01X121949D02*
Y2639627D01*
G01X120749D02*
X123149D01*
G01X129949Y2647627D02*
Y2639627D01*
G01X127649Y2647627D02*
X132249D01*
G01X144749D02*
X147149D01*
G01X145949D02*
Y2639627D01*
G01X144749D02*
X147149D01*
G01X151849Y2640693D02*
X152649Y2640027D01*
X153549Y2639627D01*
X154349D01*
X155149Y2640027D01*
X155749Y2640693D01*
X156049Y2641627D01*
X155849Y2642560D01*
X155349Y2643360D01*
X154449Y2643894D01*
X153249Y2644160D01*
X152549Y2644694D01*
X152249Y2645627D01*
X152449Y2646560D01*
X152949Y2647227D01*
X153649Y2647627D01*
X154349D01*
X155049Y2647360D01*
X155649Y2646694D01*
G01X167649Y2639627D02*
Y2647627D01*
X172249Y2639627D01*
Y2647627D01*
G01X177949Y2639627D02*
X177149Y2639760D01*
X176449Y2640294D01*
X175849Y2641094D01*
X175449Y2642027D01*
X175249Y2643094D01*
Y2644160D01*
X175449Y2645227D01*
X175849Y2646160D01*
X176449Y2646960D01*
X177149Y2647494D01*
X177949Y2647627D01*
X178749Y2647494D01*
X179449Y2646960D01*
X180049Y2646160D01*
X180449Y2645227D01*
X180649Y2644160D01*
Y2643094D01*
X180449Y2642027D01*
X180049Y2641094D01*
X179449Y2640294D01*
X178749Y2639760D01*
X177949Y2639627D01*
G01X185949Y2647627D02*
Y2639627D01*
G01X183649Y2647627D02*
X188249D01*
G01X199949Y2639627D02*
Y2647627D01*
X202349D01*
X203149Y2647227D01*
X203749Y2646294D01*
X203949Y2645227D01*
X203749Y2644160D01*
X203249Y2643360D01*
X202349Y2642960D01*
X199949D01*
G01X209949Y2639627D02*
X209149Y2639760D01*
X208449Y2640294D01*
X207849Y2641094D01*
X207449Y2642027D01*
X207249Y2643094D01*
Y2644160D01*
X207449Y2645227D01*
X207849Y2646160D01*
X208449Y2646960D01*
X209149Y2647494D01*
X209949Y2647627D01*
X210749Y2647494D01*
X211449Y2646960D01*
X212049Y2646160D01*
X212449Y2645227D01*
X212649Y2644160D01*
Y2643094D01*
X212449Y2642027D01*
X212049Y2641094D01*
X211449Y2640294D01*
X210749Y2639760D01*
X209949Y2639627D01*
G01X215849Y2640693D02*
X216649Y2640027D01*
X217549Y2639627D01*
X218349D01*
X219149Y2640027D01*
X219749Y2640693D01*
X220049Y2641627D01*
X219849Y2642560D01*
X219349Y2643360D01*
X218449Y2643894D01*
X217249Y2644160D01*
X216549Y2644694D01*
X216249Y2645627D01*
X216449Y2646560D01*
X216949Y2647227D01*
X217649Y2647627D01*
X218349D01*
X219049Y2647360D01*
X219649Y2646694D01*
G01X223849Y2640693D02*
X224649Y2640027D01*
X225549Y2639627D01*
X226349D01*
X227149Y2640027D01*
X227749Y2640693D01*
X228049Y2641627D01*
X227849Y2642560D01*
X227349Y2643360D01*
X226449Y2643894D01*
X225249Y2644160D01*
X224549Y2644694D01*
X224249Y2645627D01*
X224449Y2646560D01*
X224949Y2647227D01*
X225649Y2647627D01*
X226349D01*
X227049Y2647360D01*
X227649Y2646694D01*
G01X232749Y2647627D02*
X235149D01*
G01X233949D02*
Y2639627D01*
G01X232749D02*
X235149D01*
G01X242749Y2643894D02*
X243149Y2644294D01*
X243449Y2644960D01*
X243649Y2645894D01*
X243449Y2646694D01*
X243049Y2647227D01*
X242349Y2647627D01*
X239649D01*
Y2639627D01*
X242949D01*
X243649Y2640160D01*
X244049Y2640960D01*
X244249Y2641894D01*
X244049Y2642827D01*
X243449Y2643627D01*
X242749Y2643894D01*
X239649D01*
G01X247949Y2647627D02*
Y2639627D01*
X251949D01*
G01X259949D02*
X255949D01*
Y2647627D01*
X259949D01*
G01X258349Y2643760D02*
X255949D01*
G01X273949Y2647627D02*
Y2639627D01*
G01X271649Y2647627D02*
X276249D01*
G01X281949Y2639627D02*
X281149Y2639760D01*
X280449Y2640294D01*
X279849Y2641094D01*
X279449Y2642027D01*
X279249Y2643094D01*
Y2644160D01*
X279449Y2645227D01*
X279849Y2646160D01*
X280449Y2646960D01*
X281149Y2647494D01*
X281949Y2647627D01*
X282749Y2647494D01*
X283449Y2646960D01*
X284049Y2646160D01*
X284449Y2645227D01*
X284649Y2644160D01*
Y2643094D01*
X284449Y2642027D01*
X284049Y2641094D01*
X283449Y2640294D01*
X282749Y2639760D01*
X281949Y2639627D01*
G01X296049D02*
Y2647627D01*
X299849D01*
G01X298449Y2643760D02*
X296049D01*
G01X303949Y2647627D02*
Y2639627D01*
X307949D01*
G01X311949Y2647627D02*
Y2639627D01*
X315949D01*
G01X321949D02*
X321149Y2639760D01*
X320449Y2640294D01*
X319849Y2641094D01*
X319449Y2642027D01*
X319249Y2643094D01*
Y2644160D01*
X319449Y2645227D01*
X319849Y2646160D01*
X320449Y2646960D01*
X321149Y2647494D01*
X321949Y2647627D01*
X322749Y2647494D01*
X323449Y2646960D01*
X324049Y2646160D01*
X324449Y2645227D01*
X324649Y2644160D01*
Y2643094D01*
X324449Y2642027D01*
X324049Y2641094D01*
X323449Y2640294D01*
X322749Y2639760D01*
X321949Y2639627D01*
G01X326949Y2647627D02*
X328349Y2639627D01*
X329949Y2647627D01*
X331549Y2639627D01*
X332949Y2647627D01*
G01X339949Y2639627D02*
X335949D01*
Y2647627D01*
X339949D01*
G01X338349Y2643760D02*
X335949D01*
G01X343949Y2639627D02*
Y2647627D01*
X346449D01*
X347249Y2647227D01*
X347749Y2646694D01*
X347949Y2645627D01*
X347749Y2644560D01*
X347149Y2643894D01*
X346449Y2643494D01*
X343949D01*
G01X346449D02*
X347949Y2639627D01*
G01X361949Y2647627D02*
Y2639627D01*
G01X359649Y2647627D02*
X364249D01*
G01X367849Y2639627D02*
Y2647627D01*
G01X372049D02*
Y2639627D01*
G01Y2643627D02*
X367849D01*
G01X379949Y2639627D02*
X375949D01*
Y2647627D01*
X379949D01*
G01X378349Y2643760D02*
X375949D01*
G01X391949Y2647627D02*
Y2639627D01*
X395949D01*
G01X401949D02*
X401149Y2639760D01*
X400449Y2640294D01*
X399849Y2641094D01*
X399449Y2642027D01*
X399249Y2643094D01*
Y2644160D01*
X399449Y2645227D01*
X399849Y2646160D01*
X400449Y2646960D01*
X401149Y2647494D01*
X401949Y2647627D01*
X402749Y2647494D01*
X403449Y2646960D01*
X404049Y2646160D01*
X404449Y2645227D01*
X404649Y2644160D01*
Y2643094D01*
X404449Y2642027D01*
X404049Y2641094D01*
X403449Y2640294D01*
X402749Y2639760D01*
X401949Y2639627D01*
G01X412149Y2646960D02*
X411549Y2647360D01*
X410849Y2647627D01*
X410049D01*
X409149Y2647227D01*
X408449Y2646560D01*
X407949Y2645760D01*
X407549Y2644427D01*
X407449Y2643227D01*
X407649Y2642027D01*
X407949Y2641227D01*
X408549Y2640427D01*
X409249Y2639894D01*
X409949Y2639627D01*
X410649D01*
X411349Y2639894D01*
X411949Y2640294D01*
X412449Y2640827D01*
G01X415449Y2639627D02*
X417949Y2647627D01*
X420449Y2639627D01*
G01X419549Y2642427D02*
X416349D01*
G01X425949Y2647627D02*
Y2639627D01*
G01X423649Y2647627D02*
X428249D01*
G01X432749D02*
X435149D01*
G01X433949D02*
Y2639627D01*
G01X432749D02*
X435149D01*
G01X441949D02*
X441149Y2639760D01*
X440449Y2640294D01*
X439849Y2641094D01*
X439449Y2642027D01*
X439249Y2643094D01*
Y2644160D01*
X439449Y2645227D01*
X439849Y2646160D01*
X440449Y2646960D01*
X441149Y2647494D01*
X441949Y2647627D01*
X442749Y2647494D01*
X443449Y2646960D01*
X444049Y2646160D01*
X444449Y2645227D01*
X444649Y2644160D01*
Y2643094D01*
X444449Y2642027D01*
X444049Y2641094D01*
X443449Y2640294D01*
X442749Y2639760D01*
X441949Y2639627D01*
G01X447649D02*
Y2647627D01*
X452249Y2639627D01*
Y2647627D01*
G01X455849Y2640693D02*
X456649Y2640027D01*
X457549Y2639627D01*
X458349D01*
X459149Y2640027D01*
X459749Y2640693D01*
X460049Y2641627D01*
X459849Y2642560D01*
X459349Y2643360D01*
X458449Y2643894D01*
X457249Y2644160D01*
X456549Y2644694D01*
X456249Y2645627D01*
X456449Y2646560D01*
X456949Y2647227D01*
X457649Y2647627D01*
X458349D01*
X459049Y2647360D01*
X459649Y2646694D01*
G01X472049Y2639627D02*
Y2647627D01*
X475849D01*
G01X474449Y2643760D02*
X472049D01*
G01X481949Y2639627D02*
X481149Y2639760D01*
X480449Y2640294D01*
X479849Y2641094D01*
X479449Y2642027D01*
X479249Y2643094D01*
Y2644160D01*
X479449Y2645227D01*
X479849Y2646160D01*
X480449Y2646960D01*
X481149Y2647494D01*
X481949Y2647627D01*
X482749Y2647494D01*
X483449Y2646960D01*
X484049Y2646160D01*
X484449Y2645227D01*
X484649Y2644160D01*
Y2643094D01*
X484449Y2642027D01*
X484049Y2641094D01*
X483449Y2640294D01*
X482749Y2639760D01*
X481949Y2639627D01*
G01X487949D02*
Y2647627D01*
X490449D01*
X491249Y2647227D01*
X491749Y2646694D01*
X491949Y2645627D01*
X491749Y2644560D01*
X491149Y2643894D01*
X490449Y2643494D01*
X487949D01*
G01X490449D02*
X491949Y2639627D01*
G01X506749Y2643894D02*
X507149Y2644294D01*
X507449Y2644960D01*
X507649Y2645894D01*
X507449Y2646694D01*
X507049Y2647227D01*
X506349Y2647627D01*
X503649D01*
Y2639627D01*
X506949D01*
X507649Y2640160D01*
X508049Y2640960D01*
X508249Y2641894D01*
X508049Y2642827D01*
X507449Y2643627D01*
X506749Y2643894D01*
X503649D01*
G01X513949Y2639627D02*
X513149Y2639760D01*
X512449Y2640294D01*
X511849Y2641094D01*
X511449Y2642027D01*
X511249Y2643094D01*
Y2644160D01*
X511449Y2645227D01*
X511849Y2646160D01*
X512449Y2646960D01*
X513149Y2647494D01*
X513949Y2647627D01*
X514749Y2647494D01*
X515449Y2646960D01*
X516049Y2646160D01*
X516449Y2645227D01*
X516649Y2644160D01*
Y2643094D01*
X516449Y2642027D01*
X516049Y2641094D01*
X515449Y2640294D01*
X514749Y2639760D01*
X513949Y2639627D01*
G01X521949Y2647627D02*
Y2639627D01*
G01X519649Y2647627D02*
X524249D01*
G01X527849Y2639627D02*
Y2647627D01*
G01X532049D02*
Y2639627D01*
G01Y2643627D02*
X527849D01*
G01X-72051Y2654627D02*
Y2662627D01*
X-69651D01*
X-68851Y2662227D01*
X-68251Y2661294D01*
X-68051Y2660227D01*
X-68251Y2659160D01*
X-68751Y2658360D01*
X-69651Y2657960D01*
X-72051D01*
G01X-64051Y2662627D02*
Y2654627D01*
X-60051D01*
G01X-52051D02*
X-56051D01*
Y2662627D01*
X-52051D01*
G01X-53651Y2658760D02*
X-56051D01*
G01X-48551Y2654627D02*
X-46051Y2662627D01*
X-43551Y2654627D01*
G01X-44451Y2657427D02*
X-47651D01*
G01X-40151Y2655693D02*
X-39351Y2655027D01*
X-38451Y2654627D01*
X-37651D01*
X-36851Y2655027D01*
X-36251Y2655693D01*
X-35951Y2656627D01*
X-36151Y2657560D01*
X-36651Y2658360D01*
X-37551Y2658894D01*
X-38751Y2659160D01*
X-39451Y2659694D01*
X-39751Y2660627D01*
X-39551Y2661560D01*
X-39051Y2662227D01*
X-38351Y2662627D01*
X-37651D01*
X-36951Y2662360D01*
X-36351Y2661694D01*
G01X-28051Y2654627D02*
X-32051D01*
Y2662627D01*
X-28051D01*
G01X-29651Y2658760D02*
X-32051D01*
G01X-15951Y2654627D02*
Y2662627D01*
X-12151D01*
G01X-13551Y2658760D02*
X-15951D01*
G01X-6051Y2654627D02*
X-6851Y2654760D01*
X-7551Y2655294D01*
X-8151Y2656094D01*
X-8551Y2657027D01*
X-8751Y2658094D01*
Y2659160D01*
X-8551Y2660227D01*
X-8151Y2661160D01*
X-7551Y2661960D01*
X-6851Y2662494D01*
X-6051Y2662627D01*
X-5251Y2662494D01*
X-4551Y2661960D01*
X-3951Y2661160D01*
X-3551Y2660227D01*
X-3351Y2659160D01*
Y2658094D01*
X-3551Y2657027D01*
X-3951Y2656094D01*
X-4551Y2655294D01*
X-5251Y2654760D01*
X-6051Y2654627D01*
G01X-51Y2662627D02*
Y2654627D01*
X3949D01*
G01X7949Y2662627D02*
Y2654627D01*
X11949D01*
G01X17949D02*
X17149Y2654760D01*
X16449Y2655294D01*
X15849Y2656094D01*
X15449Y2657027D01*
X15249Y2658094D01*
Y2659160D01*
X15449Y2660227D01*
X15849Y2661160D01*
X16449Y2661960D01*
X17149Y2662494D01*
X17949Y2662627D01*
X18749Y2662494D01*
X19449Y2661960D01*
X20049Y2661160D01*
X20449Y2660227D01*
X20649Y2659160D01*
Y2658094D01*
X20449Y2657027D01*
X20049Y2656094D01*
X19449Y2655294D01*
X18749Y2654760D01*
X17949Y2654627D01*
G01X22949Y2662627D02*
X24349Y2654627D01*
X25949Y2662627D01*
X27549Y2654627D01*
X28949Y2662627D01*
G01X41949D02*
Y2654627D01*
G01X39649Y2662627D02*
X44249D01*
G01X47849Y2654627D02*
Y2662627D01*
G01X52049D02*
Y2654627D01*
G01Y2658627D02*
X47849D01*
G01X59949Y2654627D02*
X55949D01*
Y2662627D01*
X59949D01*
G01X58349Y2658760D02*
X55949D01*
G01X71849Y2655693D02*
X72649Y2655027D01*
X73549Y2654627D01*
X74349D01*
X75149Y2655027D01*
X75749Y2655693D01*
X76049Y2656627D01*
X75849Y2657560D01*
X75349Y2658360D01*
X74449Y2658894D01*
X73249Y2659160D01*
X72549Y2659694D01*
X72249Y2660627D01*
X72449Y2661560D01*
X72949Y2662227D01*
X73649Y2662627D01*
X74349D01*
X75049Y2662360D01*
X75649Y2661694D01*
G01X79949Y2662627D02*
Y2654627D01*
X83949D01*
G01X88749Y2662627D02*
X91149D01*
G01X89949D02*
Y2654627D01*
G01X88749D02*
X91149D01*
G01X95749D02*
Y2662627D01*
X97749D01*
X98549Y2662227D01*
X99149Y2661694D01*
X99649Y2660894D01*
X100049Y2659960D01*
X100149Y2658627D01*
X100049Y2657294D01*
X99649Y2656360D01*
X99149Y2655560D01*
X98549Y2655027D01*
X97749Y2654627D01*
X95749D01*
G01X107949D02*
X103949D01*
Y2662627D01*
X107949D01*
G01X106349Y2658760D02*
X103949D01*
G01X111849Y2655693D02*
X112649Y2655027D01*
X113549Y2654627D01*
X114349D01*
X115149Y2655027D01*
X115749Y2655693D01*
X116049Y2656627D01*
X115849Y2657560D01*
X115349Y2658360D01*
X114449Y2658894D01*
X113249Y2659160D01*
X112549Y2659694D01*
X112249Y2660627D01*
X112449Y2661560D01*
X112949Y2662227D01*
X113649Y2662627D01*
X114349D01*
X115049Y2662360D01*
X115649Y2661694D01*
G01X129949Y2662627D02*
Y2654627D01*
G01X127649Y2662627D02*
X132249D01*
G01X137949Y2654627D02*
X137149Y2654760D01*
X136449Y2655294D01*
X135849Y2656094D01*
X135449Y2657027D01*
X135249Y2658094D01*
Y2659160D01*
X135449Y2660227D01*
X135849Y2661160D01*
X136449Y2661960D01*
X137149Y2662494D01*
X137949Y2662627D01*
X138749Y2662494D01*
X139449Y2661960D01*
X140049Y2661160D01*
X140449Y2660227D01*
X140649Y2659160D01*
Y2658094D01*
X140449Y2657027D01*
X140049Y2656094D01*
X139449Y2655294D01*
X138749Y2654760D01*
X137949Y2654627D01*
G01X154549Y2658627D02*
X156549D01*
Y2656227D01*
X155949Y2655427D01*
X155249Y2654894D01*
X154249Y2654627D01*
X153249Y2654894D01*
X152549Y2655427D01*
X151949Y2656227D01*
X151549Y2657160D01*
X151349Y2658227D01*
Y2659160D01*
X151549Y2659960D01*
X151949Y2660894D01*
X152549Y2661694D01*
X153149Y2662227D01*
X153949Y2662627D01*
X154649D01*
X155449Y2662360D01*
X156049Y2661827D01*
G01X163949Y2654627D02*
X159949D01*
Y2662627D01*
X163949D01*
G01X162349Y2658760D02*
X159949D01*
G01X167649Y2654627D02*
Y2662627D01*
X172249Y2654627D01*
Y2662627D01*
G01X179949Y2654627D02*
X175949D01*
Y2662627D01*
X179949D01*
G01X178349Y2658760D02*
X175949D01*
G01X183949Y2654627D02*
Y2662627D01*
X186449D01*
X187249Y2662227D01*
X187749Y2661694D01*
X187949Y2660627D01*
X187749Y2659560D01*
X187149Y2658894D01*
X186449Y2658494D01*
X183949D01*
G01X186449D02*
X187949Y2654627D01*
G01X191449D02*
X193949Y2662627D01*
X196449Y2654627D01*
G01X195549Y2657427D02*
X192349D01*
G01X201949Y2662627D02*
Y2654627D01*
G01X199649Y2662627D02*
X204249D01*
G01X211949Y2654627D02*
X207949D01*
Y2662627D01*
X211949D01*
G01X210349Y2658760D02*
X207949D01*
G01X225949Y2662627D02*
Y2654627D01*
G01X223649Y2662627D02*
X228249D01*
G01X231849Y2654627D02*
Y2662627D01*
G01X236049D02*
Y2654627D01*
G01Y2658627D02*
X231849D01*
G01X243949Y2654627D02*
X239949D01*
Y2662627D01*
X243949D01*
G01X242349Y2658760D02*
X239949D01*
G01X255949Y2654627D02*
Y2662627D01*
X258349D01*
X259149Y2662227D01*
X259749Y2661294D01*
X259949Y2660227D01*
X259749Y2659160D01*
X259249Y2658360D01*
X258349Y2657960D01*
X255949D01*
G01X263449Y2654627D02*
X265949Y2662627D01*
X268449Y2654627D01*
G01X267549Y2657427D02*
X264349D01*
G01X271749Y2654627D02*
Y2662627D01*
X273749D01*
X274549Y2662227D01*
X275149Y2661694D01*
X275649Y2660894D01*
X276049Y2659960D01*
X276149Y2658627D01*
X276049Y2657294D01*
X275649Y2656360D01*
X275149Y2655560D01*
X274549Y2655027D01*
X273749Y2654627D01*
X271749D01*
G01X279849Y2655693D02*
X280649Y2655027D01*
X281549Y2654627D01*
X282349D01*
X283149Y2655027D01*
X283749Y2655693D01*
X284049Y2656627D01*
X283849Y2657560D01*
X283349Y2658360D01*
X282449Y2658894D01*
X281249Y2659160D01*
X280549Y2659694D01*
X280249Y2660627D01*
X280449Y2661560D01*
X280949Y2662227D01*
X281649Y2662627D01*
X282349D01*
X283049Y2662360D01*
X283649Y2661694D01*
G01X295449Y2654627D02*
X297949Y2662627D01*
X300449Y2654627D01*
G01X299549Y2657427D02*
X296349D01*
G01X303649Y2654627D02*
Y2662627D01*
X308249Y2654627D01*
Y2662627D01*
G01X311749Y2654627D02*
Y2662627D01*
X313749D01*
X314549Y2662227D01*
X315149Y2661694D01*
X315649Y2660894D01*
X316049Y2659960D01*
X316149Y2658627D01*
X316049Y2657294D01*
X315649Y2656360D01*
X315149Y2655560D01*
X314549Y2655027D01*
X313749Y2654627D01*
X311749D01*
G01X327349D02*
Y2662627D01*
X329949Y2655960D01*
X332549Y2662627D01*
Y2654627D01*
G01X335449D02*
X337949Y2662627D01*
X340449Y2654627D01*
G01X339549Y2657427D02*
X336349D01*
G01X343849Y2655693D02*
X344649Y2655027D01*
X345549Y2654627D01*
X346349D01*
X347149Y2655027D01*
X347749Y2655693D01*
X348049Y2656627D01*
X347849Y2657560D01*
X347349Y2658360D01*
X346449Y2658894D01*
X345249Y2659160D01*
X344549Y2659694D01*
X344249Y2660627D01*
X344449Y2661560D01*
X344949Y2662227D01*
X345649Y2662627D01*
X346349D01*
X347049Y2662360D01*
X347649Y2661694D01*
G01X351749Y2654627D02*
Y2662627D01*
G01X355549D02*
X351749Y2657693D01*
G01X356149Y2654627D02*
X353449Y2659960D01*
G01X367449Y2654627D02*
X369949Y2662627D01*
X372449Y2654627D01*
G01X371549Y2657427D02*
X368349D01*
G01X375649Y2654627D02*
Y2662627D01*
X380249Y2654627D01*
Y2662627D01*
G01X383749Y2654627D02*
Y2662627D01*
X385749D01*
X386549Y2662227D01*
X387149Y2661694D01*
X387649Y2660894D01*
X388049Y2659960D01*
X388149Y2658627D01*
X388049Y2657294D01*
X387649Y2656360D01*
X387149Y2655560D01*
X386549Y2655027D01*
X385749Y2654627D01*
X383749D01*
G01X399449D02*
X401949Y2662627D01*
X404449Y2654627D01*
G01X403549Y2657427D02*
X400349D01*
G01X407749Y2654627D02*
Y2662627D01*
X409749D01*
X410549Y2662227D01*
X411149Y2661694D01*
X411649Y2660894D01*
X412049Y2659960D01*
X412149Y2658627D01*
X412049Y2657294D01*
X411649Y2656360D01*
X411149Y2655560D01*
X410549Y2655027D01*
X409749Y2654627D01*
X407749D01*
G01X415749D02*
Y2662627D01*
X417749D01*
X418549Y2662227D01*
X419149Y2661694D01*
X419649Y2660894D01*
X420049Y2659960D01*
X420149Y2658627D01*
X420049Y2657294D01*
X419649Y2656360D01*
X419149Y2655560D01*
X418549Y2655027D01*
X417749Y2654627D01*
X415749D01*
G01X433949Y2662627D02*
Y2654627D01*
G01X431649Y2662627D02*
X436249D01*
G01X439849Y2654627D02*
Y2662627D01*
G01X444049D02*
Y2654627D01*
G01Y2658627D02*
X439849D01*
G01X451949Y2654627D02*
X447949D01*
Y2662627D01*
X451949D01*
G01X450349Y2658760D02*
X447949D01*
G01X465949Y2662627D02*
Y2654627D01*
G01X463649Y2662627D02*
X468249D01*
G01X475949Y2654627D02*
X471949D01*
Y2662627D01*
X475949D01*
G01X474349Y2658760D02*
X471949D01*
G01X479849Y2655693D02*
X480649Y2655027D01*
X481549Y2654627D01*
X482349D01*
X483149Y2655027D01*
X483749Y2655693D01*
X484049Y2656627D01*
X483849Y2657560D01*
X483349Y2658360D01*
X482449Y2658894D01*
X481249Y2659160D01*
X480549Y2659694D01*
X480249Y2660627D01*
X480449Y2661560D01*
X480949Y2662227D01*
X481649Y2662627D01*
X482349D01*
X483049Y2662360D01*
X483649Y2661694D01*
G01X489949Y2662627D02*
Y2654627D01*
G01X487649Y2662627D02*
X492249D01*
G01X503949Y2654627D02*
Y2662627D01*
X506349D01*
X507149Y2662227D01*
X507749Y2661294D01*
X507949Y2660227D01*
X507749Y2659160D01*
X507249Y2658360D01*
X506349Y2657960D01*
X503949D01*
G01X511449Y2654627D02*
X513949Y2662627D01*
X516449Y2654627D01*
G01X515549Y2657427D02*
X512349D01*
G01X519749Y2654627D02*
Y2662627D01*
X521749D01*
X522549Y2662227D01*
X523149Y2661694D01*
X523649Y2660894D01*
X524049Y2659960D01*
X524149Y2658627D01*
X524049Y2657294D01*
X523649Y2656360D01*
X523149Y2655560D01*
X522549Y2655027D01*
X521749Y2654627D01*
X519749D01*
G01X527849Y2655693D02*
X528649Y2655027D01*
X529549Y2654627D01*
X530349D01*
X531149Y2655027D01*
X531749Y2655693D01*
X532049Y2656627D01*
X531849Y2657560D01*
X531349Y2658360D01*
X530449Y2658894D01*
X529249Y2659160D01*
X528549Y2659694D01*
X528249Y2660627D01*
X528449Y2661560D01*
X528949Y2662227D01*
X529649Y2662627D01*
X530349D01*
X531049Y2662360D01*
X531649Y2661694D01*
G01X-87251Y2670827D02*
X-86651Y2670160D01*
X-85951Y2669760D01*
X-85051Y2669627D01*
X-84151Y2669894D01*
X-83451Y2670427D01*
X-82951Y2671360D01*
X-82851Y2672427D01*
X-83051Y2673494D01*
X-83551Y2674160D01*
X-84251Y2674694D01*
X-84951Y2674827D01*
X-85651Y2674694D01*
X-86551Y2674160D01*
X-86251Y2677627D01*
X-83551D01*
G01X-77051Y2669360D02*
X-77251Y2669494D01*
Y2669760D01*
X-77051Y2669894D01*
X-76851Y2669760D01*
Y2669494D01*
X-77051Y2669360D01*
G01X-71051Y2669627D02*
Y2677627D01*
X-68651D01*
X-67851Y2677227D01*
X-67251Y2676294D01*
X-67051Y2675227D01*
X-67251Y2674160D01*
X-67751Y2673360D01*
X-68651Y2672960D01*
X-71051D01*
G01X-59051Y2669627D02*
X-63051D01*
Y2677627D01*
X-59051D01*
G01X-60651Y2673760D02*
X-63051D01*
G01X-51051Y2669627D02*
X-55051D01*
Y2677627D01*
X-51051D01*
G01X-52651Y2673760D02*
X-55051D01*
G01X-47051Y2677627D02*
Y2669627D01*
X-43051D01*
G01X-38251Y2677627D02*
X-35851D01*
G01X-37051D02*
Y2669627D01*
G01X-38251D02*
X-35851D01*
G01X-31351D02*
Y2677627D01*
X-26751Y2669627D01*
Y2677627D01*
G01X-20451Y2673627D02*
X-18451D01*
Y2671227D01*
X-19051Y2670427D01*
X-19751Y2669894D01*
X-20751Y2669627D01*
X-21751Y2669894D01*
X-22451Y2670427D01*
X-23051Y2671227D01*
X-23451Y2672160D01*
X-23651Y2673227D01*
Y2674160D01*
X-23451Y2674960D01*
X-23051Y2675894D01*
X-22451Y2676694D01*
X-21851Y2677227D01*
X-21051Y2677627D01*
X-20351D01*
X-19551Y2677360D01*
X-18951Y2676827D01*
G01X-7151Y2670693D02*
X-6351Y2670027D01*
X-5451Y2669627D01*
X-4651D01*
X-3851Y2670027D01*
X-3251Y2670693D01*
X-2951Y2671627D01*
X-3151Y2672560D01*
X-3651Y2673360D01*
X-4551Y2673894D01*
X-5751Y2674160D01*
X-6451Y2674694D01*
X-6751Y2675627D01*
X-6551Y2676560D01*
X-6051Y2677227D01*
X-5351Y2677627D01*
X-4651D01*
X-3951Y2677360D01*
X-3351Y2676694D01*
G01X2949Y2677627D02*
Y2669627D01*
G01X649Y2677627D02*
X5249D01*
G01X8949Y2669627D02*
Y2677627D01*
X11449D01*
X12249Y2677227D01*
X12749Y2676694D01*
X12949Y2675627D01*
X12749Y2674560D01*
X12149Y2673894D01*
X11449Y2673494D01*
X8949D01*
G01X11449D02*
X12949Y2669627D01*
G01X20949D02*
X16949D01*
Y2677627D01*
X20949D01*
G01X19349Y2673760D02*
X16949D01*
G01X24649Y2669627D02*
Y2677627D01*
X29249Y2669627D01*
Y2677627D01*
G01X35549Y2673627D02*
X37549D01*
Y2671227D01*
X36949Y2670427D01*
X36249Y2669894D01*
X35249Y2669627D01*
X34249Y2669894D01*
X33549Y2670427D01*
X32949Y2671227D01*
X32549Y2672160D01*
X32349Y2673227D01*
Y2674160D01*
X32549Y2674960D01*
X32949Y2675894D01*
X33549Y2676694D01*
X34149Y2677227D01*
X34949Y2677627D01*
X35649D01*
X36449Y2677360D01*
X37049Y2676827D01*
G01X42949Y2677627D02*
Y2669627D01*
G01X40649Y2677627D02*
X45249D01*
G01X48849Y2669627D02*
Y2677627D01*
G01X53049D02*
Y2669627D01*
G01Y2673627D02*
X48849D01*
G01X64449Y2669627D02*
X66949Y2677627D01*
X69449Y2669627D01*
G01X68549Y2672427D02*
X65349D01*
G01X72649Y2669627D02*
Y2677627D01*
X77249Y2669627D01*
Y2677627D01*
G01X80749Y2669627D02*
Y2677627D01*
X82749D01*
X83549Y2677227D01*
X84149Y2676694D01*
X84649Y2675894D01*
X85049Y2674960D01*
X85149Y2673627D01*
X85049Y2672294D01*
X84649Y2671360D01*
X84149Y2670560D01*
X83549Y2670027D01*
X82749Y2669627D01*
X80749D01*
G01X99749Y2673894D02*
X100149Y2674294D01*
X100449Y2674960D01*
X100649Y2675894D01*
X100449Y2676694D01*
X100049Y2677227D01*
X99349Y2677627D01*
X96649D01*
Y2669627D01*
X99949D01*
X100649Y2670160D01*
X101049Y2670960D01*
X101249Y2671894D01*
X101049Y2672827D01*
X100449Y2673627D01*
X99749Y2673894D01*
X96649D01*
G01X107549Y2673627D02*
X109549D01*
Y2671227D01*
X108949Y2670427D01*
X108249Y2669894D01*
X107249Y2669627D01*
X106249Y2669894D01*
X105549Y2670427D01*
X104949Y2671227D01*
X104549Y2672160D01*
X104349Y2673227D01*
Y2674160D01*
X104549Y2674960D01*
X104949Y2675894D01*
X105549Y2676694D01*
X106149Y2677227D01*
X106949Y2677627D01*
X107649D01*
X108449Y2677360D01*
X109049Y2676827D01*
G01X112449Y2669627D02*
X114949Y2677627D01*
X117449Y2669627D01*
G01X116549Y2672427D02*
X113349D01*
G01X128949Y2669627D02*
Y2677627D01*
X131349D01*
X132149Y2677227D01*
X132749Y2676294D01*
X132949Y2675227D01*
X132749Y2674160D01*
X132249Y2673360D01*
X131349Y2672960D01*
X128949D01*
G01X136449Y2669627D02*
X138949Y2677627D01*
X141449Y2669627D01*
G01X140549Y2672427D02*
X137349D01*
G01X144749Y2669627D02*
Y2677627D01*
X146749D01*
X147549Y2677227D01*
X148149Y2676694D01*
X148649Y2675894D01*
X149049Y2674960D01*
X149149Y2673627D01*
X149049Y2672294D01*
X148649Y2671360D01*
X148149Y2670560D01*
X147549Y2670027D01*
X146749Y2669627D01*
X144749D01*
G01X152849Y2670693D02*
X153649Y2670027D01*
X154549Y2669627D01*
X155349D01*
X156149Y2670027D01*
X156749Y2670693D01*
X157049Y2671627D01*
X156849Y2672560D01*
X156349Y2673360D01*
X155449Y2673894D01*
X154249Y2674160D01*
X153549Y2674694D01*
X153249Y2675627D01*
X153449Y2676560D01*
X153949Y2677227D01*
X154649Y2677627D01*
X155349D01*
X156049Y2677360D01*
X156649Y2676694D01*
G01X168449Y2669627D02*
X170949Y2677627D01*
X173449Y2669627D01*
G01X172549Y2672427D02*
X169349D01*
G01X176749Y2669627D02*
Y2677627D01*
X178749D01*
X179549Y2677227D01*
X180149Y2676694D01*
X180649Y2675894D01*
X181049Y2674960D01*
X181149Y2673627D01*
X181049Y2672294D01*
X180649Y2671360D01*
X180149Y2670560D01*
X179549Y2670027D01*
X178749Y2669627D01*
X176749D01*
G01X184849D02*
Y2677627D01*
G01X189049D02*
Y2669627D01*
G01Y2673627D02*
X184849D01*
G01X196949Y2669627D02*
X192949D01*
Y2677627D01*
X196949D01*
G01X195349Y2673760D02*
X192949D01*
G01X200849Y2670693D02*
X201649Y2670027D01*
X202549Y2669627D01*
X203349D01*
X204149Y2670027D01*
X204749Y2670693D01*
X205049Y2671627D01*
X204849Y2672560D01*
X204349Y2673360D01*
X203449Y2673894D01*
X202249Y2674160D01*
X201549Y2674694D01*
X201249Y2675627D01*
X201449Y2676560D01*
X201949Y2677227D01*
X202649Y2677627D01*
X203349D01*
X204049Y2677360D01*
X204649Y2676694D01*
G01X209749Y2677627D02*
X212149D01*
G01X210949D02*
Y2669627D01*
G01X209749D02*
X212149D01*
G01X218949D02*
X218149Y2669760D01*
X217449Y2670294D01*
X216849Y2671094D01*
X216449Y2672027D01*
X216249Y2673094D01*
Y2674160D01*
X216449Y2675227D01*
X216849Y2676160D01*
X217449Y2676960D01*
X218149Y2677494D01*
X218949Y2677627D01*
X219749Y2677494D01*
X220449Y2676960D01*
X221049Y2676160D01*
X221449Y2675227D01*
X221649Y2674160D01*
Y2673094D01*
X221449Y2672027D01*
X221049Y2671094D01*
X220449Y2670294D01*
X219749Y2669760D01*
X218949Y2669627D01*
G01X224649D02*
Y2677627D01*
X229249Y2669627D01*
Y2677627D01*
G01X242949D02*
Y2669627D01*
G01X240649Y2677627D02*
X245249D01*
G01X252949Y2669627D02*
X248949D01*
Y2677627D01*
X252949D01*
G01X251349Y2673760D02*
X248949D01*
G01X256849Y2670693D02*
X257649Y2670027D01*
X258549Y2669627D01*
X259349D01*
X260149Y2670027D01*
X260749Y2670693D01*
X261049Y2671627D01*
X260849Y2672560D01*
X260349Y2673360D01*
X259449Y2673894D01*
X258249Y2674160D01*
X257549Y2674694D01*
X257249Y2675627D01*
X257449Y2676560D01*
X257949Y2677227D01*
X258649Y2677627D01*
X259349D01*
X260049Y2677360D01*
X260649Y2676694D01*
G01X266949Y2677627D02*
Y2669627D01*
G01X264649Y2677627D02*
X269249D01*
G01X280949Y2669627D02*
Y2677627D01*
X283349D01*
X284149Y2677227D01*
X284749Y2676294D01*
X284949Y2675227D01*
X284749Y2674160D01*
X284249Y2673360D01*
X283349Y2672960D01*
X280949D01*
G01X288449Y2669627D02*
X290949Y2677627D01*
X293449Y2669627D01*
G01X292549Y2672427D02*
X289349D01*
G01X298949Y2677627D02*
Y2669627D01*
G01X296649Y2677627D02*
X301249D01*
G01X306949D02*
Y2669627D01*
G01X304649Y2677627D02*
X309249D01*
G01X316949Y2669627D02*
X312949D01*
Y2677627D01*
X316949D01*
G01X315349Y2673760D02*
X312949D01*
G01X320949Y2669627D02*
Y2677627D01*
X323449D01*
X324249Y2677227D01*
X324749Y2676694D01*
X324949Y2675627D01*
X324749Y2674560D01*
X324149Y2673894D01*
X323449Y2673494D01*
X320949D01*
G01X323449D02*
X324949Y2669627D01*
G01X328649D02*
Y2677627D01*
X333249Y2669627D01*
Y2677627D01*
G01X336849Y2670693D02*
X337649Y2670027D01*
X338549Y2669627D01*
X339349D01*
X340149Y2670027D01*
X340749Y2670693D01*
X341049Y2671627D01*
X340849Y2672560D01*
X340349Y2673360D01*
X339449Y2673894D01*
X338249Y2674160D01*
X337549Y2674694D01*
X337249Y2675627D01*
X337449Y2676560D01*
X337949Y2677227D01*
X338649Y2677627D01*
X339349D01*
X340049Y2677360D01*
X340649Y2676694D01*
G01X346949Y2669360D02*
X346749Y2669494D01*
Y2669760D01*
X346949Y2669894D01*
X347149Y2669760D01*
Y2669494D01*
X346949Y2669360D01*
G01X-83851Y2759627D02*
Y2767627D01*
X-87551Y2761894D01*
X-82551D01*
G01X-77051Y2759360D02*
X-77251Y2759494D01*
Y2759760D01*
X-77051Y2759894D01*
X-76851Y2759760D01*
Y2759494D01*
X-77051Y2759360D01*
G01X-66851Y2766960D02*
X-67451Y2767360D01*
X-68151Y2767627D01*
X-68951D01*
X-69851Y2767227D01*
X-70551Y2766560D01*
X-71051Y2765760D01*
X-71451Y2764427D01*
X-71551Y2763227D01*
X-71351Y2762027D01*
X-71051Y2761227D01*
X-70451Y2760427D01*
X-69751Y2759894D01*
X-69051Y2759627D01*
X-68351D01*
X-67651Y2759894D01*
X-67051Y2760294D01*
X-66551Y2760827D01*
G01X-61051Y2759627D02*
X-61851Y2759760D01*
X-62551Y2760294D01*
X-63151Y2761094D01*
X-63551Y2762027D01*
X-63751Y2763094D01*
Y2764160D01*
X-63551Y2765227D01*
X-63151Y2766160D01*
X-62551Y2766960D01*
X-61851Y2767494D01*
X-61051Y2767627D01*
X-60251Y2767494D01*
X-59551Y2766960D01*
X-58951Y2766160D01*
X-58551Y2765227D01*
X-58351Y2764160D01*
Y2763094D01*
X-58551Y2762027D01*
X-58951Y2761094D01*
X-59551Y2760294D01*
X-60251Y2759760D01*
X-61051Y2759627D01*
G01X-55351D02*
Y2767627D01*
X-50751Y2759627D01*
Y2767627D01*
G01X-45051D02*
Y2759627D01*
G01X-47351Y2767627D02*
X-42751D01*
G01X-39051Y2759627D02*
Y2767627D01*
X-36551D01*
X-35751Y2767227D01*
X-35251Y2766694D01*
X-35051Y2765627D01*
X-35251Y2764560D01*
X-35851Y2763894D01*
X-36551Y2763494D01*
X-39051D01*
G01X-36551D02*
X-35051Y2759627D01*
G01X-29051D02*
X-29851Y2759760D01*
X-30551Y2760294D01*
X-31151Y2761094D01*
X-31551Y2762027D01*
X-31751Y2763094D01*
Y2764160D01*
X-31551Y2765227D01*
X-31151Y2766160D01*
X-30551Y2766960D01*
X-29851Y2767494D01*
X-29051Y2767627D01*
X-28251Y2767494D01*
X-27551Y2766960D01*
X-26951Y2766160D01*
X-26551Y2765227D01*
X-26351Y2764160D01*
Y2763094D01*
X-26551Y2762027D01*
X-26951Y2761094D01*
X-27551Y2760294D01*
X-28251Y2759760D01*
X-29051Y2759627D01*
G01X-23051Y2767627D02*
Y2759627D01*
X-19051D01*
G01X-15051Y2767627D02*
Y2759627D01*
X-11051D01*
G01X-3051D02*
X-7051D01*
Y2767627D01*
X-3051D01*
G01X-4651Y2763760D02*
X-7051D01*
G01X749Y2759627D02*
Y2767627D01*
X2749D01*
X3549Y2767227D01*
X4149Y2766694D01*
X4649Y2765894D01*
X5049Y2764960D01*
X5149Y2763627D01*
X5049Y2762294D01*
X4649Y2761360D01*
X4149Y2760560D01*
X3549Y2760027D01*
X2749Y2759627D01*
X749D01*
G01X17749Y2767627D02*
X20149D01*
G01X18949D02*
Y2759627D01*
G01X17749D02*
X20149D01*
G01X24349D02*
Y2767627D01*
X26949Y2760960D01*
X29549Y2767627D01*
Y2759627D01*
G01X32949D02*
Y2767627D01*
X35349D01*
X36149Y2767227D01*
X36749Y2766294D01*
X36949Y2765227D01*
X36749Y2764160D01*
X36249Y2763360D01*
X35349Y2762960D01*
X32949D01*
G01X44949Y2759627D02*
X40949D01*
Y2767627D01*
X44949D01*
G01X43349Y2763760D02*
X40949D01*
G01X48749Y2759627D02*
Y2767627D01*
X50749D01*
X51549Y2767227D01*
X52149Y2766694D01*
X52649Y2765894D01*
X53049Y2764960D01*
X53149Y2763627D01*
X53049Y2762294D01*
X52649Y2761360D01*
X52149Y2760560D01*
X51549Y2760027D01*
X50749Y2759627D01*
X48749D01*
G01X56449D02*
X58949Y2767627D01*
X61449Y2759627D01*
G01X60549Y2762427D02*
X57349D01*
G01X64649Y2759627D02*
Y2767627D01*
X69249Y2759627D01*
Y2767627D01*
G01X77149Y2766960D02*
X76549Y2767360D01*
X75849Y2767627D01*
X75049D01*
X74149Y2767227D01*
X73449Y2766560D01*
X72949Y2765760D01*
X72549Y2764427D01*
X72449Y2763227D01*
X72649Y2762027D01*
X72949Y2761227D01*
X73549Y2760427D01*
X74249Y2759894D01*
X74949Y2759627D01*
X75649D01*
X76349Y2759894D01*
X76949Y2760294D01*
X77449Y2760827D01*
G01X84949Y2759627D02*
X80949D01*
Y2767627D01*
X84949D01*
G01X83349Y2763760D02*
X80949D01*
G01X99749Y2763894D02*
X100149Y2764294D01*
X100449Y2764960D01*
X100649Y2765894D01*
X100449Y2766694D01*
X100049Y2767227D01*
X99349Y2767627D01*
X96649D01*
Y2759627D01*
X99949D01*
X100649Y2760160D01*
X101049Y2760960D01*
X101249Y2761894D01*
X101049Y2762827D01*
X100449Y2763627D01*
X99749Y2763894D01*
X96649D01*
G01X106949Y2759627D02*
X106149Y2759760D01*
X105449Y2760294D01*
X104849Y2761094D01*
X104449Y2762027D01*
X104249Y2763094D01*
Y2764160D01*
X104449Y2765227D01*
X104849Y2766160D01*
X105449Y2766960D01*
X106149Y2767494D01*
X106949Y2767627D01*
X107749Y2767494D01*
X108449Y2766960D01*
X109049Y2766160D01*
X109449Y2765227D01*
X109649Y2764160D01*
Y2763094D01*
X109449Y2762027D01*
X109049Y2761094D01*
X108449Y2760294D01*
X107749Y2759760D01*
X106949Y2759627D01*
G01X112449D02*
X114949Y2767627D01*
X117449Y2759627D01*
G01X116549Y2762427D02*
X113349D01*
G01X120949Y2759627D02*
Y2767627D01*
X123449D01*
X124249Y2767227D01*
X124749Y2766694D01*
X124949Y2765627D01*
X124749Y2764560D01*
X124149Y2763894D01*
X123449Y2763494D01*
X120949D01*
G01X123449D02*
X124949Y2759627D01*
G01X128749D02*
Y2767627D01*
X130749D01*
X131549Y2767227D01*
X132149Y2766694D01*
X132649Y2765894D01*
X133049Y2764960D01*
X133149Y2763627D01*
X133049Y2762294D01*
X132649Y2761360D01*
X132149Y2760560D01*
X131549Y2760027D01*
X130749Y2759627D01*
X128749D01*
G01X138949Y2759360D02*
X138749Y2759494D01*
Y2759760D01*
X138949Y2759894D01*
X139149Y2759760D01*
Y2759494D01*
X138949Y2759360D01*
G01X152849Y2760693D02*
X153649Y2760027D01*
X154549Y2759627D01*
X155349D01*
X156149Y2760027D01*
X156749Y2760693D01*
X157049Y2761627D01*
X156849Y2762560D01*
X156349Y2763360D01*
X155449Y2763894D01*
X154249Y2764160D01*
X153549Y2764694D01*
X153249Y2765627D01*
X153449Y2766560D01*
X153949Y2767227D01*
X154649Y2767627D01*
X155349D01*
X156049Y2767360D01*
X156649Y2766694D01*
G01X164949Y2759627D02*
X160949D01*
Y2767627D01*
X164949D01*
G01X163349Y2763760D02*
X160949D01*
G01X172949Y2759627D02*
X168949D01*
Y2767627D01*
X172949D01*
G01X171349Y2763760D02*
X168949D01*
G01X184949Y2767627D02*
Y2759627D01*
X188949D01*
G01X192449D02*
X194949Y2767627D01*
X197449Y2759627D01*
G01X196549Y2762427D02*
X193349D01*
G01X202949Y2759627D02*
Y2763227D01*
X200949Y2767627D01*
G01X204949D02*
X202949Y2763227D01*
G01X212949Y2759627D02*
X208949D01*
Y2767627D01*
X212949D01*
G01X211349Y2763760D02*
X208949D01*
G01X216949Y2759627D02*
Y2767627D01*
X219449D01*
X220249Y2767227D01*
X220749Y2766694D01*
X220949Y2765627D01*
X220749Y2764560D01*
X220149Y2763894D01*
X219449Y2763494D01*
X216949D01*
G01X219449D02*
X220949Y2759627D01*
G01X232849Y2760693D02*
X233649Y2760027D01*
X234549Y2759627D01*
X235349D01*
X236149Y2760027D01*
X236749Y2760693D01*
X237049Y2761627D01*
X236849Y2762560D01*
X236349Y2763360D01*
X235449Y2763894D01*
X234249Y2764160D01*
X233549Y2764694D01*
X233249Y2765627D01*
X233449Y2766560D01*
X233949Y2767227D01*
X234649Y2767627D01*
X235349D01*
X236049Y2767360D01*
X236649Y2766694D01*
G01X242949Y2767627D02*
Y2759627D01*
G01X240649Y2767627D02*
X245249D01*
G01X248449Y2759627D02*
X250949Y2767627D01*
X253449Y2759627D01*
G01X252549Y2762427D02*
X249349D01*
G01X261149Y2766960D02*
X260549Y2767360D01*
X259849Y2767627D01*
X259049D01*
X258149Y2767227D01*
X257449Y2766560D01*
X256949Y2765760D01*
X256549Y2764427D01*
X256449Y2763227D01*
X256649Y2762027D01*
X256949Y2761227D01*
X257549Y2760427D01*
X258249Y2759894D01*
X258949Y2759627D01*
X259649D01*
X260349Y2759894D01*
X260949Y2760294D01*
X261449Y2760827D01*
G01X264749Y2759627D02*
Y2767627D01*
G01X268549D02*
X264749Y2762693D01*
G01X269149Y2759627D02*
X266449Y2764960D01*
G01X272749Y2767627D02*
Y2761894D01*
X273149Y2760693D01*
X273949Y2759894D01*
X274949Y2759627D01*
X275949Y2759894D01*
X276749Y2760693D01*
X277149Y2761894D01*
Y2767627D01*
G01X280949Y2759627D02*
Y2767627D01*
X283349D01*
X284149Y2767227D01*
X284749Y2766294D01*
X284949Y2765227D01*
X284749Y2764160D01*
X284249Y2763360D01*
X283349Y2762960D01*
X280949D01*
G01X296449Y2759627D02*
X298949Y2767627D01*
X301449Y2759627D01*
G01X300549Y2762427D02*
X297349D01*
G01X304649Y2759627D02*
Y2767627D01*
X309249Y2759627D01*
Y2767627D01*
G01X312749Y2759627D02*
Y2767627D01*
X314749D01*
X315549Y2767227D01*
X316149Y2766694D01*
X316649Y2765894D01*
X317049Y2764960D01*
X317149Y2763627D01*
X317049Y2762294D01*
X316649Y2761360D01*
X316149Y2760560D01*
X315549Y2760027D01*
X314749Y2759627D01*
X312749D01*
G01X329749Y2767627D02*
X332149D01*
G01X330949D02*
Y2759627D01*
G01X329749D02*
X332149D01*
G01X336349D02*
Y2767627D01*
X338949Y2760960D01*
X341549Y2767627D01*
Y2759627D01*
G01X344949D02*
Y2767627D01*
X347349D01*
X348149Y2767227D01*
X348749Y2766294D01*
X348949Y2765227D01*
X348749Y2764160D01*
X348249Y2763360D01*
X347349Y2762960D01*
X344949D01*
G01X356949Y2759627D02*
X352949D01*
Y2767627D01*
X356949D01*
G01X355349Y2763760D02*
X352949D01*
G01X360749Y2759627D02*
Y2767627D01*
X362749D01*
X363549Y2767227D01*
X364149Y2766694D01*
X364649Y2765894D01*
X365049Y2764960D01*
X365149Y2763627D01*
X365049Y2762294D01*
X364649Y2761360D01*
X364149Y2760560D01*
X363549Y2760027D01*
X362749Y2759627D01*
X360749D01*
G01X368449D02*
X370949Y2767627D01*
X373449Y2759627D01*
G01X372549Y2762427D02*
X369349D01*
G01X376649Y2759627D02*
Y2767627D01*
X381249Y2759627D01*
Y2767627D01*
G01X389149Y2766960D02*
X388549Y2767360D01*
X387849Y2767627D01*
X387049D01*
X386149Y2767227D01*
X385449Y2766560D01*
X384949Y2765760D01*
X384549Y2764427D01*
X384449Y2763227D01*
X384649Y2762027D01*
X384949Y2761227D01*
X385549Y2760427D01*
X386249Y2759894D01*
X386949Y2759627D01*
X387649D01*
X388349Y2759894D01*
X388949Y2760294D01*
X389449Y2760827D01*
G01X396949Y2759627D02*
X392949D01*
Y2767627D01*
X396949D01*
G01X395349Y2763760D02*
X392949D01*
G01X-64451Y2778627D02*
X-62451D01*
Y2776227D01*
X-63051Y2775427D01*
X-63751Y2774894D01*
X-64751Y2774627D01*
X-65751Y2774894D01*
X-66451Y2775427D01*
X-67051Y2776227D01*
X-67451Y2777160D01*
X-67651Y2778227D01*
Y2779160D01*
X-67451Y2779960D01*
X-67051Y2780894D01*
X-66451Y2781694D01*
X-65851Y2782227D01*
X-65051Y2782627D01*
X-64351D01*
X-63551Y2782360D01*
X-62951Y2781827D01*
G01X-57051Y2774360D02*
X-57251Y2774494D01*
Y2774760D01*
X-57051Y2774894D01*
X-56851Y2774760D01*
Y2774494D01*
X-57051Y2774360D01*
G01X-51351Y2774627D02*
Y2782627D01*
X-46751Y2774627D01*
Y2782627D01*
G01X-39051Y2774627D02*
X-43051D01*
Y2782627D01*
X-39051D01*
G01X-40651Y2778760D02*
X-43051D01*
G01X-31051Y2774627D02*
X-35051D01*
Y2782627D01*
X-31051D01*
G01X-32651Y2778760D02*
X-35051D01*
G01X-27251Y2774627D02*
Y2782627D01*
X-25251D01*
X-24451Y2782227D01*
X-23851Y2781694D01*
X-23351Y2780894D01*
X-22951Y2779960D01*
X-22851Y2778627D01*
X-22951Y2777294D01*
X-23351Y2776360D01*
X-23851Y2775560D01*
X-24451Y2775027D01*
X-25251Y2774627D01*
X-27251D01*
G01X-11251Y2782627D02*
Y2776894D01*
X-10851Y2775693D01*
X-10051Y2774894D01*
X-9051Y2774627D01*
X-8051Y2774894D01*
X-7251Y2775693D01*
X-6851Y2776894D01*
Y2782627D01*
G01X-3051D02*
Y2774627D01*
X949D01*
G01X12349D02*
Y2782627D01*
X14949Y2775960D01*
X17549Y2782627D01*
Y2774627D01*
G01X20449D02*
X22949Y2782627D01*
X25449Y2774627D01*
G01X24549Y2777427D02*
X21349D01*
G01X28949Y2774627D02*
Y2782627D01*
X31449D01*
X32249Y2782227D01*
X32749Y2781694D01*
X32949Y2780627D01*
X32749Y2779560D01*
X32149Y2778894D01*
X31449Y2778494D01*
X28949D01*
G01X31449D02*
X32949Y2774627D01*
G01X36749D02*
Y2782627D01*
G01X40549D02*
X36749Y2777693D01*
G01X41149Y2774627D02*
X38449Y2779960D01*
G01X52449Y2774627D02*
X54949Y2782627D01*
X57449Y2774627D01*
G01X56549Y2777427D02*
X53349D01*
G01X60649Y2774627D02*
Y2782627D01*
X65249Y2774627D01*
Y2782627D01*
G01X68749Y2774627D02*
Y2782627D01*
X70749D01*
X71549Y2782227D01*
X72149Y2781694D01*
X72649Y2780894D01*
X73049Y2779960D01*
X73149Y2778627D01*
X73049Y2777294D01*
X72649Y2776360D01*
X72149Y2775560D01*
X71549Y2775027D01*
X70749Y2774627D01*
X68749D01*
G01X84749D02*
Y2782627D01*
X86749D01*
X87549Y2782227D01*
X88149Y2781694D01*
X88649Y2780894D01*
X89049Y2779960D01*
X89149Y2778627D01*
X89049Y2777294D01*
X88649Y2776360D01*
X88149Y2775560D01*
X87549Y2775027D01*
X86749Y2774627D01*
X84749D01*
G01X92449D02*
X94949Y2782627D01*
X97449Y2774627D01*
G01X96549Y2777427D02*
X93349D01*
G01X102949Y2782627D02*
Y2774627D01*
G01X100649Y2782627D02*
X105249D01*
G01X112949Y2774627D02*
X108949D01*
Y2782627D01*
X112949D01*
G01X111349Y2778760D02*
X108949D01*
G01X129149Y2781960D02*
X128549Y2782360D01*
X127849Y2782627D01*
X127049D01*
X126149Y2782227D01*
X125449Y2781560D01*
X124949Y2780760D01*
X124549Y2779427D01*
X124449Y2778227D01*
X124649Y2777027D01*
X124949Y2776227D01*
X125549Y2775427D01*
X126249Y2774894D01*
X126949Y2774627D01*
X127649D01*
X128349Y2774894D01*
X128949Y2775294D01*
X129449Y2775827D01*
G01X134949Y2774627D02*
X134149Y2774760D01*
X133449Y2775294D01*
X132849Y2776094D01*
X132449Y2777027D01*
X132249Y2778094D01*
Y2779160D01*
X132449Y2780227D01*
X132849Y2781160D01*
X133449Y2781960D01*
X134149Y2782494D01*
X134949Y2782627D01*
X135749Y2782494D01*
X136449Y2781960D01*
X137049Y2781160D01*
X137449Y2780227D01*
X137649Y2779160D01*
Y2778094D01*
X137449Y2777027D01*
X137049Y2776094D01*
X136449Y2775294D01*
X135749Y2774760D01*
X134949Y2774627D01*
G01X140749D02*
Y2782627D01*
X142749D01*
X143549Y2782227D01*
X144149Y2781694D01*
X144649Y2780894D01*
X145049Y2779960D01*
X145149Y2778627D01*
X145049Y2777294D01*
X144649Y2776360D01*
X144149Y2775560D01*
X143549Y2775027D01*
X142749Y2774627D01*
X140749D01*
G01X152949D02*
X148949D01*
Y2782627D01*
X152949D01*
G01X151349Y2778760D02*
X148949D01*
G01X166449Y2771960D02*
X165449Y2773294D01*
X164949Y2774627D01*
Y2779960D01*
X165449Y2781294D01*
X166449Y2782627D01*
G01X172849Y2775693D02*
X173649Y2775027D01*
X174549Y2774627D01*
X175349D01*
X176149Y2775027D01*
X176749Y2775693D01*
X177049Y2776627D01*
X176849Y2777560D01*
X176349Y2778360D01*
X175449Y2778894D01*
X174249Y2779160D01*
X173549Y2779694D01*
X173249Y2780627D01*
X173449Y2781560D01*
X173949Y2782227D01*
X174649Y2782627D01*
X175349D01*
X176049Y2782360D01*
X176649Y2781694D01*
G01X181749Y2782627D02*
X184149D01*
G01X182949D02*
Y2774627D01*
G01X181749D02*
X184149D01*
G01X188949Y2782627D02*
Y2774627D01*
X192949D01*
G01X196749D02*
Y2782627D01*
G01X200549D02*
X196749Y2777693D01*
G01X201149Y2774627D02*
X198449Y2779960D01*
G01X204849Y2775693D02*
X205649Y2775027D01*
X206549Y2774627D01*
X207349D01*
X208149Y2775027D01*
X208749Y2775693D01*
X209049Y2776627D01*
X208849Y2777560D01*
X208349Y2778360D01*
X207449Y2778894D01*
X206249Y2779160D01*
X205549Y2779694D01*
X205249Y2780627D01*
X205449Y2781560D01*
X205949Y2782227D01*
X206649Y2782627D01*
X207349D01*
X208049Y2782360D01*
X208649Y2781694D01*
G01X217149Y2781960D02*
X216549Y2782360D01*
X215849Y2782627D01*
X215049D01*
X214149Y2782227D01*
X213449Y2781560D01*
X212949Y2780760D01*
X212549Y2779427D01*
X212449Y2778227D01*
X212649Y2777027D01*
X212949Y2776227D01*
X213549Y2775427D01*
X214249Y2774894D01*
X214949Y2774627D01*
X215649D01*
X216349Y2774894D01*
X216949Y2775294D01*
X217449Y2775827D01*
G01X220949Y2774627D02*
Y2782627D01*
X223449D01*
X224249Y2782227D01*
X224749Y2781694D01*
X224949Y2780627D01*
X224749Y2779560D01*
X224149Y2778894D01*
X223449Y2778494D01*
X220949D01*
G01X223449D02*
X224949Y2774627D01*
G01X232949D02*
X228949D01*
Y2782627D01*
X232949D01*
G01X231349Y2778760D02*
X228949D01*
G01X240949Y2774627D02*
X236949D01*
Y2782627D01*
X240949D01*
G01X239349Y2778760D02*
X236949D01*
G01X244649Y2774627D02*
Y2782627D01*
X249249Y2774627D01*
Y2782627D01*
G01X254749Y2773160D02*
X255149Y2774894D01*
G01X262949Y2782627D02*
Y2774627D01*
G01X260649Y2782627D02*
X265249D01*
G01X270949Y2774627D02*
X270149Y2774760D01*
X269449Y2775294D01*
X268849Y2776094D01*
X268449Y2777027D01*
X268249Y2778094D01*
Y2779160D01*
X268449Y2780227D01*
X268849Y2781160D01*
X269449Y2781960D01*
X270149Y2782494D01*
X270949Y2782627D01*
X271749Y2782494D01*
X272449Y2781960D01*
X273049Y2781160D01*
X273449Y2780227D01*
X273649Y2779160D01*
Y2778094D01*
X273449Y2777027D01*
X273049Y2776094D01*
X272449Y2775294D01*
X271749Y2774760D01*
X270949Y2774627D01*
G01X276949D02*
Y2782627D01*
X279349D01*
X280149Y2782227D01*
X280749Y2781294D01*
X280949Y2780227D01*
X280749Y2779160D01*
X280249Y2778360D01*
X279349Y2777960D01*
X276949D01*
G01X292849Y2775693D02*
X293649Y2775027D01*
X294549Y2774627D01*
X295349D01*
X296149Y2775027D01*
X296749Y2775693D01*
X297049Y2776627D01*
X296849Y2777560D01*
X296349Y2778360D01*
X295449Y2778894D01*
X294249Y2779160D01*
X293549Y2779694D01*
X293249Y2780627D01*
X293449Y2781560D01*
X293949Y2782227D01*
X294649Y2782627D01*
X295349D01*
X296049Y2782360D01*
X296649Y2781694D01*
G01X301749Y2782627D02*
X304149D01*
G01X302949D02*
Y2774627D01*
G01X301749D02*
X304149D01*
G01X308749D02*
Y2782627D01*
X310749D01*
X311549Y2782227D01*
X312149Y2781694D01*
X312649Y2780894D01*
X313049Y2779960D01*
X313149Y2778627D01*
X313049Y2777294D01*
X312649Y2776360D01*
X312149Y2775560D01*
X311549Y2775027D01*
X310749Y2774627D01*
X308749D01*
G01X320949D02*
X316949D01*
Y2782627D01*
X320949D01*
G01X319349Y2778760D02*
X316949D01*
G01X326749Y2773160D02*
X327149Y2774894D01*
G01X339949Y2782627D02*
X341349Y2774627D01*
X342949Y2782627D01*
X344549Y2774627D01*
X345949Y2782627D01*
G01X347949D02*
X349349Y2774627D01*
X350949Y2782627D01*
X352549Y2774627D01*
X353949Y2782627D01*
G01X358949Y2774627D02*
Y2778227D01*
X356949Y2782627D01*
G01X360949D02*
X358949Y2778227D01*
G01X366949Y2774627D02*
Y2778227D01*
X364949Y2782627D01*
G01X368949D02*
X366949Y2778227D01*
G01X375449Y2771960D02*
X376449Y2773294D01*
X376949Y2774627D01*
Y2779960D01*
X376449Y2781294D01*
X375449Y2782627D01*
G01X-63051Y2804627D02*
X-67051D01*
Y2812627D01*
X-63051D01*
G01X-64651Y2808760D02*
X-67051D01*
G01X-57051Y2804360D02*
X-57251Y2804494D01*
Y2804760D01*
X-57051Y2804894D01*
X-56851Y2804760D01*
Y2804494D01*
X-57051Y2804360D01*
G01X-51051Y2804627D02*
Y2812627D01*
X-48651D01*
X-47851Y2812227D01*
X-47251Y2811294D01*
X-47051Y2810227D01*
X-47251Y2809160D01*
X-47751Y2808360D01*
X-48651Y2807960D01*
X-51051D01*
G01X-43051Y2804627D02*
Y2812627D01*
X-40551D01*
X-39751Y2812227D01*
X-39251Y2811694D01*
X-39051Y2810627D01*
X-39251Y2809560D01*
X-39851Y2808894D01*
X-40551Y2808494D01*
X-43051D01*
G01X-40551D02*
X-39051Y2804627D01*
G01X-33051D02*
X-33851Y2804760D01*
X-34551Y2805294D01*
X-35151Y2806094D01*
X-35551Y2807027D01*
X-35751Y2808094D01*
Y2809160D01*
X-35551Y2810227D01*
X-35151Y2811160D01*
X-34551Y2811960D01*
X-33851Y2812494D01*
X-33051Y2812627D01*
X-32251Y2812494D01*
X-31551Y2811960D01*
X-30951Y2811160D01*
X-30551Y2810227D01*
X-30351Y2809160D01*
Y2808094D01*
X-30551Y2807027D01*
X-30951Y2806094D01*
X-31551Y2805294D01*
X-32251Y2804760D01*
X-33051Y2804627D01*
G01X-27551Y2812627D02*
X-25051Y2804627D01*
X-22551Y2812627D01*
G01X-18251D02*
X-15851D01*
G01X-17051D02*
Y2804627D01*
G01X-18251D02*
X-15851D01*
G01X-11251D02*
Y2812627D01*
X-9251D01*
X-8451Y2812227D01*
X-7851Y2811694D01*
X-7351Y2810894D01*
X-6951Y2809960D01*
X-6851Y2808627D01*
X-6951Y2807294D01*
X-7351Y2806360D01*
X-7851Y2805560D01*
X-8451Y2805027D01*
X-9251Y2804627D01*
X-11251D01*
G01X949D02*
X-3051D01*
Y2812627D01*
X949D01*
G01X-651Y2808760D02*
X-3051D01*
G01X12949Y2804627D02*
Y2812627D01*
X15349D01*
X16149Y2812227D01*
X16749Y2811294D01*
X16949Y2810227D01*
X16749Y2809160D01*
X16249Y2808360D01*
X15349Y2807960D01*
X12949D01*
G01X25149Y2811960D02*
X24549Y2812360D01*
X23849Y2812627D01*
X23049D01*
X22149Y2812227D01*
X21449Y2811560D01*
X20949Y2810760D01*
X20549Y2809427D01*
X20449Y2808227D01*
X20649Y2807027D01*
X20949Y2806227D01*
X21549Y2805427D01*
X22249Y2804894D01*
X22949Y2804627D01*
X23649D01*
X24349Y2804894D01*
X24949Y2805294D01*
X25449Y2805827D01*
G01X31749Y2808894D02*
X32149Y2809294D01*
X32449Y2809960D01*
X32649Y2810894D01*
X32449Y2811694D01*
X32049Y2812227D01*
X31349Y2812627D01*
X28649D01*
Y2804627D01*
X31949D01*
X32649Y2805160D01*
X33049Y2805960D01*
X33249Y2806894D01*
X33049Y2807827D01*
X32449Y2808627D01*
X31749Y2808894D01*
X28649D01*
G01X45049Y2804627D02*
Y2812627D01*
X48849D01*
G01X47449Y2808760D02*
X45049D01*
G01X53749Y2812627D02*
X56149D01*
G01X54949D02*
Y2804627D01*
G01X53749D02*
X56149D01*
G01X60949Y2812627D02*
Y2804627D01*
X64949D01*
G01X68349D02*
Y2812627D01*
X70949Y2805960D01*
X73549Y2812627D01*
Y2804627D01*
G01X-66951Y2789627D02*
Y2797627D01*
X-63151D01*
G01X-64551Y2793760D02*
X-66951D01*
G01X-57051Y2789360D02*
X-57251Y2789494D01*
Y2789760D01*
X-57051Y2789894D01*
X-56851Y2789760D01*
Y2789494D01*
X-57051Y2789360D01*
G01X-51351Y2789627D02*
Y2797627D01*
X-46751Y2789627D01*
Y2797627D01*
G01X-39051Y2789627D02*
X-43051D01*
Y2797627D01*
X-39051D01*
G01X-40651Y2793760D02*
X-43051D01*
G01X-31051Y2789627D02*
X-35051D01*
Y2797627D01*
X-31051D01*
G01X-32651Y2793760D02*
X-35051D01*
G01X-27251Y2789627D02*
Y2797627D01*
X-25251D01*
X-24451Y2797227D01*
X-23851Y2796694D01*
X-23351Y2795894D01*
X-22951Y2794960D01*
X-22851Y2793627D01*
X-22951Y2792294D01*
X-23351Y2791360D01*
X-23851Y2790560D01*
X-24451Y2790027D01*
X-25251Y2789627D01*
X-27251D01*
G01X-11051D02*
Y2797627D01*
X-8651D01*
X-7851Y2797227D01*
X-7251Y2796294D01*
X-7051Y2795227D01*
X-7251Y2794160D01*
X-7751Y2793360D01*
X-8651Y2792960D01*
X-11051D01*
G01X1149Y2796960D02*
X549Y2797360D01*
X-151Y2797627D01*
X-951D01*
X-1851Y2797227D01*
X-2551Y2796560D01*
X-3051Y2795760D01*
X-3451Y2794427D01*
X-3551Y2793227D01*
X-3351Y2792027D01*
X-3051Y2791227D01*
X-2451Y2790427D01*
X-1751Y2789894D01*
X-1051Y2789627D01*
X-351D01*
X349Y2789894D01*
X949Y2790294D01*
X1449Y2790827D01*
G01X7749Y2793894D02*
X8149Y2794294D01*
X8449Y2794960D01*
X8649Y2795894D01*
X8449Y2796694D01*
X8049Y2797227D01*
X7349Y2797627D01*
X4649D01*
Y2789627D01*
X7949D01*
X8649Y2790160D01*
X9049Y2790960D01*
X9249Y2791894D01*
X9049Y2792827D01*
X8449Y2793627D01*
X7749Y2793894D01*
X4649D01*
G01X20349Y2789627D02*
Y2797627D01*
X22949Y2790960D01*
X25549Y2797627D01*
Y2789627D01*
G01X28449D02*
X30949Y2797627D01*
X33449Y2789627D01*
G01X32549Y2792427D02*
X29349D01*
G01X36749Y2789627D02*
Y2797627D01*
G01X40549D02*
X36749Y2792693D01*
G01X41149Y2789627D02*
X38449Y2794960D01*
G01X48949Y2789627D02*
X44949D01*
Y2797627D01*
X48949D01*
G01X47349Y2793760D02*
X44949D01*
G01X52949Y2789627D02*
Y2797627D01*
X55449D01*
X56249Y2797227D01*
X56749Y2796694D01*
X56949Y2795627D01*
X56749Y2794560D01*
X56149Y2793894D01*
X55449Y2793494D01*
X52949D01*
G01X55449D02*
X56949Y2789627D01*
G01X60849Y2790693D02*
X61649Y2790027D01*
X62549Y2789627D01*
X63349D01*
X64149Y2790027D01*
X64749Y2790693D01*
X65049Y2791627D01*
X64849Y2792560D01*
X64349Y2793360D01*
X63449Y2793894D01*
X62249Y2794160D01*
X61549Y2794694D01*
X61249Y2795627D01*
X61449Y2796560D01*
X61949Y2797227D01*
X62649Y2797627D01*
X63349D01*
X64049Y2797360D01*
X64649Y2796694D01*
G01X78449Y2786960D02*
X77449Y2788294D01*
X76949Y2789627D01*
Y2794960D01*
X77449Y2796294D01*
X78449Y2797627D01*
G01X84849Y2790693D02*
X85649Y2790027D01*
X86549Y2789627D01*
X87349D01*
X88149Y2790027D01*
X88749Y2790693D01*
X89049Y2791627D01*
X88849Y2792560D01*
X88349Y2793360D01*
X87449Y2793894D01*
X86249Y2794160D01*
X85549Y2794694D01*
X85249Y2795627D01*
X85449Y2796560D01*
X85949Y2797227D01*
X86649Y2797627D01*
X87349D01*
X88049Y2797360D01*
X88649Y2796694D01*
G01X93749Y2797627D02*
X96149D01*
G01X94949D02*
Y2789627D01*
G01X93749D02*
X96149D01*
G01X100949Y2797627D02*
Y2789627D01*
X104949D01*
G01X108749D02*
Y2797627D01*
G01X112549D02*
X108749Y2792693D01*
G01X113149Y2789627D02*
X110449Y2794960D01*
G01X116849Y2790693D02*
X117649Y2790027D01*
X118549Y2789627D01*
X119349D01*
X120149Y2790027D01*
X120749Y2790693D01*
X121049Y2791627D01*
X120849Y2792560D01*
X120349Y2793360D01*
X119449Y2793894D01*
X118249Y2794160D01*
X117549Y2794694D01*
X117249Y2795627D01*
X117449Y2796560D01*
X117949Y2797227D01*
X118649Y2797627D01*
X119349D01*
X120049Y2797360D01*
X120649Y2796694D01*
G01X129149Y2796960D02*
X128549Y2797360D01*
X127849Y2797627D01*
X127049D01*
X126149Y2797227D01*
X125449Y2796560D01*
X124949Y2795760D01*
X124549Y2794427D01*
X124449Y2793227D01*
X124649Y2792027D01*
X124949Y2791227D01*
X125549Y2790427D01*
X126249Y2789894D01*
X126949Y2789627D01*
X127649D01*
X128349Y2789894D01*
X128949Y2790294D01*
X129449Y2790827D01*
G01X132949Y2789627D02*
Y2797627D01*
X135449D01*
X136249Y2797227D01*
X136749Y2796694D01*
X136949Y2795627D01*
X136749Y2794560D01*
X136149Y2793894D01*
X135449Y2793494D01*
X132949D01*
G01X135449D02*
X136949Y2789627D01*
G01X144949D02*
X140949D01*
Y2797627D01*
X144949D01*
G01X143349Y2793760D02*
X140949D01*
G01X152949Y2789627D02*
X148949D01*
Y2797627D01*
X152949D01*
G01X151349Y2793760D02*
X148949D01*
G01X156649Y2789627D02*
Y2797627D01*
X161249Y2789627D01*
Y2797627D01*
G01X166949Y2789360D02*
X166749Y2789494D01*
Y2789760D01*
X166949Y2789894D01*
X167149Y2789760D01*
Y2789494D01*
X166949Y2789360D01*
G01X174949Y2797627D02*
Y2789627D01*
G01X172649Y2797627D02*
X177249D01*
G01X182949Y2789627D02*
X182149Y2789760D01*
X181449Y2790294D01*
X180849Y2791094D01*
X180449Y2792027D01*
X180249Y2793094D01*
Y2794160D01*
X180449Y2795227D01*
X180849Y2796160D01*
X181449Y2796960D01*
X182149Y2797494D01*
X182949Y2797627D01*
X183749Y2797494D01*
X184449Y2796960D01*
X185049Y2796160D01*
X185449Y2795227D01*
X185649Y2794160D01*
Y2793094D01*
X185449Y2792027D01*
X185049Y2791094D01*
X184449Y2790294D01*
X183749Y2789760D01*
X182949Y2789627D01*
G01X188949D02*
Y2797627D01*
X191349D01*
X192149Y2797227D01*
X192749Y2796294D01*
X192949Y2795227D01*
X192749Y2794160D01*
X192249Y2793360D01*
X191349Y2792960D01*
X188949D01*
G01X204849Y2790693D02*
X205649Y2790027D01*
X206549Y2789627D01*
X207349D01*
X208149Y2790027D01*
X208749Y2790693D01*
X209049Y2791627D01*
X208849Y2792560D01*
X208349Y2793360D01*
X207449Y2793894D01*
X206249Y2794160D01*
X205549Y2794694D01*
X205249Y2795627D01*
X205449Y2796560D01*
X205949Y2797227D01*
X206649Y2797627D01*
X207349D01*
X208049Y2797360D01*
X208649Y2796694D01*
G01X213749Y2797627D02*
X216149D01*
G01X214949D02*
Y2789627D01*
G01X213749D02*
X216149D01*
G01X220749D02*
Y2797627D01*
X222749D01*
X223549Y2797227D01*
X224149Y2796694D01*
X224649Y2795894D01*
X225049Y2794960D01*
X225149Y2793627D01*
X225049Y2792294D01*
X224649Y2791360D01*
X224149Y2790560D01*
X223549Y2790027D01*
X222749Y2789627D01*
X220749D01*
G01X232949D02*
X228949D01*
Y2797627D01*
X232949D01*
G01X231349Y2793760D02*
X228949D01*
G01X239449Y2786960D02*
X240449Y2788294D01*
X240949Y2789627D01*
Y2794960D01*
X240449Y2796294D01*
X239449Y2797627D01*
G01X-62851Y2841960D02*
X-63451Y2842360D01*
X-64151Y2842627D01*
X-64951D01*
X-65851Y2842227D01*
X-66551Y2841560D01*
X-67051Y2840760D01*
X-67451Y2839427D01*
X-67551Y2838227D01*
X-67351Y2837027D01*
X-67051Y2836227D01*
X-66451Y2835427D01*
X-65751Y2834894D01*
X-65051Y2834627D01*
X-64351D01*
X-63651Y2834894D01*
X-63051Y2835294D01*
X-62551Y2835827D01*
G01X-57051Y2834360D02*
X-57251Y2834494D01*
Y2834760D01*
X-57051Y2834894D01*
X-56851Y2834760D01*
Y2834494D01*
X-57051Y2834360D01*
G01X-51351Y2834627D02*
Y2842627D01*
X-46751Y2834627D01*
Y2842627D01*
G01X-41051Y2834627D02*
X-41851Y2834760D01*
X-42551Y2835294D01*
X-43151Y2836094D01*
X-43551Y2837027D01*
X-43751Y2838094D01*
Y2839160D01*
X-43551Y2840227D01*
X-43151Y2841160D01*
X-42551Y2841960D01*
X-41851Y2842494D01*
X-41051Y2842627D01*
X-40251Y2842494D01*
X-39551Y2841960D01*
X-38951Y2841160D01*
X-38551Y2840227D01*
X-38351Y2839160D01*
Y2838094D01*
X-38551Y2837027D01*
X-38951Y2836094D01*
X-39551Y2835294D01*
X-40251Y2834760D01*
X-41051Y2834627D01*
G01X-27351D02*
Y2842627D01*
X-22751Y2834627D01*
Y2842627D01*
G01X-15051Y2834627D02*
X-19051D01*
Y2842627D01*
X-15051D01*
G01X-16651Y2838760D02*
X-19051D01*
G01X-7051Y2834627D02*
X-11051D01*
Y2842627D01*
X-7051D01*
G01X-8651Y2838760D02*
X-11051D01*
G01X-3251Y2834627D02*
Y2842627D01*
X-1251D01*
X-451Y2842227D01*
X149Y2841694D01*
X649Y2840894D01*
X1049Y2839960D01*
X1149Y2838627D01*
X1049Y2837294D01*
X649Y2836360D01*
X149Y2835560D01*
X-451Y2835027D01*
X-1251Y2834627D01*
X-3251D01*
G01X14949Y2842627D02*
Y2834627D01*
G01X12649Y2842627D02*
X17249D01*
G01X22949Y2834627D02*
X22149Y2834760D01*
X21449Y2835294D01*
X20849Y2836094D01*
X20449Y2837027D01*
X20249Y2838094D01*
Y2839160D01*
X20449Y2840227D01*
X20849Y2841160D01*
X21449Y2841960D01*
X22149Y2842494D01*
X22949Y2842627D01*
X23749Y2842494D01*
X24449Y2841960D01*
X25049Y2841160D01*
X25449Y2840227D01*
X25649Y2839160D01*
Y2838094D01*
X25449Y2837027D01*
X25049Y2836094D01*
X24449Y2835294D01*
X23749Y2834760D01*
X22949Y2834627D01*
G01X36949D02*
Y2842627D01*
X39349D01*
X40149Y2842227D01*
X40749Y2841294D01*
X40949Y2840227D01*
X40749Y2839160D01*
X40249Y2838360D01*
X39349Y2837960D01*
X36949D01*
G01X44949Y2842627D02*
Y2834627D01*
X48949D01*
G01X52749Y2842627D02*
Y2836894D01*
X53149Y2835693D01*
X53949Y2834894D01*
X54949Y2834627D01*
X55949Y2834894D01*
X56749Y2835693D01*
X57149Y2836894D01*
Y2842627D01*
G01X63549Y2838627D02*
X65549D01*
Y2836227D01*
X64949Y2835427D01*
X64249Y2834894D01*
X63249Y2834627D01*
X62249Y2834894D01*
X61549Y2835427D01*
X60949Y2836227D01*
X60549Y2837160D01*
X60349Y2838227D01*
Y2839160D01*
X60549Y2839960D01*
X60949Y2840894D01*
X61549Y2841694D01*
X62149Y2842227D01*
X62949Y2842627D01*
X63649D01*
X64449Y2842360D01*
X65049Y2841827D01*
G01X78949Y2834627D02*
X79649Y2834760D01*
X80449Y2835160D01*
X80949Y2835827D01*
X81149Y2836760D01*
X80949Y2837693D01*
X80349Y2838494D01*
X79449Y2838894D01*
X78449D01*
X77849Y2839160D01*
X77349Y2839827D01*
X77149Y2840760D01*
X77449Y2841694D01*
X78149Y2842360D01*
X78949Y2842627D01*
X79749Y2842360D01*
X80449Y2841694D01*
X80749Y2840760D01*
X80549Y2839827D01*
X80049Y2839160D01*
X79449Y2838894D01*
X78449D01*
X77549Y2838494D01*
X76949Y2837693D01*
X76749Y2836760D01*
X76949Y2835827D01*
X77449Y2835160D01*
X78249Y2834760D01*
X78949Y2834627D01*
G01X92849D02*
Y2842627D01*
G01X97049D02*
Y2834627D01*
G01Y2838627D02*
X92849D01*
G01X102949Y2834627D02*
X102149Y2834760D01*
X101449Y2835294D01*
X100849Y2836094D01*
X100449Y2837027D01*
X100249Y2838094D01*
Y2839160D01*
X100449Y2840227D01*
X100849Y2841160D01*
X101449Y2841960D01*
X102149Y2842494D01*
X102949Y2842627D01*
X103749Y2842494D01*
X104449Y2841960D01*
X105049Y2841160D01*
X105449Y2840227D01*
X105649Y2839160D01*
Y2838094D01*
X105449Y2837027D01*
X105049Y2836094D01*
X104449Y2835294D01*
X103749Y2834760D01*
X102949Y2834627D01*
G01X108949Y2842627D02*
Y2834627D01*
X112949D01*
G01X120949D02*
X116949D01*
Y2842627D01*
X120949D01*
G01X119349Y2838760D02*
X116949D01*
G01X124849Y2835693D02*
X125649Y2835027D01*
X126549Y2834627D01*
X127349D01*
X128149Y2835027D01*
X128749Y2835693D01*
X129049Y2836627D01*
X128849Y2837560D01*
X128349Y2838360D01*
X127449Y2838894D01*
X126249Y2839160D01*
X125549Y2839694D01*
X125249Y2840627D01*
X125449Y2841560D01*
X125949Y2842227D01*
X126649Y2842627D01*
X127349D01*
X128049Y2842360D01*
X128649Y2841694D01*
G01X140849Y2835693D02*
X141649Y2835027D01*
X142549Y2834627D01*
X143349D01*
X144149Y2835027D01*
X144749Y2835693D01*
X145049Y2836627D01*
X144849Y2837560D01*
X144349Y2838360D01*
X143449Y2838894D01*
X142249Y2839160D01*
X141549Y2839694D01*
X141249Y2840627D01*
X141449Y2841560D01*
X141949Y2842227D01*
X142649Y2842627D01*
X143349D01*
X144049Y2842360D01*
X144649Y2841694D01*
G01X148749Y2842627D02*
Y2836894D01*
X149149Y2835693D01*
X149949Y2834894D01*
X150949Y2834627D01*
X151949Y2834894D01*
X152749Y2835693D01*
X153149Y2836894D01*
Y2842627D01*
G01X156949Y2834627D02*
Y2842627D01*
X159449D01*
X160249Y2842227D01*
X160749Y2841694D01*
X160949Y2840627D01*
X160749Y2839560D01*
X160149Y2838894D01*
X159449Y2838494D01*
X156949D01*
G01X159449D02*
X160949Y2834627D01*
G01X164949D02*
Y2842627D01*
X167449D01*
X168249Y2842227D01*
X168749Y2841694D01*
X168949Y2840627D01*
X168749Y2839560D01*
X168149Y2838894D01*
X167449Y2838494D01*
X164949D01*
G01X167449D02*
X168949Y2834627D01*
G01X174949D02*
X174149Y2834760D01*
X173449Y2835294D01*
X172849Y2836094D01*
X172449Y2837027D01*
X172249Y2838094D01*
Y2839160D01*
X172449Y2840227D01*
X172849Y2841160D01*
X173449Y2841960D01*
X174149Y2842494D01*
X174949Y2842627D01*
X175749Y2842494D01*
X176449Y2841960D01*
X177049Y2841160D01*
X177449Y2840227D01*
X177649Y2839160D01*
Y2838094D01*
X177449Y2837027D01*
X177049Y2836094D01*
X176449Y2835294D01*
X175749Y2834760D01*
X174949Y2834627D01*
G01X180749Y2842627D02*
Y2836894D01*
X181149Y2835693D01*
X181949Y2834894D01*
X182949Y2834627D01*
X183949Y2834894D01*
X184749Y2835693D01*
X185149Y2836894D01*
Y2842627D01*
G01X188649Y2834627D02*
Y2842627D01*
X193249Y2834627D01*
Y2842627D01*
G01X196749Y2834627D02*
Y2842627D01*
X198749D01*
X199549Y2842227D01*
X200149Y2841694D01*
X200649Y2840894D01*
X201049Y2839960D01*
X201149Y2838627D01*
X201049Y2837294D01*
X200649Y2836360D01*
X200149Y2835560D01*
X199549Y2835027D01*
X198749Y2834627D01*
X196749D01*
G01X205749Y2842627D02*
X208149D01*
G01X206949D02*
Y2834627D01*
G01X205749D02*
X208149D01*
G01X212649D02*
Y2842627D01*
X217249Y2834627D01*
Y2842627D01*
G01X223549Y2838627D02*
X225549D01*
Y2836227D01*
X224949Y2835427D01*
X224249Y2834894D01*
X223249Y2834627D01*
X222249Y2834894D01*
X221549Y2835427D01*
X220949Y2836227D01*
X220549Y2837160D01*
X220349Y2838227D01*
Y2839160D01*
X220549Y2839960D01*
X220949Y2840894D01*
X221549Y2841694D01*
X222149Y2842227D01*
X222949Y2842627D01*
X223649D01*
X224449Y2842360D01*
X225049Y2841827D01*
G01X236849Y2835693D02*
X237649Y2835027D01*
X238549Y2834627D01*
X239349D01*
X240149Y2835027D01*
X240749Y2835693D01*
X241049Y2836627D01*
X240849Y2837560D01*
X240349Y2838360D01*
X239449Y2838894D01*
X238249Y2839160D01*
X237549Y2839694D01*
X237249Y2840627D01*
X237449Y2841560D01*
X237949Y2842227D01*
X238649Y2842627D01*
X239349D01*
X240049Y2842360D01*
X240649Y2841694D01*
G01X249149Y2841960D02*
X248549Y2842360D01*
X247849Y2842627D01*
X247049D01*
X246149Y2842227D01*
X245449Y2841560D01*
X244949Y2840760D01*
X244549Y2839427D01*
X244449Y2838227D01*
X244649Y2837027D01*
X244949Y2836227D01*
X245549Y2835427D01*
X246249Y2834894D01*
X246949Y2834627D01*
X247649D01*
X248349Y2834894D01*
X248949Y2835294D01*
X249449Y2835827D01*
G01X252949Y2834627D02*
Y2842627D01*
X255449D01*
X256249Y2842227D01*
X256749Y2841694D01*
X256949Y2840627D01*
X256749Y2839560D01*
X256149Y2838894D01*
X255449Y2838494D01*
X252949D01*
G01X255449D02*
X256949Y2834627D01*
G01X264949D02*
X260949D01*
Y2842627D01*
X264949D01*
G01X263349Y2838760D02*
X260949D01*
G01X267949Y2842627D02*
X269349Y2834627D01*
X270949Y2842627D01*
X272549Y2834627D01*
X273949Y2842627D01*
G01X278949Y2834360D02*
X278749Y2834494D01*
Y2834760D01*
X278949Y2834894D01*
X279149Y2834760D01*
Y2834494D01*
X278949Y2834360D01*
G01X286449Y2831960D02*
X285449Y2833294D01*
X284949Y2834627D01*
Y2839960D01*
X285449Y2841294D01*
X286449Y2842627D01*
G01X292949Y2834627D02*
Y2842627D01*
X295349D01*
X296149Y2842227D01*
X296749Y2841294D01*
X296949Y2840227D01*
X296749Y2839160D01*
X296249Y2838360D01*
X295349Y2837960D01*
X292949D01*
G01X300949Y2842627D02*
Y2834627D01*
X304949D01*
G01X312949D02*
X308949D01*
Y2842627D01*
X312949D01*
G01X311349Y2838760D02*
X308949D01*
G01X316449Y2834627D02*
X318949Y2842627D01*
X321449Y2834627D01*
G01X320549Y2837427D02*
X317349D01*
G01X324849Y2835693D02*
X325649Y2835027D01*
X326549Y2834627D01*
X327349D01*
X328149Y2835027D01*
X328749Y2835693D01*
X329049Y2836627D01*
X328849Y2837560D01*
X328349Y2838360D01*
X327449Y2838894D01*
X326249Y2839160D01*
X325549Y2839694D01*
X325249Y2840627D01*
X325449Y2841560D01*
X325949Y2842227D01*
X326649Y2842627D01*
X327349D01*
X328049Y2842360D01*
X328649Y2841694D01*
G01X336949Y2834627D02*
X332949D01*
Y2842627D01*
X336949D01*
G01X335349Y2838760D02*
X332949D01*
G01X349749Y2842627D02*
X352149D01*
G01X350949D02*
Y2834627D01*
G01X349749D02*
X352149D01*
G01X359549Y2838627D02*
X361549D01*
Y2836227D01*
X360949Y2835427D01*
X360249Y2834894D01*
X359249Y2834627D01*
X358249Y2834894D01*
X357549Y2835427D01*
X356949Y2836227D01*
X356549Y2837160D01*
X356349Y2838227D01*
Y2839160D01*
X356549Y2839960D01*
X356949Y2840894D01*
X357549Y2841694D01*
X358149Y2842227D01*
X358949Y2842627D01*
X359649D01*
X360449Y2842360D01*
X361049Y2841827D01*
G01X364649Y2834627D02*
Y2842627D01*
X369249Y2834627D01*
Y2842627D01*
G01X374949Y2834627D02*
X374149Y2834760D01*
X373449Y2835294D01*
X372849Y2836094D01*
X372449Y2837027D01*
X372249Y2838094D01*
Y2839160D01*
X372449Y2840227D01*
X372849Y2841160D01*
X373449Y2841960D01*
X374149Y2842494D01*
X374949Y2842627D01*
X375749Y2842494D01*
X376449Y2841960D01*
X377049Y2841160D01*
X377449Y2840227D01*
X377649Y2839160D01*
Y2838094D01*
X377449Y2837027D01*
X377049Y2836094D01*
X376449Y2835294D01*
X375749Y2834760D01*
X374949Y2834627D01*
G01X380949D02*
Y2842627D01*
X383449D01*
X384249Y2842227D01*
X384749Y2841694D01*
X384949Y2840627D01*
X384749Y2839560D01*
X384149Y2838894D01*
X383449Y2838494D01*
X380949D01*
G01X383449D02*
X384949Y2834627D01*
G01X392949D02*
X388949D01*
Y2842627D01*
X392949D01*
G01X391349Y2838760D02*
X388949D01*
G01X406949Y2842627D02*
Y2834627D01*
G01X404649Y2842627D02*
X409249D01*
G01X412849Y2834627D02*
Y2842627D01*
G01X417049D02*
Y2834627D01*
G01Y2838627D02*
X412849D01*
G01X421749Y2842627D02*
X424149D01*
G01X422949D02*
Y2834627D01*
G01X421749D02*
X424149D01*
G01X428849Y2835693D02*
X429649Y2835027D01*
X430549Y2834627D01*
X431349D01*
X432149Y2835027D01*
X432749Y2835693D01*
X433049Y2836627D01*
X432849Y2837560D01*
X432349Y2838360D01*
X431449Y2838894D01*
X430249Y2839160D01*
X429549Y2839694D01*
X429249Y2840627D01*
X429449Y2841560D01*
X429949Y2842227D01*
X430649Y2842627D01*
X431349D01*
X432049Y2842360D01*
X432649Y2841694D01*
G01X445749Y2842627D02*
X448149D01*
G01X446949D02*
Y2834627D01*
G01X445749D02*
X448149D01*
G01X453049D02*
Y2842627D01*
X456849D01*
G01X455449Y2838760D02*
X453049D01*
G01X468649Y2834627D02*
Y2842627D01*
X473249Y2834627D01*
Y2842627D01*
G01X478949Y2834627D02*
X478149Y2834760D01*
X477449Y2835294D01*
X476849Y2836094D01*
X476449Y2837027D01*
X476249Y2838094D01*
Y2839160D01*
X476449Y2840227D01*
X476849Y2841160D01*
X477449Y2841960D01*
X478149Y2842494D01*
X478949Y2842627D01*
X479749Y2842494D01*
X480449Y2841960D01*
X481049Y2841160D01*
X481449Y2840227D01*
X481649Y2839160D01*
Y2838094D01*
X481449Y2837027D01*
X481049Y2836094D01*
X480449Y2835294D01*
X479749Y2834760D01*
X478949Y2834627D01*
G01X494949Y2842627D02*
Y2834627D01*
G01X492649Y2842627D02*
X497249D01*
G01X500849Y2834627D02*
Y2842627D01*
G01X505049D02*
Y2834627D01*
G01Y2838627D02*
X500849D01*
G01X509749Y2842627D02*
X512149D01*
G01X510949D02*
Y2834627D01*
G01X509749D02*
X512149D01*
G01X516849Y2835693D02*
X517649Y2835027D01*
X518549Y2834627D01*
X519349D01*
X520149Y2835027D01*
X520749Y2835693D01*
X521049Y2836627D01*
X520849Y2837560D01*
X520349Y2838360D01*
X519449Y2838894D01*
X518249Y2839160D01*
X517549Y2839694D01*
X517249Y2840627D01*
X517449Y2841560D01*
X517949Y2842227D01*
X518649Y2842627D01*
X519349D01*
X520049Y2842360D01*
X520649Y2841694D01*
G01X533749Y2842627D02*
X536149D01*
G01X534949D02*
Y2834627D01*
G01X533749D02*
X536149D01*
G01X542949Y2842627D02*
Y2834627D01*
G01X540649Y2842627D02*
X545249D01*
G01X552949Y2834627D02*
X548949D01*
Y2842627D01*
X552949D01*
G01X551349Y2838760D02*
X548949D01*
G01X556349Y2834627D02*
Y2842627D01*
X558949Y2835960D01*
X561549Y2842627D01*
Y2834627D01*
G01X573749Y2842627D02*
X576149D01*
G01X574949D02*
Y2834627D01*
G01X573749D02*
X576149D01*
G01X580649D02*
Y2842627D01*
X585249Y2834627D01*
Y2842627D01*
G01X599749Y2838894D02*
X600149Y2839294D01*
X600449Y2839960D01*
X600649Y2840894D01*
X600449Y2841694D01*
X600049Y2842227D01*
X599349Y2842627D01*
X596649D01*
Y2834627D01*
X599949D01*
X600649Y2835160D01*
X601049Y2835960D01*
X601249Y2836894D01*
X601049Y2837827D01*
X600449Y2838627D01*
X599749Y2838894D01*
X596649D01*
G01X606949Y2834627D02*
X606149Y2834760D01*
X605449Y2835294D01*
X604849Y2836094D01*
X604449Y2837027D01*
X604249Y2838094D01*
Y2839160D01*
X604449Y2840227D01*
X604849Y2841160D01*
X605449Y2841960D01*
X606149Y2842494D01*
X606949Y2842627D01*
X607749Y2842494D01*
X608449Y2841960D01*
X609049Y2841160D01*
X609449Y2840227D01*
X609649Y2839160D01*
Y2838094D01*
X609449Y2837027D01*
X609049Y2836094D01*
X608449Y2835294D01*
X607749Y2834760D01*
X606949Y2834627D01*
G01X612449D02*
X614949Y2842627D01*
X617449Y2834627D01*
G01X616549Y2837427D02*
X613349D01*
G01X620949Y2834627D02*
Y2842627D01*
X623449D01*
X624249Y2842227D01*
X624749Y2841694D01*
X624949Y2840627D01*
X624749Y2839560D01*
X624149Y2838894D01*
X623449Y2838494D01*
X620949D01*
G01X623449D02*
X624949Y2834627D01*
G01X628749D02*
Y2842627D01*
X630749D01*
X631549Y2842227D01*
X632149Y2841694D01*
X632649Y2840894D01*
X633049Y2839960D01*
X633149Y2838627D01*
X633049Y2837294D01*
X632649Y2836360D01*
X632149Y2835560D01*
X631549Y2835027D01*
X630749Y2834627D01*
X628749D01*
G01X645049D02*
Y2842627D01*
X648849D01*
G01X647449Y2838760D02*
X645049D01*
G01X653749Y2842627D02*
X656149D01*
G01X654949D02*
Y2834627D01*
G01X653749D02*
X656149D01*
G01X660949Y2842627D02*
Y2834627D01*
X664949D01*
G01X672949D02*
X668949D01*
Y2842627D01*
X672949D01*
G01X671349Y2838760D02*
X668949D01*
G01X679449Y2831960D02*
X680449Y2833294D01*
X680949Y2834627D01*
Y2839960D01*
X680449Y2841294D01*
X679449Y2842627D01*
G01X-67251Y2819627D02*
Y2827627D01*
X-65251D01*
X-64451Y2827227D01*
X-63851Y2826694D01*
X-63351Y2825894D01*
X-62951Y2824960D01*
X-62851Y2823627D01*
X-62951Y2822294D01*
X-63351Y2821360D01*
X-63851Y2820560D01*
X-64451Y2820027D01*
X-65251Y2819627D01*
X-67251D01*
G01X-57051Y2819360D02*
X-57251Y2819494D01*
Y2819760D01*
X-57051Y2819894D01*
X-56851Y2819760D01*
Y2819494D01*
X-57051Y2819360D01*
G01X-51051Y2819627D02*
Y2827627D01*
X-48651D01*
X-47851Y2827227D01*
X-47251Y2826294D01*
X-47051Y2825227D01*
X-47251Y2824160D01*
X-47751Y2823360D01*
X-48651Y2822960D01*
X-51051D01*
G01X-43051Y2819627D02*
Y2827627D01*
X-40551D01*
X-39751Y2827227D01*
X-39251Y2826694D01*
X-39051Y2825627D01*
X-39251Y2824560D01*
X-39851Y2823894D01*
X-40551Y2823494D01*
X-43051D01*
G01X-40551D02*
X-39051Y2819627D01*
G01X-33051D02*
X-33851Y2819760D01*
X-34551Y2820294D01*
X-35151Y2821094D01*
X-35551Y2822027D01*
X-35751Y2823094D01*
Y2824160D01*
X-35551Y2825227D01*
X-35151Y2826160D01*
X-34551Y2826960D01*
X-33851Y2827494D01*
X-33051Y2827627D01*
X-32251Y2827494D01*
X-31551Y2826960D01*
X-30951Y2826160D01*
X-30551Y2825227D01*
X-30351Y2824160D01*
Y2823094D01*
X-30551Y2822027D01*
X-30951Y2821094D01*
X-31551Y2820294D01*
X-32251Y2819760D01*
X-33051Y2819627D01*
G01X-27551Y2827627D02*
X-25051Y2819627D01*
X-22551Y2827627D01*
G01X-18251D02*
X-15851D01*
G01X-17051D02*
Y2819627D01*
G01X-18251D02*
X-15851D01*
G01X-11251D02*
Y2827627D01*
X-9251D01*
X-8451Y2827227D01*
X-7851Y2826694D01*
X-7351Y2825894D01*
X-6951Y2824960D01*
X-6851Y2823627D01*
X-6951Y2822294D01*
X-7351Y2821360D01*
X-7851Y2820560D01*
X-8451Y2820027D01*
X-9251Y2819627D01*
X-11251D01*
G01X949D02*
X-3051D01*
Y2827627D01*
X949D01*
G01X-651Y2823760D02*
X-3051D01*
G01X13749Y2827627D02*
X16149D01*
G01X14949D02*
Y2819627D01*
G01X13749D02*
X16149D01*
G01X20349D02*
Y2827627D01*
X22949Y2820960D01*
X25549Y2827627D01*
Y2819627D01*
G01X28949D02*
Y2827627D01*
X31349D01*
X32149Y2827227D01*
X32749Y2826294D01*
X32949Y2825227D01*
X32749Y2824160D01*
X32249Y2823360D01*
X31349Y2822960D01*
X28949D01*
G01X40949Y2819627D02*
X36949D01*
Y2827627D01*
X40949D01*
G01X39349Y2823760D02*
X36949D01*
G01X44749Y2819627D02*
Y2827627D01*
X46749D01*
X47549Y2827227D01*
X48149Y2826694D01*
X48649Y2825894D01*
X49049Y2824960D01*
X49149Y2823627D01*
X49049Y2822294D01*
X48649Y2821360D01*
X48149Y2820560D01*
X47549Y2820027D01*
X46749Y2819627D01*
X44749D01*
G01X52449D02*
X54949Y2827627D01*
X57449Y2819627D01*
G01X56549Y2822427D02*
X53349D01*
G01X60649Y2819627D02*
Y2827627D01*
X65249Y2819627D01*
Y2827627D01*
G01X73149Y2826960D02*
X72549Y2827360D01*
X71849Y2827627D01*
X71049D01*
X70149Y2827227D01*
X69449Y2826560D01*
X68949Y2825760D01*
X68549Y2824427D01*
X68449Y2823227D01*
X68649Y2822027D01*
X68949Y2821227D01*
X69549Y2820427D01*
X70249Y2819894D01*
X70949Y2819627D01*
X71649D01*
X72349Y2819894D01*
X72949Y2820294D01*
X73449Y2820827D01*
G01X80949Y2819627D02*
X76949D01*
Y2827627D01*
X80949D01*
G01X79349Y2823760D02*
X76949D01*
G01X97149Y2826960D02*
X96549Y2827360D01*
X95849Y2827627D01*
X95049D01*
X94149Y2827227D01*
X93449Y2826560D01*
X92949Y2825760D01*
X92549Y2824427D01*
X92449Y2823227D01*
X92649Y2822027D01*
X92949Y2821227D01*
X93549Y2820427D01*
X94249Y2819894D01*
X94949Y2819627D01*
X95649D01*
X96349Y2819894D01*
X96949Y2820294D01*
X97449Y2820827D01*
G01X102949Y2819627D02*
X102149Y2819760D01*
X101449Y2820294D01*
X100849Y2821094D01*
X100449Y2822027D01*
X100249Y2823094D01*
Y2824160D01*
X100449Y2825227D01*
X100849Y2826160D01*
X101449Y2826960D01*
X102149Y2827494D01*
X102949Y2827627D01*
X103749Y2827494D01*
X104449Y2826960D01*
X105049Y2826160D01*
X105449Y2825227D01*
X105649Y2824160D01*
Y2823094D01*
X105449Y2822027D01*
X105049Y2821094D01*
X104449Y2820294D01*
X103749Y2819760D01*
X102949Y2819627D01*
G01X108749Y2827627D02*
Y2821894D01*
X109149Y2820693D01*
X109949Y2819894D01*
X110949Y2819627D01*
X111949Y2819894D01*
X112749Y2820693D01*
X113149Y2821894D01*
Y2827627D01*
G01X116949Y2819627D02*
Y2827627D01*
X119349D01*
X120149Y2827227D01*
X120749Y2826294D01*
X120949Y2825227D01*
X120749Y2824160D01*
X120249Y2823360D01*
X119349Y2822960D01*
X116949D01*
G01X126949Y2819627D02*
X126149Y2819760D01*
X125449Y2820294D01*
X124849Y2821094D01*
X124449Y2822027D01*
X124249Y2823094D01*
Y2824160D01*
X124449Y2825227D01*
X124849Y2826160D01*
X125449Y2826960D01*
X126149Y2827494D01*
X126949Y2827627D01*
X127749Y2827494D01*
X128449Y2826960D01*
X129049Y2826160D01*
X129449Y2825227D01*
X129649Y2824160D01*
Y2823094D01*
X129449Y2822027D01*
X129049Y2821094D01*
X128449Y2820294D01*
X127749Y2819760D01*
X126949Y2819627D01*
G01X132649D02*
Y2827627D01*
X137249Y2819627D01*
Y2827627D01*
G01X148449Y2819627D02*
X150949Y2827627D01*
X153449Y2819627D01*
G01X152549Y2822427D02*
X149349D01*
G01X156649Y2819627D02*
Y2827627D01*
X161249Y2819627D01*
Y2827627D01*
G01X164749Y2819627D02*
Y2827627D01*
X166749D01*
X167549Y2827227D01*
X168149Y2826694D01*
X168649Y2825894D01*
X169049Y2824960D01*
X169149Y2823627D01*
X169049Y2822294D01*
X168649Y2821360D01*
X168149Y2820560D01*
X167549Y2820027D01*
X166749Y2819627D01*
X164749D01*
G01X180349D02*
Y2827627D01*
X182949Y2820960D01*
X185549Y2827627D01*
Y2819627D01*
G01X192949D02*
X188949D01*
Y2827627D01*
X192949D01*
G01X191349Y2823760D02*
X188949D01*
G01X196449Y2819627D02*
X198949Y2827627D01*
X201449Y2819627D01*
G01X200549Y2822427D02*
X197349D01*
G01X204849Y2820693D02*
X205649Y2820027D01*
X206549Y2819627D01*
X207349D01*
X208149Y2820027D01*
X208749Y2820693D01*
X209049Y2821627D01*
X208849Y2822560D01*
X208349Y2823360D01*
X207449Y2823894D01*
X206249Y2824160D01*
X205549Y2824694D01*
X205249Y2825627D01*
X205449Y2826560D01*
X205949Y2827227D01*
X206649Y2827627D01*
X207349D01*
X208049Y2827360D01*
X208649Y2826694D01*
G01X212749Y2827627D02*
Y2821894D01*
X213149Y2820693D01*
X213949Y2819894D01*
X214949Y2819627D01*
X215949Y2819894D01*
X216749Y2820693D01*
X217149Y2821894D01*
Y2827627D01*
G01X220949Y2819627D02*
Y2827627D01*
X223449D01*
X224249Y2827227D01*
X224749Y2826694D01*
X224949Y2825627D01*
X224749Y2824560D01*
X224149Y2823894D01*
X223449Y2823494D01*
X220949D01*
G01X223449D02*
X224949Y2819627D01*
G01X232949D02*
X228949D01*
Y2827627D01*
X232949D01*
G01X231349Y2823760D02*
X228949D01*
G01X236349Y2819627D02*
Y2827627D01*
X238949Y2820960D01*
X241549Y2827627D01*
Y2819627D01*
G01X248949D02*
X244949D01*
Y2827627D01*
X248949D01*
G01X247349Y2823760D02*
X244949D01*
G01X252649Y2819627D02*
Y2827627D01*
X257249Y2819627D01*
Y2827627D01*
G01X262949D02*
Y2819627D01*
G01X260649Y2827627D02*
X265249D01*
G01X276949Y2819627D02*
Y2827627D01*
X279449D01*
X280249Y2827227D01*
X280749Y2826694D01*
X280949Y2825627D01*
X280749Y2824560D01*
X280149Y2823894D01*
X279449Y2823494D01*
X276949D01*
G01X279449D02*
X280949Y2819627D01*
G01X288949D02*
X284949D01*
Y2827627D01*
X288949D01*
G01X287349Y2823760D02*
X284949D01*
G01X292949Y2819627D02*
Y2827627D01*
X295349D01*
X296149Y2827227D01*
X296749Y2826294D01*
X296949Y2825227D01*
X296749Y2824160D01*
X296249Y2823360D01*
X295349Y2822960D01*
X292949D01*
G01X302949Y2819627D02*
X302149Y2819760D01*
X301449Y2820294D01*
X300849Y2821094D01*
X300449Y2822027D01*
X300249Y2823094D01*
Y2824160D01*
X300449Y2825227D01*
X300849Y2826160D01*
X301449Y2826960D01*
X302149Y2827494D01*
X302949Y2827627D01*
X303749Y2827494D01*
X304449Y2826960D01*
X305049Y2826160D01*
X305449Y2825227D01*
X305649Y2824160D01*
Y2823094D01*
X305449Y2822027D01*
X305049Y2821094D01*
X304449Y2820294D01*
X303749Y2819760D01*
X302949Y2819627D01*
G01X308949D02*
Y2827627D01*
X311449D01*
X312249Y2827227D01*
X312749Y2826694D01*
X312949Y2825627D01*
X312749Y2824560D01*
X312149Y2823894D01*
X311449Y2823494D01*
X308949D01*
G01X311449D02*
X312949Y2819627D01*
G01X318949Y2827627D02*
Y2819627D01*
G01X316649Y2827627D02*
X321249D01*
G01X-64251Y2853894D02*
X-63851Y2854294D01*
X-63551Y2854960D01*
X-63351Y2855894D01*
X-63551Y2856694D01*
X-63951Y2857227D01*
X-64651Y2857627D01*
X-67351D01*
Y2849627D01*
X-64051D01*
X-63351Y2850160D01*
X-62951Y2850960D01*
X-62751Y2851894D01*
X-62951Y2852827D01*
X-63551Y2853627D01*
X-64251Y2853894D01*
X-67351D01*
G01X-57051Y2849360D02*
X-57251Y2849494D01*
Y2849760D01*
X-57051Y2849894D01*
X-56851Y2849760D01*
Y2849494D01*
X-57051Y2849360D01*
G01X-51551Y2849627D02*
X-49051Y2857627D01*
X-46551Y2849627D01*
G01X-47451Y2852427D02*
X-50651D01*
G01X-43051Y2857627D02*
Y2849627D01*
X-39051D01*
G01X-35051Y2857627D02*
Y2849627D01*
X-31051D01*
G01X-19551Y2857627D02*
X-17051Y2849627D01*
X-14551Y2857627D01*
G01X-10251D02*
X-7851D01*
G01X-9051D02*
Y2849627D01*
G01X-10251D02*
X-7851D01*
G01X-3551D02*
X-1051Y2857627D01*
X1449Y2849627D01*
G01X549Y2852427D02*
X-2651D01*
G01X4849Y2850693D02*
X5649Y2850027D01*
X6549Y2849627D01*
X7349D01*
X8149Y2850027D01*
X8749Y2850693D01*
X9049Y2851627D01*
X8849Y2852560D01*
X8349Y2853360D01*
X7449Y2853894D01*
X6249Y2854160D01*
X5549Y2854694D01*
X5249Y2855627D01*
X5449Y2856560D01*
X5949Y2857227D01*
X6649Y2857627D01*
X7349D01*
X8049Y2857360D01*
X8649Y2856694D01*
G01X20949Y2849627D02*
Y2857627D01*
X23349D01*
X24149Y2857227D01*
X24749Y2856294D01*
X24949Y2855227D01*
X24749Y2854160D01*
X24249Y2853360D01*
X23349Y2852960D01*
X20949D01*
G01X28949Y2857627D02*
Y2849627D01*
X32949D01*
G01X36749Y2857627D02*
Y2851894D01*
X37149Y2850693D01*
X37949Y2849894D01*
X38949Y2849627D01*
X39949Y2849894D01*
X40749Y2850693D01*
X41149Y2851894D01*
Y2857627D01*
G01X47549Y2853627D02*
X49549D01*
Y2851227D01*
X48949Y2850427D01*
X48249Y2849894D01*
X47249Y2849627D01*
X46249Y2849894D01*
X45549Y2850427D01*
X44949Y2851227D01*
X44549Y2852160D01*
X44349Y2853227D01*
Y2854160D01*
X44549Y2854960D01*
X44949Y2855894D01*
X45549Y2856694D01*
X46149Y2857227D01*
X46949Y2857627D01*
X47649D01*
X48449Y2857360D01*
X49049Y2856827D01*
G01X55549Y2853627D02*
X57549D01*
Y2851227D01*
X56949Y2850427D01*
X56249Y2849894D01*
X55249Y2849627D01*
X54249Y2849894D01*
X53549Y2850427D01*
X52949Y2851227D01*
X52549Y2852160D01*
X52349Y2853227D01*
Y2854160D01*
X52549Y2854960D01*
X52949Y2855894D01*
X53549Y2856694D01*
X54149Y2857227D01*
X54949Y2857627D01*
X55649D01*
X56449Y2857360D01*
X57049Y2856827D01*
G01X64949Y2849627D02*
X60949D01*
Y2857627D01*
X64949D01*
G01X63349Y2853760D02*
X60949D01*
G01X68749Y2849627D02*
Y2857627D01*
X70749D01*
X71549Y2857227D01*
X72149Y2856694D01*
X72649Y2855894D01*
X73049Y2854960D01*
X73149Y2853627D01*
X73049Y2852294D01*
X72649Y2851360D01*
X72149Y2850560D01*
X71549Y2850027D01*
X70749Y2849627D01*
X68749D01*
G01X88949D02*
X84949D01*
Y2857627D01*
X88949D01*
G01X87349Y2853760D02*
X84949D01*
G01X92849Y2849627D02*
X97049Y2857627D01*
G01X92849D02*
X97049Y2849627D01*
G01X105149Y2856960D02*
X104549Y2857360D01*
X103849Y2857627D01*
X103049D01*
X102149Y2857227D01*
X101449Y2856560D01*
X100949Y2855760D01*
X100549Y2854427D01*
X100449Y2853227D01*
X100649Y2852027D01*
X100949Y2851227D01*
X101549Y2850427D01*
X102249Y2849894D01*
X102949Y2849627D01*
X103649D01*
X104349Y2849894D01*
X104949Y2850294D01*
X105449Y2850827D01*
G01X112949Y2849627D02*
X108949D01*
Y2857627D01*
X112949D01*
G01X111349Y2853760D02*
X108949D01*
G01X116949Y2849627D02*
Y2857627D01*
X119349D01*
X120149Y2857227D01*
X120749Y2856294D01*
X120949Y2855227D01*
X120749Y2854160D01*
X120249Y2853360D01*
X119349Y2852960D01*
X116949D01*
G01X126949Y2857627D02*
Y2849627D01*
G01X124649Y2857627D02*
X129249D01*
G01X141049Y2849627D02*
Y2857627D01*
X144849D01*
G01X143449Y2853760D02*
X141049D01*
G01X150949Y2849627D02*
X150149Y2849760D01*
X149449Y2850294D01*
X148849Y2851094D01*
X148449Y2852027D01*
X148249Y2853094D01*
Y2854160D01*
X148449Y2855227D01*
X148849Y2856160D01*
X149449Y2856960D01*
X150149Y2857494D01*
X150949Y2857627D01*
X151749Y2857494D01*
X152449Y2856960D01*
X153049Y2856160D01*
X153449Y2855227D01*
X153649Y2854160D01*
Y2853094D01*
X153449Y2852027D01*
X153049Y2851094D01*
X152449Y2850294D01*
X151749Y2849760D01*
X150949Y2849627D01*
G01X156949D02*
Y2857627D01*
X159449D01*
X160249Y2857227D01*
X160749Y2856694D01*
X160949Y2855627D01*
X160749Y2854560D01*
X160149Y2853894D01*
X159449Y2853494D01*
X156949D01*
G01X159449D02*
X160949Y2849627D01*
G01X-67551Y2864627D02*
X-65051Y2872627D01*
X-62551Y2864627D01*
G01X-63451Y2867427D02*
X-66651D01*
G01X-57051Y2864360D02*
X-57251Y2864494D01*
Y2864760D01*
X-57051Y2864894D01*
X-56851Y2864760D01*
Y2864494D01*
X-57051Y2864360D01*
G01X-51551Y2872627D02*
X-49051Y2864627D01*
X-46551Y2872627D01*
G01X-42251D02*
X-39851D01*
G01X-41051D02*
Y2864627D01*
G01X-42251D02*
X-39851D01*
G01X-35551D02*
X-33051Y2872627D01*
X-30551Y2864627D01*
G01X-31451Y2867427D02*
X-34651D01*
G01X-17051Y2872627D02*
Y2864627D01*
G01X-19351Y2872627D02*
X-14751D01*
G01X-7051Y2864627D02*
X-11051D01*
Y2872627D01*
X-7051D01*
G01X-8651Y2868760D02*
X-11051D01*
G01X-3551Y2864627D02*
X-1051Y2872627D01*
X1449Y2864627D01*
G01X549Y2867427D02*
X-2651D01*
G01X4949Y2864627D02*
Y2872627D01*
X7449D01*
X8249Y2872227D01*
X8749Y2871694D01*
X8949Y2870627D01*
X8749Y2869560D01*
X8149Y2868894D01*
X7449Y2868494D01*
X4949D01*
G01X7449D02*
X8949Y2864627D01*
G01X20749D02*
Y2872627D01*
X22749D01*
X23549Y2872227D01*
X24149Y2871694D01*
X24649Y2870894D01*
X25049Y2869960D01*
X25149Y2868627D01*
X25049Y2867294D01*
X24649Y2866360D01*
X24149Y2865560D01*
X23549Y2865027D01*
X22749Y2864627D01*
X20749D01*
G01X28949D02*
Y2872627D01*
X31449D01*
X32249Y2872227D01*
X32749Y2871694D01*
X32949Y2870627D01*
X32749Y2869560D01*
X32149Y2868894D01*
X31449Y2868494D01*
X28949D01*
G01X31449D02*
X32949Y2864627D01*
G01X38949D02*
X38149Y2864760D01*
X37449Y2865294D01*
X36849Y2866094D01*
X36449Y2867027D01*
X36249Y2868094D01*
Y2869160D01*
X36449Y2870227D01*
X36849Y2871160D01*
X37449Y2871960D01*
X38149Y2872494D01*
X38949Y2872627D01*
X39749Y2872494D01*
X40449Y2871960D01*
X41049Y2871160D01*
X41449Y2870227D01*
X41649Y2869160D01*
Y2868094D01*
X41449Y2867027D01*
X41049Y2866094D01*
X40449Y2865294D01*
X39749Y2864760D01*
X38949Y2864627D01*
G01X44949D02*
Y2872627D01*
X47349D01*
X48149Y2872227D01*
X48749Y2871294D01*
X48949Y2870227D01*
X48749Y2869160D01*
X48249Y2868360D01*
X47349Y2867960D01*
X44949D01*
G01X62449Y2861960D02*
X61449Y2863294D01*
X60949Y2864627D01*
Y2869960D01*
X61449Y2871294D01*
X62449Y2872627D01*
G01X69049Y2864627D02*
Y2872627D01*
X72849D01*
G01X71449Y2868760D02*
X69049D01*
G01X78949Y2864627D02*
X78149Y2864760D01*
X77449Y2865294D01*
X76849Y2866094D01*
X76449Y2867027D01*
X76249Y2868094D01*
Y2869160D01*
X76449Y2870227D01*
X76849Y2871160D01*
X77449Y2871960D01*
X78149Y2872494D01*
X78949Y2872627D01*
X79749Y2872494D01*
X80449Y2871960D01*
X81049Y2871160D01*
X81449Y2870227D01*
X81649Y2869160D01*
Y2868094D01*
X81449Y2867027D01*
X81049Y2866094D01*
X80449Y2865294D01*
X79749Y2864760D01*
X78949Y2864627D01*
G01X84949D02*
Y2872627D01*
X87449D01*
X88249Y2872227D01*
X88749Y2871694D01*
X88949Y2870627D01*
X88749Y2869560D01*
X88149Y2868894D01*
X87449Y2868494D01*
X84949D01*
G01X87449D02*
X88949Y2864627D01*
G01X100449D02*
X102949Y2872627D01*
X105449Y2864627D01*
G01X104549Y2867427D02*
X101349D01*
G01X108949Y2872627D02*
Y2864627D01*
X112949D01*
G01X116949Y2872627D02*
Y2864627D01*
X120949D01*
G01X132449Y2872627D02*
X134949Y2864627D01*
X137449Y2872627D01*
G01X141749D02*
X144149D01*
G01X142949D02*
Y2864627D01*
G01X141749D02*
X144149D01*
G01X148449D02*
X150949Y2872627D01*
X153449Y2864627D01*
G01X152549Y2867427D02*
X149349D01*
G01X156849Y2865693D02*
X157649Y2865027D01*
X158549Y2864627D01*
X159349D01*
X160149Y2865027D01*
X160749Y2865693D01*
X161049Y2866627D01*
X160849Y2867560D01*
X160349Y2868360D01*
X159449Y2868894D01*
X158249Y2869160D01*
X157549Y2869694D01*
X157249Y2870627D01*
X157449Y2871560D01*
X157949Y2872227D01*
X158649Y2872627D01*
X159349D01*
X160049Y2872360D01*
X160649Y2871694D01*
G01X172449Y2864627D02*
X174949Y2872627D01*
X177449Y2864627D01*
G01X176549Y2867427D02*
X173349D01*
G01X180649Y2864627D02*
Y2872627D01*
X185249Y2864627D01*
Y2872627D01*
G01X188749Y2864627D02*
Y2872627D01*
X190749D01*
X191549Y2872227D01*
X192149Y2871694D01*
X192649Y2870894D01*
X193049Y2869960D01*
X193149Y2868627D01*
X193049Y2867294D01*
X192649Y2866360D01*
X192149Y2865560D01*
X191549Y2865027D01*
X190749Y2864627D01*
X188749D01*
G01X204949D02*
Y2872627D01*
X207349D01*
X208149Y2872227D01*
X208749Y2871294D01*
X208949Y2870227D01*
X208749Y2869160D01*
X208249Y2868360D01*
X207349Y2867960D01*
X204949D01*
G01X213749Y2872627D02*
X216149D01*
G01X214949D02*
Y2864627D01*
G01X213749D02*
X216149D01*
G01X220649D02*
Y2872627D01*
X225249Y2864627D01*
Y2872627D01*
G01X228849Y2865693D02*
X229649Y2865027D01*
X230549Y2864627D01*
X231349D01*
X232149Y2865027D01*
X232749Y2865693D01*
X233049Y2866627D01*
X232849Y2867560D01*
X232349Y2868360D01*
X231449Y2868894D01*
X230249Y2869160D01*
X229549Y2869694D01*
X229249Y2870627D01*
X229449Y2871560D01*
X229949Y2872227D01*
X230649Y2872627D01*
X231349D01*
X232049Y2872360D01*
X232649Y2871694D01*
G01X239449Y2861960D02*
X240449Y2863294D01*
X240949Y2864627D01*
Y2869960D01*
X240449Y2871294D01*
X239449Y2872627D01*
G01X246949Y2864360D02*
X246749Y2864494D01*
Y2864760D01*
X246949Y2864894D01*
X247149Y2864760D01*
Y2864494D01*
X246949Y2864360D01*
G01X-85251Y2881227D02*
X-84651Y2880294D01*
X-83851Y2879760D01*
X-82951Y2879627D01*
X-82151Y2879760D01*
X-81351Y2880427D01*
X-80851Y2881227D01*
X-80751Y2882027D01*
X-80951Y2882960D01*
X-81651Y2883627D01*
X-82351Y2883894D01*
X-83251D01*
G01X-82351D02*
X-81751Y2884294D01*
X-81251Y2884960D01*
X-81051Y2885760D01*
X-81251Y2886560D01*
X-81751Y2887227D01*
X-82651Y2887627D01*
X-83551Y2887494D01*
X-84451Y2886960D01*
G01X-75051Y2879360D02*
X-75251Y2879494D01*
Y2879760D01*
X-75051Y2879894D01*
X-74851Y2879760D01*
Y2879494D01*
X-75051Y2879360D01*
G01X-69051Y2879627D02*
Y2887627D01*
X-66651D01*
X-65851Y2887227D01*
X-65251Y2886294D01*
X-65051Y2885227D01*
X-65251Y2884160D01*
X-65751Y2883360D01*
X-66651Y2882960D01*
X-69051D01*
G01X-56851Y2886960D02*
X-57451Y2887360D01*
X-58151Y2887627D01*
X-58951D01*
X-59851Y2887227D01*
X-60551Y2886560D01*
X-61051Y2885760D01*
X-61451Y2884427D01*
X-61551Y2883227D01*
X-61351Y2882027D01*
X-61051Y2881227D01*
X-60451Y2880427D01*
X-59751Y2879894D01*
X-59051Y2879627D01*
X-58351D01*
X-57651Y2879894D01*
X-57051Y2880294D01*
X-56551Y2880827D01*
G01X-50251Y2883894D02*
X-49851Y2884294D01*
X-49551Y2884960D01*
X-49351Y2885894D01*
X-49551Y2886694D01*
X-49951Y2887227D01*
X-50651Y2887627D01*
X-53351D01*
Y2879627D01*
X-50051D01*
X-49351Y2880160D01*
X-48951Y2880960D01*
X-48751Y2881894D01*
X-48951Y2882827D01*
X-49551Y2883627D01*
X-50251Y2883894D01*
X-53351D01*
G01X-37051Y2879627D02*
Y2887627D01*
X-34651D01*
X-33851Y2887227D01*
X-33251Y2886294D01*
X-33051Y2885227D01*
X-33251Y2884160D01*
X-33751Y2883360D01*
X-34651Y2882960D01*
X-37051D01*
G01X-29051Y2879627D02*
Y2887627D01*
X-26551D01*
X-25751Y2887227D01*
X-25251Y2886694D01*
X-25051Y2885627D01*
X-25251Y2884560D01*
X-25851Y2883894D01*
X-26551Y2883494D01*
X-29051D01*
G01X-26551D02*
X-25051Y2879627D01*
G01X-19051D02*
X-19851Y2879760D01*
X-20551Y2880294D01*
X-21151Y2881094D01*
X-21551Y2882027D01*
X-21751Y2883094D01*
Y2884160D01*
X-21551Y2885227D01*
X-21151Y2886160D01*
X-20551Y2886960D01*
X-19851Y2887494D01*
X-19051Y2887627D01*
X-18251Y2887494D01*
X-17551Y2886960D01*
X-16951Y2886160D01*
X-16551Y2885227D01*
X-16351Y2884160D01*
Y2883094D01*
X-16551Y2882027D01*
X-16951Y2881094D01*
X-17551Y2880294D01*
X-18251Y2879760D01*
X-19051Y2879627D01*
G01X-8851Y2886960D02*
X-9451Y2887360D01*
X-10151Y2887627D01*
X-10951D01*
X-11851Y2887227D01*
X-12551Y2886560D01*
X-13051Y2885760D01*
X-13451Y2884427D01*
X-13551Y2883227D01*
X-13351Y2882027D01*
X-13051Y2881227D01*
X-12451Y2880427D01*
X-11751Y2879894D01*
X-11051Y2879627D01*
X-10351D01*
X-9651Y2879894D01*
X-9051Y2880294D01*
X-8551Y2880827D01*
G01X-1051Y2879627D02*
X-5051D01*
Y2887627D01*
X-1051D01*
G01X-2651Y2883760D02*
X-5051D01*
G01X2849Y2880693D02*
X3649Y2880027D01*
X4549Y2879627D01*
X5349D01*
X6149Y2880027D01*
X6749Y2880693D01*
X7049Y2881627D01*
X6849Y2882560D01*
X6349Y2883360D01*
X5449Y2883894D01*
X4249Y2884160D01*
X3549Y2884694D01*
X3249Y2885627D01*
X3449Y2886560D01*
X3949Y2887227D01*
X4649Y2887627D01*
X5349D01*
X6049Y2887360D01*
X6649Y2886694D01*
G01X10849Y2880693D02*
X11649Y2880027D01*
X12549Y2879627D01*
X13349D01*
X14149Y2880027D01*
X14749Y2880693D01*
X15049Y2881627D01*
X14849Y2882560D01*
X14349Y2883360D01*
X13449Y2883894D01*
X12249Y2884160D01*
X11549Y2884694D01*
X11249Y2885627D01*
X11449Y2886560D01*
X11949Y2887227D01*
X12649Y2887627D01*
X13349D01*
X14049Y2887360D01*
X14649Y2886694D01*
G01X20949Y2879360D02*
X20749Y2879494D01*
Y2879760D01*
X20949Y2879894D01*
X21149Y2879760D01*
Y2879494D01*
X20949Y2879360D01*
G01Y2882960D02*
X20749Y2883094D01*
Y2883360D01*
X20949Y2883494D01*
X21149Y2883360D01*
Y2883094D01*
X20949Y2882960D01*
G01X-84951Y2901294D02*
X-84351Y2902094D01*
X-83651Y2902494D01*
X-82851Y2902627D01*
X-81851Y2902360D01*
X-81151Y2901694D01*
X-80951Y2900894D01*
X-81051Y2900093D01*
X-81451Y2899427D01*
X-83451Y2898094D01*
X-84351Y2897160D01*
X-84951Y2895827D01*
X-85151Y2894627D01*
X-80951D01*
G01X-75051Y2894360D02*
X-75251Y2894494D01*
Y2894760D01*
X-75051Y2894894D01*
X-74851Y2894760D01*
Y2894494D01*
X-75051Y2894360D01*
G01X-68951Y2894627D02*
Y2902627D01*
X-65151D01*
G01X-66551Y2898760D02*
X-68951D01*
G01X-61551Y2894627D02*
X-59051Y2902627D01*
X-56551Y2894627D01*
G01X-57451Y2897427D02*
X-60651D01*
G01X-50251Y2898894D02*
X-49851Y2899294D01*
X-49551Y2899960D01*
X-49351Y2900894D01*
X-49551Y2901694D01*
X-49951Y2902227D01*
X-50651Y2902627D01*
X-53351D01*
Y2894627D01*
X-50051D01*
X-49351Y2895160D01*
X-48951Y2895960D01*
X-48751Y2896894D01*
X-48951Y2897827D01*
X-49551Y2898627D01*
X-50251Y2898894D01*
X-53351D01*
G01X-45051Y2894627D02*
Y2902627D01*
X-42551D01*
X-41751Y2902227D01*
X-41251Y2901694D01*
X-41051Y2900627D01*
X-41251Y2899560D01*
X-41851Y2898894D01*
X-42551Y2898494D01*
X-45051D01*
G01X-42551D02*
X-41051Y2894627D01*
G01X-36251Y2902627D02*
X-33851D01*
G01X-35051D02*
Y2894627D01*
G01X-36251D02*
X-33851D01*
G01X-24851Y2901960D02*
X-25451Y2902360D01*
X-26151Y2902627D01*
X-26951D01*
X-27851Y2902227D01*
X-28551Y2901560D01*
X-29051Y2900760D01*
X-29451Y2899427D01*
X-29551Y2898227D01*
X-29351Y2897027D01*
X-29051Y2896227D01*
X-28451Y2895427D01*
X-27751Y2894894D01*
X-27051Y2894627D01*
X-26351D01*
X-25651Y2894894D01*
X-25051Y2895294D01*
X-24551Y2895827D01*
G01X-21551Y2894627D02*
X-19051Y2902627D01*
X-16551Y2894627D01*
G01X-17451Y2897427D02*
X-20651D01*
G01X-11051Y2902627D02*
Y2894627D01*
G01X-13351Y2902627D02*
X-8751D01*
G01X-1051Y2894627D02*
X-5051D01*
Y2902627D01*
X-1051D01*
G01X-2651Y2898760D02*
X-5051D01*
G01X10949Y2894627D02*
Y2902627D01*
X13349D01*
X14149Y2902227D01*
X14749Y2901294D01*
X14949Y2900227D01*
X14749Y2899160D01*
X14249Y2898360D01*
X13349Y2897960D01*
X10949D01*
G01X22949Y2894627D02*
X18949D01*
Y2902627D01*
X22949D01*
G01X21349Y2898760D02*
X18949D01*
G01X26949Y2894627D02*
Y2902627D01*
X29449D01*
X30249Y2902227D01*
X30749Y2901694D01*
X30949Y2900627D01*
X30749Y2899560D01*
X30149Y2898894D01*
X29449Y2898494D01*
X26949D01*
G01X29449D02*
X30949Y2894627D01*
G01X44949D02*
X44149Y2894760D01*
X43449Y2895294D01*
X42849Y2896094D01*
X42449Y2897027D01*
X42249Y2898094D01*
Y2899160D01*
X42449Y2900227D01*
X42849Y2901160D01*
X43449Y2901960D01*
X44149Y2902494D01*
X44949Y2902627D01*
X45749Y2902494D01*
X46449Y2901960D01*
X47049Y2901160D01*
X47449Y2900227D01*
X47649Y2899160D01*
Y2898094D01*
X47449Y2897027D01*
X47049Y2896094D01*
X46449Y2895294D01*
X45749Y2894760D01*
X44949Y2894627D01*
G01X45749Y2896760D02*
X46949Y2894627D01*
G01X50749Y2902627D02*
Y2896894D01*
X51149Y2895693D01*
X51949Y2894894D01*
X52949Y2894627D01*
X53949Y2894894D01*
X54749Y2895693D01*
X55149Y2896894D01*
Y2902627D01*
G01X58449Y2894627D02*
X60949Y2902627D01*
X63449Y2894627D01*
G01X62549Y2897427D02*
X59349D01*
G01X66649Y2894627D02*
Y2902627D01*
X71249Y2894627D01*
Y2902627D01*
G01X76949D02*
Y2894627D01*
G01X74649Y2902627D02*
X79249D01*
G01X82449Y2894627D02*
X84949Y2902627D01*
X87449Y2894627D01*
G01X86549Y2897427D02*
X83349D01*
G01X98949Y2894627D02*
Y2902627D01*
X101349D01*
X102149Y2902227D01*
X102749Y2901294D01*
X102949Y2900227D01*
X102749Y2899160D01*
X102249Y2898360D01*
X101349Y2897960D01*
X98949D01*
G01X111149Y2901960D02*
X110549Y2902360D01*
X109849Y2902627D01*
X109049D01*
X108149Y2902227D01*
X107449Y2901560D01*
X106949Y2900760D01*
X106549Y2899427D01*
X106449Y2898227D01*
X106649Y2897027D01*
X106949Y2896227D01*
X107549Y2895427D01*
X108249Y2894894D01*
X108949Y2894627D01*
X109649D01*
X110349Y2894894D01*
X110949Y2895294D01*
X111449Y2895827D01*
G01X117749Y2898894D02*
X118149Y2899294D01*
X118449Y2899960D01*
X118649Y2900894D01*
X118449Y2901694D01*
X118049Y2902227D01*
X117349Y2902627D01*
X114649D01*
Y2894627D01*
X117949D01*
X118649Y2895160D01*
X119049Y2895960D01*
X119249Y2896894D01*
X119049Y2897827D01*
X118449Y2898627D01*
X117749Y2898894D01*
X114649D01*
G01X130849Y2895693D02*
X131649Y2895027D01*
X132549Y2894627D01*
X133349D01*
X134149Y2895027D01*
X134749Y2895693D01*
X135049Y2896627D01*
X134849Y2897560D01*
X134349Y2898360D01*
X133449Y2898894D01*
X132249Y2899160D01*
X131549Y2899694D01*
X131249Y2900627D01*
X131449Y2901560D01*
X131949Y2902227D01*
X132649Y2902627D01*
X133349D01*
X134049Y2902360D01*
X134649Y2901694D01*
G01X138949Y2894627D02*
Y2902627D01*
X141349D01*
X142149Y2902227D01*
X142749Y2901294D01*
X142949Y2900227D01*
X142749Y2899160D01*
X142249Y2898360D01*
X141349Y2897960D01*
X138949D01*
G01X150949Y2894627D02*
X146949D01*
Y2902627D01*
X150949D01*
G01X149349Y2898760D02*
X146949D01*
G01X159149Y2901960D02*
X158549Y2902360D01*
X157849Y2902627D01*
X157049D01*
X156149Y2902227D01*
X155449Y2901560D01*
X154949Y2900760D01*
X154549Y2899427D01*
X154449Y2898227D01*
X154649Y2897027D01*
X154949Y2896227D01*
X155549Y2895427D01*
X156249Y2894894D01*
X156949Y2894627D01*
X157649D01*
X158349Y2894894D01*
X158949Y2895294D01*
X159449Y2895827D01*
G01X163749Y2902627D02*
X166149D01*
G01X164949D02*
Y2894627D01*
G01X163749D02*
X166149D01*
G01X171049D02*
Y2902627D01*
X174849D01*
G01X173449Y2898760D02*
X171049D01*
G01X179749Y2902627D02*
X182149D01*
G01X180949D02*
Y2894627D01*
G01X179749D02*
X182149D01*
G01X191149Y2901960D02*
X190549Y2902360D01*
X189849Y2902627D01*
X189049D01*
X188149Y2902227D01*
X187449Y2901560D01*
X186949Y2900760D01*
X186549Y2899427D01*
X186449Y2898227D01*
X186649Y2897027D01*
X186949Y2896227D01*
X187549Y2895427D01*
X188249Y2894894D01*
X188949Y2894627D01*
X189649D01*
X190349Y2894894D01*
X190949Y2895294D01*
X191449Y2895827D01*
G01X194449Y2894627D02*
X196949Y2902627D01*
X199449Y2894627D01*
G01X198549Y2897427D02*
X195349D01*
G01X204949Y2902627D02*
Y2894627D01*
G01X202649Y2902627D02*
X207249D01*
G01X211749D02*
X214149D01*
G01X212949D02*
Y2894627D01*
G01X211749D02*
X214149D01*
G01X220949D02*
X220149Y2894760D01*
X219449Y2895294D01*
X218849Y2896094D01*
X218449Y2897027D01*
X218249Y2898094D01*
Y2899160D01*
X218449Y2900227D01*
X218849Y2901160D01*
X219449Y2901960D01*
X220149Y2902494D01*
X220949Y2902627D01*
X221749Y2902494D01*
X222449Y2901960D01*
X223049Y2901160D01*
X223449Y2900227D01*
X223649Y2899160D01*
Y2898094D01*
X223449Y2897027D01*
X223049Y2896094D01*
X222449Y2895294D01*
X221749Y2894760D01*
X220949Y2894627D01*
G01X226649D02*
Y2902627D01*
X231249Y2894627D01*
Y2902627D01*
G01X236949Y2894360D02*
X236749Y2894494D01*
Y2894760D01*
X236949Y2894894D01*
X237149Y2894760D01*
Y2894494D01*
X236949Y2894360D01*
G01X-85351Y2924627D02*
Y2932627D01*
X-80751Y2924627D01*
Y2932627D01*
G01X-75051Y2924627D02*
X-75851Y2924760D01*
X-76551Y2925294D01*
X-77151Y2926094D01*
X-77551Y2927027D01*
X-77751Y2928094D01*
Y2929160D01*
X-77551Y2930227D01*
X-77151Y2931160D01*
X-76551Y2931960D01*
X-75851Y2932494D01*
X-75051Y2932627D01*
X-74251Y2932494D01*
X-73551Y2931960D01*
X-72951Y2931160D01*
X-72551Y2930227D01*
X-72351Y2929160D01*
Y2928094D01*
X-72551Y2927027D01*
X-72951Y2926094D01*
X-73551Y2925294D01*
X-74251Y2924760D01*
X-75051Y2924627D01*
G01X-67051Y2932627D02*
Y2924627D01*
G01X-69351Y2932627D02*
X-64751D01*
G01X-57051Y2924627D02*
X-61051D01*
Y2932627D01*
X-57051D01*
G01X-58651Y2928760D02*
X-61051D01*
G01X-53151Y2925693D02*
X-52351Y2925027D01*
X-51451Y2924627D01*
X-50651D01*
X-49851Y2925027D01*
X-49251Y2925693D01*
X-48951Y2926627D01*
X-49151Y2927560D01*
X-49651Y2928360D01*
X-50551Y2928894D01*
X-51751Y2929160D01*
X-52451Y2929694D01*
X-52751Y2930627D01*
X-52551Y2931560D01*
X-52051Y2932227D01*
X-51351Y2932627D01*
X-50651D01*
X-49951Y2932360D01*
X-49351Y2931694D01*
G01X-43051Y2924360D02*
X-43251Y2924494D01*
Y2924760D01*
X-43051Y2924894D01*
X-42851Y2924760D01*
Y2924494D01*
X-43051Y2924360D01*
G01Y2927960D02*
X-43251Y2928094D01*
Y2928360D01*
X-43051Y2928494D01*
X-42851Y2928360D01*
Y2928094D01*
X-43051Y2927960D01*
G01X-35551Y2921960D02*
X-36551Y2923294D01*
X-37051Y2924627D01*
Y2929960D01*
X-36551Y2931294D01*
X-35551Y2932627D01*
G01X-29251D02*
Y2926894D01*
X-28851Y2925693D01*
X-28051Y2924894D01*
X-27051Y2924627D01*
X-26051Y2924894D01*
X-25251Y2925693D01*
X-24851Y2926894D01*
Y2932627D01*
G01X-21351Y2924627D02*
Y2932627D01*
X-16751Y2924627D01*
Y2932627D01*
G01X-13051D02*
Y2924627D01*
X-9051D01*
G01X-1051D02*
X-5051D01*
Y2932627D01*
X-1051D01*
G01X-2651Y2928760D02*
X-5051D01*
G01X2849Y2925693D02*
X3649Y2925027D01*
X4549Y2924627D01*
X5349D01*
X6149Y2925027D01*
X6749Y2925693D01*
X7049Y2926627D01*
X6849Y2927560D01*
X6349Y2928360D01*
X5449Y2928894D01*
X4249Y2929160D01*
X3549Y2929694D01*
X3249Y2930627D01*
X3449Y2931560D01*
X3949Y2932227D01*
X4649Y2932627D01*
X5349D01*
X6049Y2932360D01*
X6649Y2931694D01*
G01X10849Y2925693D02*
X11649Y2925027D01*
X12549Y2924627D01*
X13349D01*
X14149Y2925027D01*
X14749Y2925693D01*
X15049Y2926627D01*
X14849Y2927560D01*
X14349Y2928360D01*
X13449Y2928894D01*
X12249Y2929160D01*
X11549Y2929694D01*
X11249Y2930627D01*
X11449Y2931560D01*
X11949Y2932227D01*
X12649Y2932627D01*
X13349D01*
X14049Y2932360D01*
X14649Y2931694D01*
G01X28949Y2924627D02*
X28149Y2924760D01*
X27449Y2925294D01*
X26849Y2926094D01*
X26449Y2927027D01*
X26249Y2928094D01*
Y2929160D01*
X26449Y2930227D01*
X26849Y2931160D01*
X27449Y2931960D01*
X28149Y2932494D01*
X28949Y2932627D01*
X29749Y2932494D01*
X30449Y2931960D01*
X31049Y2931160D01*
X31449Y2930227D01*
X31649Y2929160D01*
Y2928094D01*
X31449Y2927027D01*
X31049Y2926094D01*
X30449Y2925294D01*
X29749Y2924760D01*
X28949Y2924627D01*
G01X36949Y2932627D02*
Y2924627D01*
G01X34649Y2932627D02*
X39249D01*
G01X42849Y2924627D02*
Y2932627D01*
G01X47049D02*
Y2924627D01*
G01Y2928627D02*
X42849D01*
G01X54949Y2924627D02*
X50949D01*
Y2932627D01*
X54949D01*
G01X53349Y2928760D02*
X50949D01*
G01X58949Y2924627D02*
Y2932627D01*
X61449D01*
X62249Y2932227D01*
X62749Y2931694D01*
X62949Y2930627D01*
X62749Y2929560D01*
X62149Y2928894D01*
X61449Y2928494D01*
X58949D01*
G01X61449D02*
X62949Y2924627D01*
G01X65949Y2932627D02*
X67349Y2924627D01*
X68949Y2932627D01*
X70549Y2924627D01*
X71949Y2932627D01*
G01X75749D02*
X78149D01*
G01X76949D02*
Y2924627D01*
G01X75749D02*
X78149D01*
G01X82849Y2925693D02*
X83649Y2925027D01*
X84549Y2924627D01*
X85349D01*
X86149Y2925027D01*
X86749Y2925693D01*
X87049Y2926627D01*
X86849Y2927560D01*
X86349Y2928360D01*
X85449Y2928894D01*
X84249Y2929160D01*
X83549Y2929694D01*
X83249Y2930627D01*
X83449Y2931560D01*
X83949Y2932227D01*
X84649Y2932627D01*
X85349D01*
X86049Y2932360D01*
X86649Y2931694D01*
G01X94949Y2924627D02*
X90949D01*
Y2932627D01*
X94949D01*
G01X93349Y2928760D02*
X90949D01*
G01X106849Y2925693D02*
X107649Y2925027D01*
X108549Y2924627D01*
X109349D01*
X110149Y2925027D01*
X110749Y2925693D01*
X111049Y2926627D01*
X110849Y2927560D01*
X110349Y2928360D01*
X109449Y2928894D01*
X108249Y2929160D01*
X107549Y2929694D01*
X107249Y2930627D01*
X107449Y2931560D01*
X107949Y2932227D01*
X108649Y2932627D01*
X109349D01*
X110049Y2932360D01*
X110649Y2931694D01*
G01X114949Y2924627D02*
Y2932627D01*
X117349D01*
X118149Y2932227D01*
X118749Y2931294D01*
X118949Y2930227D01*
X118749Y2929160D01*
X118249Y2928360D01*
X117349Y2927960D01*
X114949D01*
G01X126949Y2924627D02*
X122949D01*
Y2932627D01*
X126949D01*
G01X125349Y2928760D02*
X122949D01*
G01X135149Y2931960D02*
X134549Y2932360D01*
X133849Y2932627D01*
X133049D01*
X132149Y2932227D01*
X131449Y2931560D01*
X130949Y2930760D01*
X130549Y2929427D01*
X130449Y2928227D01*
X130649Y2927027D01*
X130949Y2926227D01*
X131549Y2925427D01*
X132249Y2924894D01*
X132949Y2924627D01*
X133649D01*
X134349Y2924894D01*
X134949Y2925294D01*
X135449Y2925827D01*
G01X139749Y2932627D02*
X142149D01*
G01X140949D02*
Y2924627D01*
G01X139749D02*
X142149D01*
G01X147049D02*
Y2932627D01*
X150849D01*
G01X149449Y2928760D02*
X147049D01*
G01X155749Y2932627D02*
X158149D01*
G01X156949D02*
Y2924627D01*
G01X155749D02*
X158149D01*
G01X166949D02*
X162949D01*
Y2932627D01*
X166949D01*
G01X165349Y2928760D02*
X162949D01*
G01X170749Y2924627D02*
Y2932627D01*
X172749D01*
X173549Y2932227D01*
X174149Y2931694D01*
X174649Y2930894D01*
X175049Y2929960D01*
X175149Y2928627D01*
X175049Y2927294D01*
X174649Y2926360D01*
X174149Y2925560D01*
X173549Y2925027D01*
X172749Y2924627D01*
X170749D01*
G01X187749Y2932627D02*
X190149D01*
G01X188949D02*
Y2924627D01*
G01X187749D02*
X190149D01*
G01X194649D02*
Y2932627D01*
X199249Y2924627D01*
Y2932627D01*
G01X212949D02*
Y2924627D01*
G01X210649Y2932627D02*
X215249D01*
G01X219049Y2927960D02*
X219749Y2928894D01*
X220349Y2929427D01*
X221149Y2929694D01*
X221849Y2929427D01*
X222349Y2928894D01*
X222749Y2928094D01*
X222849Y2927160D01*
X222749Y2926360D01*
X222349Y2925560D01*
X221749Y2924894D01*
X221049Y2924627D01*
X220249Y2924894D01*
X219549Y2925693D01*
X219149Y2926894D01*
X219049Y2928227D01*
X219249Y2929960D01*
X219549Y2930894D01*
X220049Y2931827D01*
X220749Y2932494D01*
X221449Y2932627D01*
X222149Y2932360D01*
X222649Y2931694D01*
G01X226349Y2924627D02*
Y2932627D01*
X228949Y2925960D01*
X231549Y2932627D01*
Y2924627D01*
G01X233949Y2921960D02*
X239949D01*
G01X242949Y2924627D02*
Y2932627D01*
X245349D01*
X246149Y2932227D01*
X246749Y2931294D01*
X246949Y2930227D01*
X246749Y2929160D01*
X246249Y2928360D01*
X245349Y2927960D01*
X242949D01*
G01X250749Y2924627D02*
Y2932627D01*
X252749D01*
X253549Y2932227D01*
X254149Y2931694D01*
X254649Y2930894D01*
X255049Y2929960D01*
X255149Y2928627D01*
X255049Y2927294D01*
X254649Y2926360D01*
X254149Y2925560D01*
X253549Y2925027D01*
X252749Y2924627D01*
X250749D01*
G01X261749Y2928894D02*
X262149Y2929294D01*
X262449Y2929960D01*
X262649Y2930894D01*
X262449Y2931694D01*
X262049Y2932227D01*
X261349Y2932627D01*
X258649D01*
Y2924627D01*
X261949D01*
X262649Y2925160D01*
X263049Y2925960D01*
X263249Y2926894D01*
X263049Y2927827D01*
X262449Y2928627D01*
X261749Y2928894D01*
X258649D01*
G01X265949Y2921960D02*
X271949D01*
G01X274749Y2924627D02*
Y2932627D01*
X276749D01*
X277549Y2932227D01*
X278149Y2931694D01*
X278649Y2930894D01*
X279049Y2929960D01*
X279149Y2928627D01*
X279049Y2927294D01*
X278649Y2926360D01*
X278149Y2925560D01*
X277549Y2925027D01*
X276749Y2924627D01*
X274749D01*
G01X284949Y2924360D02*
X284749Y2924494D01*
Y2924760D01*
X284949Y2924894D01*
X285149Y2924760D01*
Y2924494D01*
X284949Y2924360D01*
G01X290749Y2924627D02*
Y2932627D01*
X292749D01*
X293549Y2932227D01*
X294149Y2931694D01*
X294649Y2930894D01*
X295049Y2929960D01*
X295149Y2928627D01*
X295049Y2927294D01*
X294649Y2926360D01*
X294149Y2925560D01*
X293549Y2925027D01*
X292749Y2924627D01*
X290749D01*
G01X300949D02*
X300149Y2924760D01*
X299449Y2925294D01*
X298849Y2926094D01*
X298449Y2927027D01*
X298249Y2928094D01*
Y2929160D01*
X298449Y2930227D01*
X298849Y2931160D01*
X299449Y2931960D01*
X300149Y2932494D01*
X300949Y2932627D01*
X301749Y2932494D01*
X302449Y2931960D01*
X303049Y2931160D01*
X303449Y2930227D01*
X303649Y2929160D01*
Y2928094D01*
X303449Y2927027D01*
X303049Y2926094D01*
X302449Y2925294D01*
X301749Y2924760D01*
X300949Y2924627D01*
G01X311149Y2931960D02*
X310549Y2932360D01*
X309849Y2932627D01*
X309049D01*
X308149Y2932227D01*
X307449Y2931560D01*
X306949Y2930760D01*
X306549Y2929427D01*
X306449Y2928227D01*
X306649Y2927027D01*
X306949Y2926227D01*
X307549Y2925427D01*
X308249Y2924894D01*
X308949Y2924627D01*
X309649D01*
X310349Y2924894D01*
X310949Y2925294D01*
X311449Y2925827D01*
G01X317449Y2921960D02*
X318449Y2923294D01*
X318949Y2924627D01*
Y2929960D01*
X318449Y2931294D01*
X317449Y2932627D01*
G01X-83051Y2909627D02*
Y2917627D01*
X-84251Y2916027D01*
G01Y2909627D02*
X-81851D01*
G01X-75051Y2909360D02*
X-75251Y2909494D01*
Y2909760D01*
X-75051Y2909894D01*
X-74851Y2909760D01*
Y2909494D01*
X-75051Y2909360D01*
G01X-69051Y2909627D02*
Y2917627D01*
X-66651D01*
X-65851Y2917227D01*
X-65251Y2916294D01*
X-65051Y2915227D01*
X-65251Y2914160D01*
X-65751Y2913360D01*
X-66651Y2912960D01*
X-69051D01*
G01X-56851Y2916960D02*
X-57451Y2917360D01*
X-58151Y2917627D01*
X-58951D01*
X-59851Y2917227D01*
X-60551Y2916560D01*
X-61051Y2915760D01*
X-61451Y2914427D01*
X-61551Y2913227D01*
X-61351Y2912027D01*
X-61051Y2911227D01*
X-60451Y2910427D01*
X-59751Y2909894D01*
X-59051Y2909627D01*
X-58351D01*
X-57651Y2909894D01*
X-57051Y2910294D01*
X-56551Y2910827D01*
G01X-50251Y2913894D02*
X-49851Y2914294D01*
X-49551Y2914960D01*
X-49351Y2915894D01*
X-49551Y2916694D01*
X-49951Y2917227D01*
X-50651Y2917627D01*
X-53351D01*
Y2909627D01*
X-50051D01*
X-49351Y2910160D01*
X-48951Y2910960D01*
X-48751Y2911894D01*
X-48951Y2912827D01*
X-49551Y2913627D01*
X-50251Y2913894D01*
X-53351D01*
G01X-37151Y2910693D02*
X-36351Y2910027D01*
X-35451Y2909627D01*
X-34651D01*
X-33851Y2910027D01*
X-33251Y2910693D01*
X-32951Y2911627D01*
X-33151Y2912560D01*
X-33651Y2913360D01*
X-34551Y2913894D01*
X-35751Y2914160D01*
X-36451Y2914694D01*
X-36751Y2915627D01*
X-36551Y2916560D01*
X-36051Y2917227D01*
X-35351Y2917627D01*
X-34651D01*
X-33951Y2917360D01*
X-33351Y2916694D01*
G01X-28251Y2917627D02*
X-25851D01*
G01X-27051D02*
Y2909627D01*
G01X-28251D02*
X-25851D01*
G01X-20951Y2917627D02*
X-17151D01*
X-20951Y2909627D01*
X-17151D01*
G01X-9051D02*
X-13051D01*
Y2917627D01*
X-9051D01*
G01X-10651Y2913760D02*
X-13051D01*
G01X20949Y2909360D02*
X20749Y2909494D01*
Y2909760D01*
X20949Y2909894D01*
X21149Y2909760D01*
Y2909494D01*
X20949Y2909360D01*
G01Y2912960D02*
X20749Y2913094D01*
Y2913360D01*
X20949Y2913494D01*
X21149Y2913360D01*
Y2913094D01*
X20949Y2912960D01*
G01X35049Y2909627D02*
Y2917627D01*
X38849D01*
G01X37449Y2913760D02*
X35049D01*
G01X44949Y2909627D02*
X44149Y2909760D01*
X43449Y2910294D01*
X42849Y2911094D01*
X42449Y2912027D01*
X42249Y2913094D01*
Y2914160D01*
X42449Y2915227D01*
X42849Y2916160D01*
X43449Y2916960D01*
X44149Y2917494D01*
X44949Y2917627D01*
X45749Y2917494D01*
X46449Y2916960D01*
X47049Y2916160D01*
X47449Y2915227D01*
X47649Y2914160D01*
Y2913094D01*
X47449Y2912027D01*
X47049Y2911094D01*
X46449Y2910294D01*
X45749Y2909760D01*
X44949Y2909627D01*
G01X50949Y2917627D02*
Y2909627D01*
X54949D01*
G01X58949Y2917627D02*
Y2909627D01*
X62949D01*
G01X68949D02*
X68149Y2909760D01*
X67449Y2910294D01*
X66849Y2911094D01*
X66449Y2912027D01*
X66249Y2913094D01*
Y2914160D01*
X66449Y2915227D01*
X66849Y2916160D01*
X67449Y2916960D01*
X68149Y2917494D01*
X68949Y2917627D01*
X69749Y2917494D01*
X70449Y2916960D01*
X71049Y2916160D01*
X71449Y2915227D01*
X71649Y2914160D01*
Y2913094D01*
X71449Y2912027D01*
X71049Y2911094D01*
X70449Y2910294D01*
X69749Y2909760D01*
X68949Y2909627D01*
G01X73949Y2917627D02*
X75349Y2909627D01*
X76949Y2917627D01*
X78549Y2909627D01*
X79949Y2917627D01*
G01X93549Y2913627D02*
X95549D01*
Y2911227D01*
X94949Y2910427D01*
X94249Y2909894D01*
X93249Y2909627D01*
X92249Y2909894D01*
X91549Y2910427D01*
X90949Y2911227D01*
X90549Y2912160D01*
X90349Y2913227D01*
Y2914160D01*
X90549Y2914960D01*
X90949Y2915894D01*
X91549Y2916694D01*
X92149Y2917227D01*
X92949Y2917627D01*
X93649D01*
X94449Y2917360D01*
X95049Y2916827D01*
G01X102949Y2909627D02*
X98949D01*
Y2917627D01*
X102949D01*
G01X101349Y2913760D02*
X98949D01*
G01X106949Y2909627D02*
Y2917627D01*
X109449D01*
X110249Y2917227D01*
X110749Y2916694D01*
X110949Y2915627D01*
X110749Y2914560D01*
X110149Y2913894D01*
X109449Y2913494D01*
X106949D01*
G01X109449D02*
X110949Y2909627D01*
G01X117749Y2913894D02*
X118149Y2914294D01*
X118449Y2914960D01*
X118649Y2915894D01*
X118449Y2916694D01*
X118049Y2917227D01*
X117349Y2917627D01*
X114649D01*
Y2909627D01*
X117949D01*
X118649Y2910160D01*
X119049Y2910960D01*
X119249Y2911894D01*
X119049Y2912827D01*
X118449Y2913627D01*
X117749Y2913894D01*
X114649D01*
G01X126949Y2909627D02*
X122949D01*
Y2917627D01*
X126949D01*
G01X125349Y2913760D02*
X122949D01*
G01X130949Y2909627D02*
Y2917627D01*
X133449D01*
X134249Y2917227D01*
X134749Y2916694D01*
X134949Y2915627D01*
X134749Y2914560D01*
X134149Y2913894D01*
X133449Y2913494D01*
X130949D01*
G01X133449D02*
X134949Y2909627D01*
G01X147049D02*
Y2917627D01*
X150849D01*
G01X149449Y2913760D02*
X147049D01*
G01X155749Y2917627D02*
X158149D01*
G01X156949D02*
Y2909627D01*
G01X155749D02*
X158149D01*
G01X162949Y2917627D02*
Y2909627D01*
X166949D01*
G01X174949D02*
X170949D01*
Y2917627D01*
X174949D01*
G01X173349Y2913760D02*
X170949D01*
G01X180249Y2907227D02*
X181649Y2909094D01*
Y2910960D01*
X180249D01*
Y2909094D01*
X181649D01*
G01Y2912294D02*
Y2914160D01*
X180249D01*
Y2912294D01*
X181649D01*
G01X193949Y2917627D02*
X195349Y2909627D01*
X196949Y2917627D01*
X198549Y2909627D01*
X199949Y2917627D01*
G01X203749D02*
X206149D01*
G01X204949D02*
Y2909627D01*
G01X203749D02*
X206149D01*
G01X212949Y2917627D02*
Y2909627D01*
G01X210649Y2917627D02*
X215249D01*
G01X218849Y2909627D02*
Y2917627D01*
G01X223049D02*
Y2909627D01*
G01Y2913627D02*
X218849D01*
G01X236949Y2917627D02*
Y2909627D01*
G01X234649Y2917627D02*
X239249D01*
G01X244949Y2909627D02*
X244149Y2909760D01*
X243449Y2910294D01*
X242849Y2911094D01*
X242449Y2912027D01*
X242249Y2913094D01*
Y2914160D01*
X242449Y2915227D01*
X242849Y2916160D01*
X243449Y2916960D01*
X244149Y2917494D01*
X244949Y2917627D01*
X245749Y2917494D01*
X246449Y2916960D01*
X247049Y2916160D01*
X247449Y2915227D01*
X247649Y2914160D01*
Y2913094D01*
X247449Y2912027D01*
X247049Y2911094D01*
X246449Y2910294D01*
X245749Y2909760D01*
X244949Y2909627D01*
G01X250949Y2917627D02*
Y2909627D01*
X254949D01*
G01X262949D02*
X258949D01*
Y2917627D01*
X262949D01*
G01X261349Y2913760D02*
X258949D01*
G01X266949Y2909627D02*
Y2917627D01*
X269449D01*
X270249Y2917227D01*
X270749Y2916694D01*
X270949Y2915627D01*
X270749Y2914560D01*
X270149Y2913894D01*
X269449Y2913494D01*
X266949D01*
G01X269449D02*
X270949Y2909627D01*
G01X274449D02*
X276949Y2917627D01*
X279449Y2909627D01*
G01X278549Y2912427D02*
X275349D01*
G01X282649Y2909627D02*
Y2917627D01*
X287249Y2909627D01*
Y2917627D01*
G01X295149Y2916960D02*
X294549Y2917360D01*
X293849Y2917627D01*
X293049D01*
X292149Y2917227D01*
X291449Y2916560D01*
X290949Y2915760D01*
X290549Y2914427D01*
X290449Y2913227D01*
X290649Y2912027D01*
X290949Y2911227D01*
X291549Y2910427D01*
X292249Y2909894D01*
X292949Y2909627D01*
X293649D01*
X294349Y2909894D01*
X294949Y2910294D01*
X295449Y2910827D01*
G01X302949Y2909627D02*
X298949D01*
Y2917627D01*
X302949D01*
G01X301349Y2913760D02*
X298949D01*
G01X315649Y2911094D02*
X318249D01*
G01Y2913494D02*
X315649D01*
G01X323849Y2912294D02*
X326249D01*
G01X324949Y2914027D02*
Y2910560D01*
G01X331149Y2909360D02*
X334749Y2917627D01*
G01X339649Y2912294D02*
X342249D01*
G01X348949Y2917627D02*
X348149Y2917360D01*
X347549Y2916694D01*
X347149Y2915894D01*
X346849Y2914827D01*
X346749Y2913627D01*
X346849Y2912427D01*
X347149Y2911360D01*
X347549Y2910560D01*
X348149Y2909894D01*
X348949Y2909627D01*
X349749Y2909894D01*
X350349Y2910560D01*
X350749Y2911360D01*
X351049Y2912427D01*
X351149Y2913627D01*
X351049Y2914827D01*
X350749Y2915894D01*
X350349Y2916694D01*
X349749Y2917360D01*
X348949Y2917627D01*
G01X356949Y2909360D02*
X356749Y2909494D01*
Y2909760D01*
X356949Y2909894D01*
X357149Y2909760D01*
Y2909494D01*
X356949Y2909360D01*
G01X364949Y2909627D02*
Y2917627D01*
X363749Y2916027D01*
G01Y2909627D02*
X366149D01*
G01X370749Y2910827D02*
X371349Y2910160D01*
X372049Y2909760D01*
X372949Y2909627D01*
X373849Y2909894D01*
X374549Y2910427D01*
X375049Y2911360D01*
X375149Y2912427D01*
X374949Y2913494D01*
X374449Y2914160D01*
X373749Y2914694D01*
X373049Y2914827D01*
X372349Y2914694D01*
X371449Y2914160D01*
X371749Y2917627D01*
X374449D01*
G01X378349Y2909627D02*
Y2917627D01*
X380949Y2910960D01*
X383549Y2917627D01*
Y2909627D01*
G01X386349D02*
Y2917627D01*
X388949Y2910960D01*
X391549Y2917627D01*
Y2909627D01*
G01X-24429Y2456134D02*
X-67736D01*
G01X-59862D02*
Y2509284D01*
G01X-24429Y2471883D02*
X-67736D01*
G01X-68051Y2684627D02*
X-68851Y2684760D01*
X-69551Y2685294D01*
X-70151Y2686094D01*
X-70551Y2687027D01*
X-70751Y2688094D01*
Y2689160D01*
X-70551Y2690227D01*
X-70151Y2691160D01*
X-69551Y2691960D01*
X-68851Y2692494D01*
X-68051Y2692627D01*
X-67251Y2692494D01*
X-66551Y2691960D01*
X-65951Y2691160D01*
X-65551Y2690227D01*
X-65351Y2689160D01*
Y2688094D01*
X-65551Y2687027D01*
X-65951Y2686094D01*
X-66551Y2685294D01*
X-67251Y2684760D01*
X-68051Y2684627D01*
G01X-67251Y2686760D02*
X-66051Y2684627D01*
G01X-62251Y2692627D02*
Y2686894D01*
X-61851Y2685693D01*
X-61051Y2684894D01*
X-60051Y2684627D01*
X-59051Y2684894D01*
X-58251Y2685693D01*
X-57851Y2686894D01*
Y2692627D01*
G01X-54551Y2684627D02*
X-52051Y2692627D01*
X-49551Y2684627D01*
G01X-50451Y2687427D02*
X-53651D01*
G01X-46351Y2684627D02*
Y2692627D01*
X-41751Y2684627D01*
Y2692627D01*
G01X-36051D02*
Y2684627D01*
G01X-38351Y2692627D02*
X-33751D01*
G01X-30551Y2684627D02*
X-28051Y2692627D01*
X-25551Y2684627D01*
G01X-26451Y2687427D02*
X-29651D01*
G01X-14051Y2684627D02*
Y2692627D01*
X-11651D01*
X-10851Y2692227D01*
X-10251Y2691294D01*
X-10051Y2690227D01*
X-10251Y2689160D01*
X-10751Y2688360D01*
X-11651Y2687960D01*
X-14051D01*
G01X-6051Y2684627D02*
Y2692627D01*
X-3551D01*
X-2751Y2692227D01*
X-2251Y2691694D01*
X-2051Y2690627D01*
X-2251Y2689560D01*
X-2851Y2688894D01*
X-3551Y2688494D01*
X-6051D01*
G01X-3551D02*
X-2051Y2684627D01*
G01X2749Y2692627D02*
X5149D01*
G01X3949D02*
Y2684627D01*
G01X2749D02*
X5149D01*
G01X11949D02*
X11149Y2684760D01*
X10449Y2685294D01*
X9849Y2686094D01*
X9449Y2687027D01*
X9249Y2688094D01*
Y2689160D01*
X9449Y2690227D01*
X9849Y2691160D01*
X10449Y2691960D01*
X11149Y2692494D01*
X11949Y2692627D01*
X12749Y2692494D01*
X13449Y2691960D01*
X14049Y2691160D01*
X14449Y2690227D01*
X14649Y2689160D01*
Y2688094D01*
X14449Y2687027D01*
X14049Y2686094D01*
X13449Y2685294D01*
X12749Y2684760D01*
X11949Y2684627D01*
G01X17949D02*
Y2692627D01*
X20449D01*
X21249Y2692227D01*
X21749Y2691694D01*
X21949Y2690627D01*
X21749Y2689560D01*
X21149Y2688894D01*
X20449Y2688494D01*
X17949D01*
G01X20449D02*
X21949Y2684627D01*
G01X35949Y2692627D02*
Y2684627D01*
G01X33649Y2692627D02*
X38249D01*
G01X43949Y2684627D02*
X43149Y2684760D01*
X42449Y2685294D01*
X41849Y2686094D01*
X41449Y2687027D01*
X41249Y2688094D01*
Y2689160D01*
X41449Y2690227D01*
X41849Y2691160D01*
X42449Y2691960D01*
X43149Y2692494D01*
X43949Y2692627D01*
X44749Y2692494D01*
X45449Y2691960D01*
X46049Y2691160D01*
X46449Y2690227D01*
X46649Y2689160D01*
Y2688094D01*
X46449Y2687027D01*
X46049Y2686094D01*
X45449Y2685294D01*
X44749Y2684760D01*
X43949Y2684627D01*
G01X58749Y2692627D02*
X61149D01*
G01X59949D02*
Y2684627D01*
G01X58749D02*
X61149D01*
G01X67949Y2692627D02*
Y2684627D01*
G01X65649Y2692627D02*
X70249D01*
G01X73849Y2685693D02*
X74649Y2685027D01*
X75549Y2684627D01*
X76349D01*
X77149Y2685027D01*
X77749Y2685693D01*
X78049Y2686627D01*
X77849Y2687560D01*
X77349Y2688360D01*
X76449Y2688894D01*
X75249Y2689160D01*
X74549Y2689694D01*
X74249Y2690627D01*
X74449Y2691560D01*
X74949Y2692227D01*
X75649Y2692627D01*
X76349D01*
X77049Y2692360D01*
X77649Y2691694D01*
G01X90749Y2692627D02*
X93149D01*
G01X91949D02*
Y2684627D01*
G01X90749D02*
X93149D01*
G01X97349D02*
Y2692627D01*
X99949Y2685960D01*
X102549Y2692627D01*
Y2684627D01*
G01X105949D02*
Y2692627D01*
X108349D01*
X109149Y2692227D01*
X109749Y2691294D01*
X109949Y2690227D01*
X109749Y2689160D01*
X109249Y2688360D01*
X108349Y2687960D01*
X105949D01*
G01X113949Y2692627D02*
Y2684627D01*
X117949D01*
G01X125949D02*
X121949D01*
Y2692627D01*
X125949D01*
G01X124349Y2688760D02*
X121949D01*
G01X129349Y2684627D02*
Y2692627D01*
X131949Y2685960D01*
X134549Y2692627D01*
Y2684627D01*
G01X141949D02*
X137949D01*
Y2692627D01*
X141949D01*
G01X140349Y2688760D02*
X137949D01*
G01X145649Y2684627D02*
Y2692627D01*
X150249Y2684627D01*
Y2692627D01*
G01X155949D02*
Y2684627D01*
G01X153649Y2692627D02*
X158249D01*
G01X161449Y2684627D02*
X163949Y2692627D01*
X166449Y2684627D01*
G01X165549Y2687427D02*
X162349D01*
G01X171949Y2692627D02*
Y2684627D01*
G01X169649Y2692627D02*
X174249D01*
G01X178749D02*
X181149D01*
G01X179949D02*
Y2684627D01*
G01X178749D02*
X181149D01*
G01X187949D02*
X187149Y2684760D01*
X186449Y2685294D01*
X185849Y2686094D01*
X185449Y2687027D01*
X185249Y2688094D01*
Y2689160D01*
X185449Y2690227D01*
X185849Y2691160D01*
X186449Y2691960D01*
X187149Y2692494D01*
X187949Y2692627D01*
X188749Y2692494D01*
X189449Y2691960D01*
X190049Y2691160D01*
X190449Y2690227D01*
X190649Y2689160D01*
Y2688094D01*
X190449Y2687027D01*
X190049Y2686094D01*
X189449Y2685294D01*
X188749Y2684760D01*
X187949Y2684627D01*
G01X193649D02*
Y2692627D01*
X198249Y2684627D01*
Y2692627D01*
G01X203949Y2684360D02*
X203749Y2684494D01*
Y2684760D01*
X203949Y2684894D01*
X204149Y2684760D01*
Y2684494D01*
X203949Y2684360D01*
G01X-69251Y2722627D02*
X-66851D01*
G01X-68051D02*
Y2714627D01*
G01X-69251D02*
X-66851D01*
G01X-62651D02*
Y2722627D01*
X-60051Y2715960D01*
X-57451Y2722627D01*
Y2714627D01*
G01X-54051D02*
Y2722627D01*
X-51651D01*
X-50851Y2722227D01*
X-50251Y2721294D01*
X-50051Y2720227D01*
X-50251Y2719160D01*
X-50751Y2718360D01*
X-51651Y2717960D01*
X-54051D01*
G01X-42051Y2714627D02*
X-46051D01*
Y2722627D01*
X-42051D01*
G01X-43651Y2718760D02*
X-46051D01*
G01X-38251Y2714627D02*
Y2722627D01*
X-36251D01*
X-35451Y2722227D01*
X-34851Y2721694D01*
X-34351Y2720894D01*
X-33951Y2719960D01*
X-33851Y2718627D01*
X-33951Y2717294D01*
X-34351Y2716360D01*
X-34851Y2715560D01*
X-35451Y2715027D01*
X-36251Y2714627D01*
X-38251D01*
G01X-30551D02*
X-28051Y2722627D01*
X-25551Y2714627D01*
G01X-26451Y2717427D02*
X-29651D01*
G01X-22351Y2714627D02*
Y2722627D01*
X-17751Y2714627D01*
Y2722627D01*
G01X-9851Y2721960D02*
X-10451Y2722360D01*
X-11151Y2722627D01*
X-11951D01*
X-12851Y2722227D01*
X-13551Y2721560D01*
X-14051Y2720760D01*
X-14451Y2719427D01*
X-14551Y2718227D01*
X-14351Y2717027D01*
X-14051Y2716227D01*
X-13451Y2715427D01*
X-12751Y2714894D01*
X-12051Y2714627D01*
X-11351D01*
X-10651Y2714894D01*
X-10051Y2715294D01*
X-9551Y2715827D01*
G01X-2051Y2714627D02*
X-6051D01*
Y2722627D01*
X-2051D01*
G01X-3651Y2718760D02*
X-6051D01*
G01X1849Y2715693D02*
X2649Y2715027D01*
X3549Y2714627D01*
X4349D01*
X5149Y2715027D01*
X5749Y2715693D01*
X6049Y2716627D01*
X5849Y2717560D01*
X5349Y2718360D01*
X4449Y2718894D01*
X3249Y2719160D01*
X2549Y2719694D01*
X2249Y2720627D01*
X2449Y2721560D01*
X2949Y2722227D01*
X3649Y2722627D01*
X4349D01*
X5049Y2722360D01*
X5649Y2721694D01*
G01X17449Y2714627D02*
X19949Y2722627D01*
X22449Y2714627D01*
G01X21549Y2717427D02*
X18349D01*
G01X25649Y2714627D02*
Y2722627D01*
X30249Y2714627D01*
Y2722627D01*
G01X33749Y2714627D02*
Y2722627D01*
X35749D01*
X36549Y2722227D01*
X37149Y2721694D01*
X37649Y2720894D01*
X38049Y2719960D01*
X38149Y2718627D01*
X38049Y2717294D01*
X37649Y2716360D01*
X37149Y2715560D01*
X36549Y2715027D01*
X35749Y2714627D01*
X33749D01*
G01X52749Y2718894D02*
X53149Y2719294D01*
X53449Y2719960D01*
X53649Y2720894D01*
X53449Y2721694D01*
X53049Y2722227D01*
X52349Y2722627D01*
X49649D01*
Y2714627D01*
X52949D01*
X53649Y2715160D01*
X54049Y2715960D01*
X54249Y2716894D01*
X54049Y2717827D01*
X53449Y2718627D01*
X52749Y2718894D01*
X49649D01*
G01X59949Y2714627D02*
X59149Y2714760D01*
X58449Y2715294D01*
X57849Y2716094D01*
X57449Y2717027D01*
X57249Y2718094D01*
Y2719160D01*
X57449Y2720227D01*
X57849Y2721160D01*
X58449Y2721960D01*
X59149Y2722494D01*
X59949Y2722627D01*
X60749Y2722494D01*
X61449Y2721960D01*
X62049Y2721160D01*
X62449Y2720227D01*
X62649Y2719160D01*
Y2718094D01*
X62449Y2717027D01*
X62049Y2716094D01*
X61449Y2715294D01*
X60749Y2714760D01*
X59949Y2714627D01*
G01X65449D02*
X67949Y2722627D01*
X70449Y2714627D01*
G01X69549Y2717427D02*
X66349D01*
G01X73949Y2714627D02*
Y2722627D01*
X76449D01*
X77249Y2722227D01*
X77749Y2721694D01*
X77949Y2720627D01*
X77749Y2719560D01*
X77149Y2718894D01*
X76449Y2718494D01*
X73949D01*
G01X76449D02*
X77949Y2714627D01*
G01X81749D02*
Y2722627D01*
X83749D01*
X84549Y2722227D01*
X85149Y2721694D01*
X85649Y2720894D01*
X86049Y2719960D01*
X86149Y2718627D01*
X86049Y2717294D01*
X85649Y2716360D01*
X85149Y2715560D01*
X84549Y2715027D01*
X83749Y2714627D01*
X81749D01*
G01X99949Y2722627D02*
Y2714627D01*
G01X97649Y2722627D02*
X102249D01*
G01X105849Y2714627D02*
Y2722627D01*
G01X110049D02*
Y2714627D01*
G01Y2718627D02*
X105849D01*
G01X114749Y2722627D02*
X117149D01*
G01X115949D02*
Y2714627D01*
G01X114749D02*
X117149D01*
G01X126149Y2721960D02*
X125549Y2722360D01*
X124849Y2722627D01*
X124049D01*
X123149Y2722227D01*
X122449Y2721560D01*
X121949Y2720760D01*
X121549Y2719427D01*
X121449Y2718227D01*
X121649Y2717027D01*
X121949Y2716227D01*
X122549Y2715427D01*
X123249Y2714894D01*
X123949Y2714627D01*
X124649D01*
X125349Y2714894D01*
X125949Y2715294D01*
X126449Y2715827D01*
G01X129749Y2714627D02*
Y2722627D01*
G01X133549D02*
X129749Y2717693D01*
G01X134149Y2714627D02*
X131449Y2719960D01*
G01X137649Y2714627D02*
Y2722627D01*
X142249Y2714627D01*
Y2722627D01*
G01X149949Y2714627D02*
X145949D01*
Y2722627D01*
X149949D01*
G01X148349Y2718760D02*
X145949D01*
G01X153849Y2715693D02*
X154649Y2715027D01*
X155549Y2714627D01*
X156349D01*
X157149Y2715027D01*
X157749Y2715693D01*
X158049Y2716627D01*
X157849Y2717560D01*
X157349Y2718360D01*
X156449Y2718894D01*
X155249Y2719160D01*
X154549Y2719694D01*
X154249Y2720627D01*
X154449Y2721560D01*
X154949Y2722227D01*
X155649Y2722627D01*
X156349D01*
X157049Y2722360D01*
X157649Y2721694D01*
G01X161849Y2715693D02*
X162649Y2715027D01*
X163549Y2714627D01*
X164349D01*
X165149Y2715027D01*
X165749Y2715693D01*
X166049Y2716627D01*
X165849Y2717560D01*
X165349Y2718360D01*
X164449Y2718894D01*
X163249Y2719160D01*
X162549Y2719694D01*
X162249Y2720627D01*
X162449Y2721560D01*
X162949Y2722227D01*
X163649Y2722627D01*
X164349D01*
X165049Y2722360D01*
X165649Y2721694D01*
G01X171949Y2714360D02*
X171749Y2714494D01*
Y2714760D01*
X171949Y2714894D01*
X172149Y2714760D01*
Y2714494D01*
X171949Y2714360D01*
G01X194749Y2722627D02*
X197149D01*
G01X195949D02*
Y2714627D01*
G01X194749D02*
X197149D01*
G01X201649D02*
Y2722627D01*
X206249Y2714627D01*
Y2722627D01*
G01X210749D02*
X213149D01*
G01X211949D02*
Y2714627D01*
G01X210749D02*
X213149D01*
G01X219949Y2722627D02*
Y2714627D01*
G01X217649Y2722627D02*
X222249D01*
G01X226749D02*
X229149D01*
G01X227949D02*
Y2714627D01*
G01X226749D02*
X229149D01*
G01X233449D02*
X235949Y2722627D01*
X238449Y2714627D01*
G01X237549Y2717427D02*
X234349D01*
G01X241949Y2722627D02*
Y2714627D01*
X245949D01*
G01X257749D02*
Y2722627D01*
X259749D01*
X260549Y2722227D01*
X261149Y2721694D01*
X261649Y2720894D01*
X262049Y2719960D01*
X262149Y2718627D01*
X262049Y2717294D01*
X261649Y2716360D01*
X261149Y2715560D01*
X260549Y2715027D01*
X259749Y2714627D01*
X257749D01*
G01X269949D02*
X265949D01*
Y2722627D01*
X269949D01*
G01X268349Y2718760D02*
X265949D01*
G01X275949Y2722627D02*
Y2714627D01*
G01X273649Y2722627D02*
X278249D01*
G01X281449Y2714627D02*
X283949Y2722627D01*
X286449Y2714627D01*
G01X285549Y2717427D02*
X282349D01*
G01X290749Y2722627D02*
X293149D01*
G01X291949D02*
Y2714627D01*
G01X290749D02*
X293149D01*
G01X297949Y2722627D02*
Y2714627D01*
X301949D01*
G01X313949Y2722627D02*
Y2714627D01*
X317949D01*
G01X321449D02*
X323949Y2722627D01*
X326449Y2714627D01*
G01X325549Y2717427D02*
X322349D01*
G01X331949Y2714627D02*
Y2718227D01*
X329949Y2722627D01*
G01X333949D02*
X331949Y2718227D01*
G01X341949Y2714627D02*
X337949D01*
Y2722627D01*
X341949D01*
G01X340349Y2718760D02*
X337949D01*
G01X345949Y2714627D02*
Y2722627D01*
X348449D01*
X349249Y2722227D01*
X349749Y2721694D01*
X349949Y2720627D01*
X349749Y2719560D01*
X349149Y2718894D01*
X348449Y2718494D01*
X345949D01*
G01X348449D02*
X349949Y2714627D01*
G01X-70151Y2700693D02*
X-69351Y2700027D01*
X-68451Y2699627D01*
X-67651D01*
X-66851Y2700027D01*
X-66251Y2700693D01*
X-65951Y2701627D01*
X-66151Y2702560D01*
X-66651Y2703360D01*
X-67551Y2703894D01*
X-68751Y2704160D01*
X-69451Y2704694D01*
X-69751Y2705627D01*
X-69551Y2706560D01*
X-69051Y2707227D01*
X-68351Y2707627D01*
X-67651D01*
X-66951Y2707360D01*
X-66351Y2706694D01*
G01X-60051Y2707627D02*
Y2699627D01*
G01X-62351Y2707627D02*
X-57751D01*
G01X-54551Y2699627D02*
X-52051Y2707627D01*
X-49551Y2699627D01*
G01X-50451Y2702427D02*
X-53651D01*
G01X-41851Y2706960D02*
X-42451Y2707360D01*
X-43151Y2707627D01*
X-43951D01*
X-44851Y2707227D01*
X-45551Y2706560D01*
X-46051Y2705760D01*
X-46451Y2704427D01*
X-46551Y2703227D01*
X-46351Y2702027D01*
X-46051Y2701227D01*
X-45451Y2700427D01*
X-44751Y2699894D01*
X-44051Y2699627D01*
X-43351D01*
X-42651Y2699894D01*
X-42051Y2700294D01*
X-41551Y2700827D01*
G01X-38251Y2699627D02*
Y2707627D01*
G01X-34451D02*
X-38251Y2702693D01*
G01X-33851Y2699627D02*
X-36551Y2704960D01*
G01X-29251Y2707627D02*
X-26851D01*
G01X-28051D02*
Y2699627D01*
G01X-29251D02*
X-26851D01*
G01X-22351D02*
Y2707627D01*
X-17751Y2699627D01*
Y2707627D01*
G01X-11451Y2703627D02*
X-9451D01*
Y2701227D01*
X-10051Y2700427D01*
X-10751Y2699894D01*
X-11751Y2699627D01*
X-12751Y2699894D01*
X-13451Y2700427D01*
X-14051Y2701227D01*
X-14451Y2702160D01*
X-14651Y2703227D01*
Y2704160D01*
X-14451Y2704960D01*
X-14051Y2705894D01*
X-13451Y2706694D01*
X-12851Y2707227D01*
X-12051Y2707627D01*
X-11351D01*
X-10551Y2707360D01*
X-9951Y2706827D01*
G01X1449Y2699627D02*
X3949Y2707627D01*
X6449Y2699627D01*
G01X5549Y2702427D02*
X2349D01*
G01X9649Y2699627D02*
Y2707627D01*
X14249Y2699627D01*
Y2707627D01*
G01X17749Y2699627D02*
Y2707627D01*
X19749D01*
X20549Y2707227D01*
X21149Y2706694D01*
X21649Y2705894D01*
X22049Y2704960D01*
X22149Y2703627D01*
X22049Y2702294D01*
X21649Y2701360D01*
X21149Y2700560D01*
X20549Y2700027D01*
X19749Y2699627D01*
X17749D01*
G01X35949D02*
X35149Y2699760D01*
X34449Y2700294D01*
X33849Y2701094D01*
X33449Y2702027D01*
X33249Y2703094D01*
Y2704160D01*
X33449Y2705227D01*
X33849Y2706160D01*
X34449Y2706960D01*
X35149Y2707494D01*
X35949Y2707627D01*
X36749Y2707494D01*
X37449Y2706960D01*
X38049Y2706160D01*
X38449Y2705227D01*
X38649Y2704160D01*
Y2703094D01*
X38449Y2702027D01*
X38049Y2701094D01*
X37449Y2700294D01*
X36749Y2699760D01*
X35949Y2699627D01*
G01X43949Y2707627D02*
Y2699627D01*
G01X41649Y2707627D02*
X46249D01*
G01X49849Y2699627D02*
Y2707627D01*
G01X54049D02*
Y2699627D01*
G01Y2703627D02*
X49849D01*
G01X61949Y2699627D02*
X57949D01*
Y2707627D01*
X61949D01*
G01X60349Y2703760D02*
X57949D01*
G01X65949Y2699627D02*
Y2707627D01*
X68449D01*
X69249Y2707227D01*
X69749Y2706694D01*
X69949Y2705627D01*
X69749Y2704560D01*
X69149Y2703894D01*
X68449Y2703494D01*
X65949D01*
G01X68449D02*
X69949Y2699627D01*
G01X81849Y2700693D02*
X82649Y2700027D01*
X83549Y2699627D01*
X84349D01*
X85149Y2700027D01*
X85749Y2700693D01*
X86049Y2701627D01*
X85849Y2702560D01*
X85349Y2703360D01*
X84449Y2703894D01*
X83249Y2704160D01*
X82549Y2704694D01*
X82249Y2705627D01*
X82449Y2706560D01*
X82949Y2707227D01*
X83649Y2707627D01*
X84349D01*
X85049Y2707360D01*
X85649Y2706694D01*
G01X89749Y2707627D02*
Y2701894D01*
X90149Y2700693D01*
X90949Y2699894D01*
X91949Y2699627D01*
X92949Y2699894D01*
X93749Y2700693D01*
X94149Y2701894D01*
Y2707627D01*
G01X100749Y2703894D02*
X101149Y2704294D01*
X101449Y2704960D01*
X101649Y2705894D01*
X101449Y2706694D01*
X101049Y2707227D01*
X100349Y2707627D01*
X97649D01*
Y2699627D01*
X100949D01*
X101649Y2700160D01*
X102049Y2700960D01*
X102249Y2701894D01*
X102049Y2702827D01*
X101449Y2703627D01*
X100749Y2703894D01*
X97649D01*
G01X105849Y2700693D02*
X106649Y2700027D01*
X107549Y2699627D01*
X108349D01*
X109149Y2700027D01*
X109749Y2700693D01*
X110049Y2701627D01*
X109849Y2702560D01*
X109349Y2703360D01*
X108449Y2703894D01*
X107249Y2704160D01*
X106549Y2704694D01*
X106249Y2705627D01*
X106449Y2706560D01*
X106949Y2707227D01*
X107649Y2707627D01*
X108349D01*
X109049Y2707360D01*
X109649Y2706694D01*
G01X117949Y2699627D02*
X113949D01*
Y2707627D01*
X117949D01*
G01X116349Y2703760D02*
X113949D01*
G01X123949Y2699627D02*
X123149Y2699760D01*
X122449Y2700294D01*
X121849Y2701094D01*
X121449Y2702027D01*
X121249Y2703094D01*
Y2704160D01*
X121449Y2705227D01*
X121849Y2706160D01*
X122449Y2706960D01*
X123149Y2707494D01*
X123949Y2707627D01*
X124749Y2707494D01*
X125449Y2706960D01*
X126049Y2706160D01*
X126449Y2705227D01*
X126649Y2704160D01*
Y2703094D01*
X126449Y2702027D01*
X126049Y2701094D01*
X125449Y2700294D01*
X124749Y2699760D01*
X123949Y2699627D01*
G01X124749Y2701760D02*
X125949Y2699627D01*
G01X129749Y2707627D02*
Y2701894D01*
X130149Y2700693D01*
X130949Y2699894D01*
X131949Y2699627D01*
X132949Y2699894D01*
X133749Y2700693D01*
X134149Y2701894D01*
Y2707627D01*
G01X141949Y2699627D02*
X137949D01*
Y2707627D01*
X141949D01*
G01X140349Y2703760D02*
X137949D01*
G01X145649Y2699627D02*
Y2707627D01*
X150249Y2699627D01*
Y2707627D01*
G01X155949D02*
Y2699627D01*
G01X153649Y2707627D02*
X158249D01*
G01X174149Y2706960D02*
X173549Y2707360D01*
X172849Y2707627D01*
X172049D01*
X171149Y2707227D01*
X170449Y2706560D01*
X169949Y2705760D01*
X169549Y2704427D01*
X169449Y2703227D01*
X169649Y2702027D01*
X169949Y2701227D01*
X170549Y2700427D01*
X171249Y2699894D01*
X171949Y2699627D01*
X172649D01*
X173349Y2699894D01*
X173949Y2700294D01*
X174449Y2700827D01*
G01X177849Y2699627D02*
Y2707627D01*
G01X182049D02*
Y2699627D01*
G01Y2703627D02*
X177849D01*
G01X185449Y2699627D02*
X187949Y2707627D01*
X190449Y2699627D01*
G01X189549Y2702427D02*
X186349D01*
G01X193649Y2699627D02*
Y2707627D01*
X198249Y2699627D01*
Y2707627D01*
G01X204549Y2703627D02*
X206549D01*
Y2701227D01*
X205949Y2700427D01*
X205249Y2699894D01*
X204249Y2699627D01*
X203249Y2699894D01*
X202549Y2700427D01*
X201949Y2701227D01*
X201549Y2702160D01*
X201349Y2703227D01*
Y2704160D01*
X201549Y2704960D01*
X201949Y2705894D01*
X202549Y2706694D01*
X203149Y2707227D01*
X203949Y2707627D01*
X204649D01*
X205449Y2707360D01*
X206049Y2706827D01*
G01X213949Y2699627D02*
X209949D01*
Y2707627D01*
X213949D01*
G01X212349Y2703760D02*
X209949D01*
G01X217849Y2700693D02*
X218649Y2700027D01*
X219549Y2699627D01*
X220349D01*
X221149Y2700027D01*
X221749Y2700693D01*
X222049Y2701627D01*
X221849Y2702560D01*
X221349Y2703360D01*
X220449Y2703894D01*
X219249Y2704160D01*
X218549Y2704694D01*
X218249Y2705627D01*
X218449Y2706560D01*
X218949Y2707227D01*
X219649Y2707627D01*
X220349D01*
X221049Y2707360D01*
X221649Y2706694D01*
G01X233349Y2699627D02*
Y2707627D01*
X235949Y2700960D01*
X238549Y2707627D01*
Y2699627D01*
G01X241749Y2707627D02*
Y2701894D01*
X242149Y2700693D01*
X242949Y2699894D01*
X243949Y2699627D01*
X244949Y2699894D01*
X245749Y2700693D01*
X246149Y2701894D01*
Y2707627D01*
G01X249849Y2700693D02*
X250649Y2700027D01*
X251549Y2699627D01*
X252349D01*
X253149Y2700027D01*
X253749Y2700693D01*
X254049Y2701627D01*
X253849Y2702560D01*
X253349Y2703360D01*
X252449Y2703894D01*
X251249Y2704160D01*
X250549Y2704694D01*
X250249Y2705627D01*
X250449Y2706560D01*
X250949Y2707227D01*
X251649Y2707627D01*
X252349D01*
X253049Y2707360D01*
X253649Y2706694D01*
G01X259949Y2707627D02*
Y2699627D01*
G01X257649Y2707627D02*
X262249D01*
G01X276749Y2703894D02*
X277149Y2704294D01*
X277449Y2704960D01*
X277649Y2705894D01*
X277449Y2706694D01*
X277049Y2707227D01*
X276349Y2707627D01*
X273649D01*
Y2699627D01*
X276949D01*
X277649Y2700160D01*
X278049Y2700960D01*
X278249Y2701894D01*
X278049Y2702827D01*
X277449Y2703627D01*
X276749Y2703894D01*
X273649D01*
G01X285949Y2699627D02*
X281949D01*
Y2707627D01*
X285949D01*
G01X284349Y2703760D02*
X281949D01*
G01X297449Y2699627D02*
X299949Y2707627D01*
X302449Y2699627D01*
G01X301549Y2702427D02*
X298349D01*
G01X305949Y2699627D02*
Y2707627D01*
X308349D01*
X309149Y2707227D01*
X309749Y2706294D01*
X309949Y2705227D01*
X309749Y2704160D01*
X309249Y2703360D01*
X308349Y2702960D01*
X305949D01*
G01X313949Y2699627D02*
Y2707627D01*
X316349D01*
X317149Y2707227D01*
X317749Y2706294D01*
X317949Y2705227D01*
X317749Y2704160D01*
X317249Y2703360D01*
X316349Y2702960D01*
X313949D01*
G01X321949Y2699627D02*
Y2707627D01*
X324449D01*
X325249Y2707227D01*
X325749Y2706694D01*
X325949Y2705627D01*
X325749Y2704560D01*
X325149Y2703894D01*
X324449Y2703494D01*
X321949D01*
G01X324449D02*
X325949Y2699627D01*
G01X331949D02*
X331149Y2699760D01*
X330449Y2700294D01*
X329849Y2701094D01*
X329449Y2702027D01*
X329249Y2703094D01*
Y2704160D01*
X329449Y2705227D01*
X329849Y2706160D01*
X330449Y2706960D01*
X331149Y2707494D01*
X331949Y2707627D01*
X332749Y2707494D01*
X333449Y2706960D01*
X334049Y2706160D01*
X334449Y2705227D01*
X334649Y2704160D01*
Y2703094D01*
X334449Y2702027D01*
X334049Y2701094D01*
X333449Y2700294D01*
X332749Y2699760D01*
X331949Y2699627D01*
G01X337449Y2707627D02*
X339949Y2699627D01*
X342449Y2707627D01*
G01X349949Y2699627D02*
X345949D01*
Y2707627D01*
X349949D01*
G01X348349Y2703760D02*
X345949D01*
G01X353749Y2699627D02*
Y2707627D01*
X355749D01*
X356549Y2707227D01*
X357149Y2706694D01*
X357649Y2705894D01*
X358049Y2704960D01*
X358149Y2703627D01*
X358049Y2702294D01*
X357649Y2701360D01*
X357149Y2700560D01*
X356549Y2700027D01*
X355749Y2699627D01*
X353749D01*
G01X372749Y2703894D02*
X373149Y2704294D01*
X373449Y2704960D01*
X373649Y2705894D01*
X373449Y2706694D01*
X373049Y2707227D01*
X372349Y2707627D01*
X369649D01*
Y2699627D01*
X372949D01*
X373649Y2700160D01*
X374049Y2700960D01*
X374249Y2701894D01*
X374049Y2702827D01*
X373449Y2703627D01*
X372749Y2703894D01*
X369649D01*
G01X379949Y2699627D02*
Y2703227D01*
X377949Y2707627D01*
G01X381949D02*
X379949Y2703227D01*
G01X-70151Y2730693D02*
X-69351Y2730027D01*
X-68451Y2729627D01*
X-67651D01*
X-66851Y2730027D01*
X-66251Y2730693D01*
X-65951Y2731627D01*
X-66151Y2732560D01*
X-66651Y2733360D01*
X-67551Y2733894D01*
X-68751Y2734160D01*
X-69451Y2734694D01*
X-69751Y2735627D01*
X-69551Y2736560D01*
X-69051Y2737227D01*
X-68351Y2737627D01*
X-67651D01*
X-66951Y2737360D01*
X-66351Y2736694D01*
G01X-62051Y2729627D02*
Y2737627D01*
X-59651D01*
X-58851Y2737227D01*
X-58251Y2736294D01*
X-58051Y2735227D01*
X-58251Y2734160D01*
X-58751Y2733360D01*
X-59651Y2732960D01*
X-62051D01*
G01X-54551Y2729627D02*
X-52051Y2737627D01*
X-49551Y2729627D01*
G01X-50451Y2732427D02*
X-53651D01*
G01X-41851Y2736960D02*
X-42451Y2737360D01*
X-43151Y2737627D01*
X-43951D01*
X-44851Y2737227D01*
X-45551Y2736560D01*
X-46051Y2735760D01*
X-46451Y2734427D01*
X-46551Y2733227D01*
X-46351Y2732027D01*
X-46051Y2731227D01*
X-45451Y2730427D01*
X-44751Y2729894D01*
X-44051Y2729627D01*
X-43351D01*
X-42651Y2729894D01*
X-42051Y2730294D01*
X-41551Y2730827D01*
G01X-37251Y2737627D02*
X-34851D01*
G01X-36051D02*
Y2729627D01*
G01X-37251D02*
X-34851D01*
G01X-30351D02*
Y2737627D01*
X-25751Y2729627D01*
Y2737627D01*
G01X-19451Y2733627D02*
X-17451D01*
Y2731227D01*
X-18051Y2730427D01*
X-18751Y2729894D01*
X-19751Y2729627D01*
X-20751Y2729894D01*
X-21451Y2730427D01*
X-22051Y2731227D01*
X-22451Y2732160D01*
X-22651Y2733227D01*
Y2734160D01*
X-22451Y2734960D01*
X-22051Y2735894D01*
X-21451Y2736694D01*
X-20851Y2737227D01*
X-20051Y2737627D01*
X-19351D01*
X-18551Y2737360D01*
X-17951Y2736827D01*
G01X-6551Y2729627D02*
X-4051Y2737627D01*
X-1551Y2729627D01*
G01X-2451Y2732427D02*
X-5651D01*
G01X1649Y2729627D02*
Y2737627D01*
X6249Y2729627D01*
Y2737627D01*
G01X9749Y2729627D02*
Y2737627D01*
X11749D01*
X12549Y2737227D01*
X13149Y2736694D01*
X13649Y2735894D01*
X14049Y2734960D01*
X14149Y2733627D01*
X14049Y2732294D01*
X13649Y2731360D01*
X13149Y2730560D01*
X12549Y2730027D01*
X11749Y2729627D01*
X9749D01*
G01X25349D02*
Y2737627D01*
X27949Y2730960D01*
X30549Y2737627D01*
Y2729627D01*
G01X33449D02*
X35949Y2737627D01*
X38449Y2729627D01*
G01X37549Y2732427D02*
X34349D01*
G01X43949Y2737627D02*
Y2729627D01*
G01X41649Y2737627D02*
X46249D01*
G01X53949Y2729627D02*
X49949D01*
Y2737627D01*
X53949D01*
G01X52349Y2733760D02*
X49949D01*
G01X57949Y2729627D02*
Y2737627D01*
X60449D01*
X61249Y2737227D01*
X61749Y2736694D01*
X61949Y2735627D01*
X61749Y2734560D01*
X61149Y2733894D01*
X60449Y2733494D01*
X57949D01*
G01X60449D02*
X61949Y2729627D01*
G01X66749Y2737627D02*
X69149D01*
G01X67949D02*
Y2729627D01*
G01X66749D02*
X69149D01*
G01X73449D02*
X75949Y2737627D01*
X78449Y2729627D01*
G01X77549Y2732427D02*
X74349D01*
G01X81949Y2737627D02*
Y2729627D01*
X85949D01*
G01X97749D02*
Y2737627D01*
X99749D01*
X100549Y2737227D01*
X101149Y2736694D01*
X101649Y2735894D01*
X102049Y2734960D01*
X102149Y2733627D01*
X102049Y2732294D01*
X101649Y2731360D01*
X101149Y2730560D01*
X100549Y2730027D01*
X99749Y2729627D01*
X97749D01*
G01X106749Y2737627D02*
X109149D01*
G01X107949D02*
Y2729627D01*
G01X106749D02*
X109149D01*
G01X117949D02*
X113949D01*
Y2737627D01*
X117949D01*
G01X116349Y2733760D02*
X113949D01*
G01X121949Y2737627D02*
Y2729627D01*
X125949D01*
G01X133949D02*
X129949D01*
Y2737627D01*
X133949D01*
G01X132349Y2733760D02*
X129949D01*
G01X142149Y2736960D02*
X141549Y2737360D01*
X140849Y2737627D01*
X140049D01*
X139149Y2737227D01*
X138449Y2736560D01*
X137949Y2735760D01*
X137549Y2734427D01*
X137449Y2733227D01*
X137649Y2732027D01*
X137949Y2731227D01*
X138549Y2730427D01*
X139249Y2729894D01*
X139949Y2729627D01*
X140649D01*
X141349Y2729894D01*
X141949Y2730294D01*
X142449Y2730827D01*
G01X147949Y2737627D02*
Y2729627D01*
G01X145649Y2737627D02*
X150249D01*
G01X153949Y2729627D02*
Y2737627D01*
X156449D01*
X157249Y2737227D01*
X157749Y2736694D01*
X157949Y2735627D01*
X157749Y2734560D01*
X157149Y2733894D01*
X156449Y2733494D01*
X153949D01*
G01X156449D02*
X157949Y2729627D01*
G01X162749Y2737627D02*
X165149D01*
G01X163949D02*
Y2729627D01*
G01X162749D02*
X165149D01*
G01X174149Y2736960D02*
X173549Y2737360D01*
X172849Y2737627D01*
X172049D01*
X171149Y2737227D01*
X170449Y2736560D01*
X169949Y2735760D01*
X169549Y2734427D01*
X169449Y2733227D01*
X169649Y2732027D01*
X169949Y2731227D01*
X170549Y2730427D01*
X171249Y2729894D01*
X171949Y2729627D01*
X172649D01*
X173349Y2729894D01*
X173949Y2730294D01*
X174449Y2730827D01*
G01X190149Y2736960D02*
X189549Y2737360D01*
X188849Y2737627D01*
X188049D01*
X187149Y2737227D01*
X186449Y2736560D01*
X185949Y2735760D01*
X185549Y2734427D01*
X185449Y2733227D01*
X185649Y2732027D01*
X185949Y2731227D01*
X186549Y2730427D01*
X187249Y2729894D01*
X187949Y2729627D01*
X188649D01*
X189349Y2729894D01*
X189949Y2730294D01*
X190449Y2730827D01*
G01X195949Y2729627D02*
X195149Y2729760D01*
X194449Y2730294D01*
X193849Y2731094D01*
X193449Y2732027D01*
X193249Y2733094D01*
Y2734160D01*
X193449Y2735227D01*
X193849Y2736160D01*
X194449Y2736960D01*
X195149Y2737494D01*
X195949Y2737627D01*
X196749Y2737494D01*
X197449Y2736960D01*
X198049Y2736160D01*
X198449Y2735227D01*
X198649Y2734160D01*
Y2733094D01*
X198449Y2732027D01*
X198049Y2731094D01*
X197449Y2730294D01*
X196749Y2729760D01*
X195949Y2729627D01*
G01X201649D02*
Y2737627D01*
X206249Y2729627D01*
Y2737627D01*
G01X209849Y2730693D02*
X210649Y2730027D01*
X211549Y2729627D01*
X212349D01*
X213149Y2730027D01*
X213749Y2730693D01*
X214049Y2731627D01*
X213849Y2732560D01*
X213349Y2733360D01*
X212449Y2733894D01*
X211249Y2734160D01*
X210549Y2734694D01*
X210249Y2735627D01*
X210449Y2736560D01*
X210949Y2737227D01*
X211649Y2737627D01*
X212349D01*
X213049Y2737360D01*
X213649Y2736694D01*
G01X219949Y2737627D02*
Y2729627D01*
G01X217649Y2737627D02*
X222249D01*
G01X225449Y2729627D02*
X227949Y2737627D01*
X230449Y2729627D01*
G01X229549Y2732427D02*
X226349D01*
G01X233649Y2729627D02*
Y2737627D01*
X238249Y2729627D01*
Y2737627D01*
G01X243949D02*
Y2729627D01*
G01X241649Y2737627D02*
X246249D01*
G01X259949D02*
Y2729627D01*
G01X257649Y2737627D02*
X262249D01*
G01X267949Y2729627D02*
X267149Y2729760D01*
X266449Y2730294D01*
X265849Y2731094D01*
X265449Y2732027D01*
X265249Y2733094D01*
Y2734160D01*
X265449Y2735227D01*
X265849Y2736160D01*
X266449Y2736960D01*
X267149Y2737494D01*
X267949Y2737627D01*
X268749Y2737494D01*
X269449Y2736960D01*
X270049Y2736160D01*
X270449Y2735227D01*
X270649Y2734160D01*
Y2733094D01*
X270449Y2732027D01*
X270049Y2731094D01*
X269449Y2730294D01*
X268749Y2729760D01*
X267949Y2729627D01*
G01X281449D02*
X283949Y2737627D01*
X286449Y2729627D01*
G01X285549Y2732427D02*
X282349D01*
G01X294149Y2736960D02*
X293549Y2737360D01*
X292849Y2737627D01*
X292049D01*
X291149Y2737227D01*
X290449Y2736560D01*
X289949Y2735760D01*
X289549Y2734427D01*
X289449Y2733227D01*
X289649Y2732027D01*
X289949Y2731227D01*
X290549Y2730427D01*
X291249Y2729894D01*
X291949Y2729627D01*
X292649D01*
X293349Y2729894D01*
X293949Y2730294D01*
X294449Y2730827D01*
G01X297849Y2729627D02*
Y2737627D01*
G01X302049D02*
Y2729627D01*
G01Y2733627D02*
X297849D01*
G01X306749Y2737627D02*
X309149D01*
G01X307949D02*
Y2729627D01*
G01X306749D02*
X309149D01*
G01X317949D02*
X313949D01*
Y2737627D01*
X317949D01*
G01X316349Y2733760D02*
X313949D01*
G01X321449Y2737627D02*
X323949Y2729627D01*
X326449Y2737627D01*
G01X333949Y2729627D02*
X329949D01*
Y2737627D01*
X333949D01*
G01X332349Y2733760D02*
X329949D01*
G01X345949Y2729627D02*
Y2737627D01*
X348449D01*
X349249Y2737227D01*
X349749Y2736694D01*
X349949Y2735627D01*
X349749Y2734560D01*
X349149Y2733894D01*
X348449Y2733494D01*
X345949D01*
G01X348449D02*
X349949Y2729627D01*
G01X357949D02*
X353949D01*
Y2737627D01*
X357949D01*
G01X356349Y2733760D02*
X353949D01*
G01X363949Y2729627D02*
X363149Y2729760D01*
X362449Y2730294D01*
X361849Y2731094D01*
X361449Y2732027D01*
X361249Y2733094D01*
Y2734160D01*
X361449Y2735227D01*
X361849Y2736160D01*
X362449Y2736960D01*
X363149Y2737494D01*
X363949Y2737627D01*
X364749Y2737494D01*
X365449Y2736960D01*
X366049Y2736160D01*
X366449Y2735227D01*
X366649Y2734160D01*
Y2733094D01*
X366449Y2732027D01*
X366049Y2731094D01*
X365449Y2730294D01*
X364749Y2729760D01*
X363949Y2729627D01*
G01X364749Y2731760D02*
X365949Y2729627D01*
G01X369749Y2737627D02*
Y2731894D01*
X370149Y2730693D01*
X370949Y2729894D01*
X371949Y2729627D01*
X372949Y2729894D01*
X373749Y2730693D01*
X374149Y2731894D01*
Y2737627D01*
G01X378749D02*
X381149D01*
G01X379949D02*
Y2729627D01*
G01X378749D02*
X381149D01*
G01X385949D02*
Y2737627D01*
X388449D01*
X389249Y2737227D01*
X389749Y2736694D01*
X389949Y2735627D01*
X389749Y2734560D01*
X389149Y2733894D01*
X388449Y2733494D01*
X385949D01*
G01X388449D02*
X389949Y2729627D01*
G01X397949D02*
X393949D01*
Y2737627D01*
X397949D01*
G01X396349Y2733760D02*
X393949D01*
G01X401749Y2729627D02*
Y2737627D01*
X403749D01*
X404549Y2737227D01*
X405149Y2736694D01*
X405649Y2735894D01*
X406049Y2734960D01*
X406149Y2733627D01*
X406049Y2732294D01*
X405649Y2731360D01*
X405149Y2730560D01*
X404549Y2730027D01*
X403749Y2729627D01*
X401749D01*
G01X-65851Y2751960D02*
X-66451Y2752360D01*
X-67151Y2752627D01*
X-67951D01*
X-68851Y2752227D01*
X-69551Y2751560D01*
X-70051Y2750760D01*
X-70451Y2749427D01*
X-70551Y2748227D01*
X-70351Y2747027D01*
X-70051Y2746227D01*
X-69451Y2745427D01*
X-68751Y2744894D01*
X-68051Y2744627D01*
X-67351D01*
X-66651Y2744894D01*
X-66051Y2745294D01*
X-65551Y2745827D01*
G01X-62151Y2744627D02*
Y2752627D01*
G01X-57951D02*
Y2744627D01*
G01Y2748627D02*
X-62151D01*
G01X-54551Y2744627D02*
X-52051Y2752627D01*
X-49551Y2744627D01*
G01X-50451Y2747427D02*
X-53651D01*
G01X-46051Y2744627D02*
Y2752627D01*
X-43551D01*
X-42751Y2752227D01*
X-42251Y2751694D01*
X-42051Y2750627D01*
X-42251Y2749560D01*
X-42851Y2748894D01*
X-43551Y2748494D01*
X-46051D01*
G01X-43551D02*
X-42051Y2744627D01*
G01X-36051Y2752627D02*
Y2744627D01*
G01X-38351Y2752627D02*
X-33751D01*
G01X-28051Y2744360D02*
X-28251Y2744494D01*
Y2744760D01*
X-28051Y2744894D01*
X-27851Y2744760D01*
Y2744494D01*
X-28051Y2744360D01*
G01X-14651Y2744627D02*
Y2752627D01*
X-12051Y2745960D01*
X-9451Y2752627D01*
Y2744627D01*
G01X-6551D02*
X-4051Y2752627D01*
X-1551Y2744627D01*
G01X-2451Y2747427D02*
X-5651D01*
G01X1649Y2744627D02*
Y2752627D01*
X6249Y2744627D01*
Y2752627D01*
G01X9749D02*
Y2746894D01*
X10149Y2745693D01*
X10949Y2744894D01*
X11949Y2744627D01*
X12949Y2744894D01*
X13749Y2745693D01*
X14149Y2746894D01*
Y2752627D01*
G01X18049Y2744627D02*
Y2752627D01*
X21849D01*
G01X20449Y2748760D02*
X18049D01*
G01X25449Y2744627D02*
X27949Y2752627D01*
X30449Y2744627D01*
G01X29549Y2747427D02*
X26349D01*
G01X38149Y2751960D02*
X37549Y2752360D01*
X36849Y2752627D01*
X36049D01*
X35149Y2752227D01*
X34449Y2751560D01*
X33949Y2750760D01*
X33549Y2749427D01*
X33449Y2748227D01*
X33649Y2747027D01*
X33949Y2746227D01*
X34549Y2745427D01*
X35249Y2744894D01*
X35949Y2744627D01*
X36649D01*
X37349Y2744894D01*
X37949Y2745294D01*
X38449Y2745827D01*
G01X43949Y2752627D02*
Y2744627D01*
G01X41649Y2752627D02*
X46249D01*
G01X49749D02*
Y2746894D01*
X50149Y2745693D01*
X50949Y2744894D01*
X51949Y2744627D01*
X52949Y2744894D01*
X53749Y2745693D01*
X54149Y2746894D01*
Y2752627D01*
G01X57949Y2744627D02*
Y2752627D01*
X60449D01*
X61249Y2752227D01*
X61749Y2751694D01*
X61949Y2750627D01*
X61749Y2749560D01*
X61149Y2748894D01*
X60449Y2748494D01*
X57949D01*
G01X60449D02*
X61949Y2744627D01*
G01X69949D02*
X65949D01*
Y2752627D01*
X69949D01*
G01X68349Y2748760D02*
X65949D01*
G01X73949Y2744627D02*
Y2752627D01*
X76449D01*
X77249Y2752227D01*
X77749Y2751694D01*
X77949Y2750627D01*
X77749Y2749560D01*
X77149Y2748894D01*
X76449Y2748494D01*
X73949D01*
G01X76449D02*
X77949Y2744627D01*
G01X90749Y2752627D02*
X93149D01*
G01X91949D02*
Y2744627D01*
G01X90749D02*
X93149D01*
G01X97849Y2745693D02*
X98649Y2745027D01*
X99549Y2744627D01*
X100349D01*
X101149Y2745027D01*
X101749Y2745693D01*
X102049Y2746627D01*
X101849Y2747560D01*
X101349Y2748360D01*
X100449Y2748894D01*
X99249Y2749160D01*
X98549Y2749694D01*
X98249Y2750627D01*
X98449Y2751560D01*
X98949Y2752227D01*
X99649Y2752627D01*
X100349D01*
X101049Y2752360D01*
X101649Y2751694D01*
G01X114049Y2744627D02*
Y2752627D01*
X117849D01*
G01X116449Y2748760D02*
X114049D01*
G01X121949Y2744627D02*
Y2752627D01*
X124449D01*
X125249Y2752227D01*
X125749Y2751694D01*
X125949Y2750627D01*
X125749Y2749560D01*
X125149Y2748894D01*
X124449Y2748494D01*
X121949D01*
G01X124449D02*
X125949Y2744627D01*
G01X133949D02*
X129949D01*
Y2752627D01*
X133949D01*
G01X132349Y2748760D02*
X129949D01*
G01X141949Y2744627D02*
X137949D01*
Y2752627D01*
X141949D01*
G01X140349Y2748760D02*
X137949D01*
G01X155949Y2752627D02*
Y2744627D01*
G01X153649Y2752627D02*
X158249D01*
G01X163949Y2744627D02*
X163149Y2744760D01*
X162449Y2745294D01*
X161849Y2746094D01*
X161449Y2747027D01*
X161249Y2748094D01*
Y2749160D01*
X161449Y2750227D01*
X161849Y2751160D01*
X162449Y2751960D01*
X163149Y2752494D01*
X163949Y2752627D01*
X164749Y2752494D01*
X165449Y2751960D01*
X166049Y2751160D01*
X166449Y2750227D01*
X166649Y2749160D01*
Y2748094D01*
X166449Y2747027D01*
X166049Y2746094D01*
X165449Y2745294D01*
X164749Y2744760D01*
X163949Y2744627D01*
G01X177449D02*
X179949Y2752627D01*
X182449Y2744627D01*
G01X181549Y2747427D02*
X178349D01*
G01X185749Y2744627D02*
Y2752627D01*
X187749D01*
X188549Y2752227D01*
X189149Y2751694D01*
X189649Y2750894D01*
X190049Y2749960D01*
X190149Y2748627D01*
X190049Y2747294D01*
X189649Y2746360D01*
X189149Y2745560D01*
X188549Y2745027D01*
X187749Y2744627D01*
X185749D01*
G01X193949Y2746227D02*
X194449Y2745427D01*
X195049Y2744894D01*
X195749Y2744627D01*
X196549Y2744894D01*
X197149Y2745427D01*
X197749Y2746227D01*
X197949Y2747294D01*
Y2752627D01*
G01X201749D02*
Y2746894D01*
X202149Y2745693D01*
X202949Y2744894D01*
X203949Y2744627D01*
X204949Y2744894D01*
X205749Y2745693D01*
X206149Y2746894D01*
Y2752627D01*
G01X209849Y2745693D02*
X210649Y2745027D01*
X211549Y2744627D01*
X212349D01*
X213149Y2745027D01*
X213749Y2745693D01*
X214049Y2746627D01*
X213849Y2747560D01*
X213349Y2748360D01*
X212449Y2748894D01*
X211249Y2749160D01*
X210549Y2749694D01*
X210249Y2750627D01*
X210449Y2751560D01*
X210949Y2752227D01*
X211649Y2752627D01*
X212349D01*
X213049Y2752360D01*
X213649Y2751694D01*
G01X219949Y2752627D02*
Y2744627D01*
G01X217649Y2752627D02*
X222249D01*
G01X235949D02*
Y2744627D01*
G01X233649Y2752627D02*
X238249D01*
G01X241949Y2744627D02*
Y2752627D01*
X244449D01*
X245249Y2752227D01*
X245749Y2751694D01*
X245949Y2750627D01*
X245749Y2749560D01*
X245149Y2748894D01*
X244449Y2748494D01*
X241949D01*
G01X244449D02*
X245949Y2744627D01*
G01X249449D02*
X251949Y2752627D01*
X254449Y2744627D01*
G01X253549Y2747427D02*
X250349D01*
G01X262149Y2751960D02*
X261549Y2752360D01*
X260849Y2752627D01*
X260049D01*
X259149Y2752227D01*
X258449Y2751560D01*
X257949Y2750760D01*
X257549Y2749427D01*
X257449Y2748227D01*
X257649Y2747027D01*
X257949Y2746227D01*
X258549Y2745427D01*
X259249Y2744894D01*
X259949Y2744627D01*
X260649D01*
X261349Y2744894D01*
X261949Y2745294D01*
X262449Y2745827D01*
G01X269949Y2744627D02*
X265949D01*
Y2752627D01*
X269949D01*
G01X268349Y2748760D02*
X265949D01*
G01X280949Y2752627D02*
X282349Y2744627D01*
X283949Y2752627D01*
X285549Y2744627D01*
X286949Y2752627D01*
G01X290749D02*
X293149D01*
G01X291949D02*
Y2744627D01*
G01X290749D02*
X293149D01*
G01X297749D02*
Y2752627D01*
X299749D01*
X300549Y2752227D01*
X301149Y2751694D01*
X301649Y2750894D01*
X302049Y2749960D01*
X302149Y2748627D01*
X302049Y2747294D01*
X301649Y2746360D01*
X301149Y2745560D01*
X300549Y2745027D01*
X299749Y2744627D01*
X297749D01*
G01X307949Y2752627D02*
Y2744627D01*
G01X305649Y2752627D02*
X310249D01*
G01X313849Y2744627D02*
Y2752627D01*
G01X318049D02*
Y2744627D01*
G01Y2748627D02*
X313849D01*
G01X321849Y2745693D02*
X322649Y2745027D01*
X323549Y2744627D01*
X324349D01*
X325149Y2745027D01*
X325749Y2745693D01*
X326049Y2746627D01*
X325849Y2747560D01*
X325349Y2748360D01*
X324449Y2748894D01*
X323249Y2749160D01*
X322549Y2749694D01*
X322249Y2750627D01*
X322449Y2751560D01*
X322949Y2752227D01*
X323649Y2752627D01*
X324349D01*
X325049Y2752360D01*
X325649Y2751694D01*
G01X331749Y2743160D02*
X332149Y2744894D01*
G01X353749Y2744627D02*
Y2752627D01*
X355749D01*
X356549Y2752227D01*
X357149Y2751694D01*
X357649Y2750894D01*
X358049Y2749960D01*
X358149Y2748627D01*
X358049Y2747294D01*
X357649Y2746360D01*
X357149Y2745560D01*
X356549Y2745027D01*
X355749Y2744627D01*
X353749D01*
G01X362749Y2752627D02*
X365149D01*
G01X363949D02*
Y2744627D01*
G01X362749D02*
X365149D01*
G01X373949D02*
X369949D01*
Y2752627D01*
X373949D01*
G01X372349Y2748760D02*
X369949D01*
G01X377949Y2752627D02*
Y2744627D01*
X381949D01*
G01X389949D02*
X385949D01*
Y2752627D01*
X389949D01*
G01X388349Y2748760D02*
X385949D01*
G01X398149Y2751960D02*
X397549Y2752360D01*
X396849Y2752627D01*
X396049D01*
X395149Y2752227D01*
X394449Y2751560D01*
X393949Y2750760D01*
X393549Y2749427D01*
X393449Y2748227D01*
X393649Y2747027D01*
X393949Y2746227D01*
X394549Y2745427D01*
X395249Y2744894D01*
X395949Y2744627D01*
X396649D01*
X397349Y2744894D01*
X397949Y2745294D01*
X398449Y2745827D01*
G01X403949Y2752627D02*
Y2744627D01*
G01X401649Y2752627D02*
X406249D01*
G01X409949Y2744627D02*
Y2752627D01*
X412449D01*
X413249Y2752227D01*
X413749Y2751694D01*
X413949Y2750627D01*
X413749Y2749560D01*
X413149Y2748894D01*
X412449Y2748494D01*
X409949D01*
G01X412449D02*
X413949Y2744627D01*
G01X418749Y2752627D02*
X421149D01*
G01X419949D02*
Y2744627D01*
G01X418749D02*
X421149D01*
G01X430149Y2751960D02*
X429549Y2752360D01*
X428849Y2752627D01*
X428049D01*
X427149Y2752227D01*
X426449Y2751560D01*
X425949Y2750760D01*
X425549Y2749427D01*
X425449Y2748227D01*
X425649Y2747027D01*
X425949Y2746227D01*
X426549Y2745427D01*
X427249Y2744894D01*
X427949Y2744627D01*
X428649D01*
X429349Y2744894D01*
X429949Y2745294D01*
X430449Y2745827D01*
G01X-3000Y0D02*
X-36584D01*
G01X62354Y114960D02*
X-35948D01*
G01X54735Y181976D02*
X-25169D01*
G01X62354Y464960D02*
X-44032D01*
G01X55995Y543701D02*
X-45043D01*
G01X62354Y814960D02*
X-28537D01*
G01X17472Y1050669D02*
X-26582D01*
G01X55995Y1587992D02*
X-30792D01*
G01X54735Y1922291D02*
X-33808D01*
G01X54735Y2026661D02*
X-36503D01*
G01X-4000Y-62500D02*
Y-137500D01*
X496000D01*
Y-62500D01*
X-4000D01*
G01X0Y-3000D02*
Y-26333D01*
G01X104331Y0D02*
X397638D01*
G03X405512Y7874I0J7874D01*
G01Y2078740D01*
G03X397638Y2086614I-7874J0D01*
G01X104331D01*
G03X98425Y2080709I0J-5906D01*
G01Y2076772D01*
G02X92520Y2070866I-5905J-1D01*
G01X5906D01*
G03X0Y2064961I-1J-5905D01*
G01Y21654D01*
G03X5906Y15748I5906J0D01*
G01X92520D01*
G02X98425Y9843I0J-5905D01*
G01Y5906D01*
G03X104331Y0I5906J0D01*
G01X54735Y59953D02*
X-20908D01*
G01X54735Y268811D02*
X-8327D01*
G01X54735Y390834D02*
X-23484D01*
G01X62354Y1164960D02*
X-20335D01*
G01X62354Y1514960D02*
X-20687D01*
G01X62354Y1864961D02*
X-21346D01*
G01X24783Y2304560D02*
X-6713D01*
G01D02*
X34626D01*
G01X5098Y2374442D02*
G03I-2953J0D01*
G01X-14587D02*
G03I-2953J0D01*
G01X5098Y2394127D02*
G03I-2953J0D01*
G01X-14587D02*
G03I-2953J0D01*
G01X-20492Y2436449D02*
X554311D01*
G01X-20492Y2452197D02*
Y2436449D01*
G01Y2456134D02*
X554311D01*
G01Y2452197D02*
X-20492D01*
G01Y2471883D02*
Y2456134D01*
G01X554311Y2471883D02*
X-20492D01*
G01Y2475820D02*
Y2546686D01*
G01Y2538812D02*
X274783D01*
G01X8000Y-127500D02*
Y-132500D01*
G01X6543Y-127500D02*
X9457D01*
G01X14367Y-132500D02*
X11833D01*
Y-127500D01*
X14367D01*
G01X13353Y-129917D02*
X11833D01*
G01X16933Y-127500D02*
Y-132500D01*
X19467D01*
G01X23300Y-132667D02*
X23173Y-132583D01*
Y-132417D01*
X23300Y-132333D01*
X23427Y-132417D01*
Y-132583D01*
X23300Y-132667D01*
G01Y-130417D02*
X23173Y-130333D01*
Y-130167D01*
X23300Y-130083D01*
X23427Y-130167D01*
Y-130333D01*
X23300Y-130417D01*
G01X28083Y-134167D02*
X27450Y-133333D01*
X27133Y-132500D01*
Y-129167D01*
X27450Y-128333D01*
X28083Y-127500D01*
G01X33500D02*
X32993Y-127667D01*
X32613Y-128083D01*
X32360Y-128583D01*
X32170Y-129250D01*
X32107Y-130000D01*
X32170Y-130750D01*
X32360Y-131417D01*
X32613Y-131917D01*
X32993Y-132333D01*
X33500Y-132500D01*
X34007Y-132333D01*
X34387Y-131917D01*
X34640Y-131417D01*
X34830Y-130750D01*
X34893Y-130000D01*
X34830Y-129250D01*
X34640Y-128583D01*
X34387Y-128083D01*
X34007Y-127667D01*
X33500Y-127500D01*
G01X37207Y-131500D02*
X37587Y-132083D01*
X38093Y-132417D01*
X38663Y-132500D01*
X39170Y-132417D01*
X39677Y-132000D01*
X39993Y-131500D01*
X40057Y-131000D01*
X39930Y-130417D01*
X39487Y-130000D01*
X39043Y-129833D01*
X38473D01*
G01X39043D02*
X39423Y-129583D01*
X39740Y-129167D01*
X39867Y-128667D01*
X39740Y-128167D01*
X39423Y-127750D01*
X38853Y-127500D01*
X38283Y-127583D01*
X37713Y-127917D01*
G01X44017Y-134167D02*
X44650Y-133333D01*
X44967Y-132500D01*
Y-129167D01*
X44650Y-128333D01*
X44017Y-127500D01*
G01X47407Y-131500D02*
X47787Y-132083D01*
X48293Y-132417D01*
X48863Y-132500D01*
X49370Y-132417D01*
X49877Y-132000D01*
X50193Y-131500D01*
X50257Y-131000D01*
X50130Y-130417D01*
X49687Y-130000D01*
X49243Y-129833D01*
X48673D01*
G01X49243D02*
X49623Y-129583D01*
X49940Y-129167D01*
X50067Y-128667D01*
X49940Y-128167D01*
X49623Y-127750D01*
X49053Y-127500D01*
X48483Y-127583D01*
X47913Y-127917D01*
G01X52697Y-128333D02*
X53077Y-127833D01*
X53520Y-127583D01*
X54027Y-127500D01*
X54660Y-127667D01*
X55103Y-128083D01*
X55230Y-128583D01*
X55167Y-129083D01*
X54913Y-129500D01*
X53647Y-130333D01*
X53077Y-130917D01*
X52697Y-131750D01*
X52570Y-132500D01*
X55230D01*
G01X58873D02*
X59000Y-131417D01*
X59190Y-130500D01*
X59443Y-129667D01*
X59760Y-128750D01*
X60267Y-127500D01*
X57733D01*
G01X63277Y-130833D02*
X64923D01*
G01X67997Y-128333D02*
X68377Y-127833D01*
X68820Y-127583D01*
X69327Y-127500D01*
X69960Y-127667D01*
X70403Y-128083D01*
X70530Y-128583D01*
X70467Y-129083D01*
X70213Y-129500D01*
X68947Y-130333D01*
X68377Y-130917D01*
X67997Y-131750D01*
X67870Y-132500D01*
X70530D01*
G01X72907Y-131500D02*
X73287Y-132083D01*
X73793Y-132417D01*
X74363Y-132500D01*
X74870Y-132417D01*
X75377Y-132000D01*
X75693Y-131500D01*
X75757Y-131000D01*
X75630Y-130417D01*
X75187Y-130000D01*
X74743Y-129833D01*
X74173D01*
G01X74743D02*
X75123Y-129583D01*
X75440Y-129167D01*
X75567Y-128667D01*
X75440Y-128167D01*
X75123Y-127750D01*
X74553Y-127500D01*
X73983Y-127583D01*
X73413Y-127917D01*
G01X80160Y-132500D02*
Y-127500D01*
X77817Y-131083D01*
X80983D01*
G01X83107Y-131750D02*
X83487Y-132167D01*
X83930Y-132417D01*
X84500Y-132500D01*
X85070Y-132333D01*
X85513Y-132000D01*
X85830Y-131417D01*
X85893Y-130750D01*
X85767Y-130083D01*
X85450Y-129667D01*
X85007Y-129333D01*
X84563Y-129250D01*
X84120Y-129333D01*
X83550Y-129667D01*
X83740Y-127500D01*
X85450D01*
G01X93497Y-132500D02*
Y-127500D01*
X95903D01*
G01X95017Y-129917D02*
X93497D01*
G01X98217Y-132500D02*
X99800Y-127500D01*
X101383Y-132500D01*
G01X100813Y-130750D02*
X98787D01*
G01X103570Y-132500D02*
X106230Y-127500D01*
G01X103570D02*
X106230Y-132500D01*
G01X110000Y-132667D02*
X109873Y-132583D01*
Y-132417D01*
X110000Y-132333D01*
X110127Y-132417D01*
Y-132583D01*
X110000Y-132667D01*
G01Y-130417D02*
X109873Y-130333D01*
Y-130167D01*
X110000Y-130083D01*
X110127Y-130167D01*
Y-130333D01*
X110000Y-130417D01*
G01X114783Y-134167D02*
X114150Y-133333D01*
X113833Y-132500D01*
Y-129167D01*
X114150Y-128333D01*
X114783Y-127500D01*
G01X120200D02*
X119693Y-127667D01*
X119313Y-128083D01*
X119060Y-128583D01*
X118870Y-129250D01*
X118807Y-130000D01*
X118870Y-130750D01*
X119060Y-131417D01*
X119313Y-131917D01*
X119693Y-132333D01*
X120200Y-132500D01*
X120707Y-132333D01*
X121087Y-131917D01*
X121340Y-131417D01*
X121530Y-130750D01*
X121593Y-130000D01*
X121530Y-129250D01*
X121340Y-128583D01*
X121087Y-128083D01*
X120707Y-127667D01*
X120200Y-127500D01*
G01X123907Y-131500D02*
X124287Y-132083D01*
X124793Y-132417D01*
X125363Y-132500D01*
X125870Y-132417D01*
X126377Y-132000D01*
X126693Y-131500D01*
X126757Y-131000D01*
X126630Y-130417D01*
X126187Y-130000D01*
X125743Y-129833D01*
X125173D01*
G01X125743D02*
X126123Y-129583D01*
X126440Y-129167D01*
X126567Y-128667D01*
X126440Y-128167D01*
X126123Y-127750D01*
X125553Y-127500D01*
X124983Y-127583D01*
X124413Y-127917D01*
G01X130717Y-134167D02*
X131350Y-133333D01*
X131667Y-132500D01*
Y-129167D01*
X131350Y-128333D01*
X130717Y-127500D01*
G01X134107Y-131500D02*
X134487Y-132083D01*
X134993Y-132417D01*
X135563Y-132500D01*
X136070Y-132417D01*
X136577Y-132000D01*
X136893Y-131500D01*
X136957Y-131000D01*
X136830Y-130417D01*
X136387Y-130000D01*
X135943Y-129833D01*
X135373D01*
G01X135943D02*
X136323Y-129583D01*
X136640Y-129167D01*
X136767Y-128667D01*
X136640Y-128167D01*
X136323Y-127750D01*
X135753Y-127500D01*
X135183Y-127583D01*
X134613Y-127917D01*
G01X139523Y-131917D02*
X139967Y-132333D01*
X140473Y-132500D01*
X140980Y-132333D01*
X141423Y-131833D01*
X141740Y-131083D01*
X141867Y-130333D01*
Y-129417D01*
X141740Y-128667D01*
X141423Y-128000D01*
X141043Y-127667D01*
X140600Y-127500D01*
X140093Y-127667D01*
X139713Y-128000D01*
X139460Y-128500D01*
X139333Y-129167D01*
X139460Y-129750D01*
X139777Y-130333D01*
X140157Y-130667D01*
X140600Y-130750D01*
X141107Y-130583D01*
X141487Y-130167D01*
X141867Y-129417D01*
G01X145573Y-132500D02*
X145700Y-131417D01*
X145890Y-130500D01*
X146143Y-129667D01*
X146460Y-128750D01*
X146967Y-127500D01*
X144433D01*
G01X149977Y-130833D02*
X151623D01*
G01X154507Y-131500D02*
X154887Y-132083D01*
X155393Y-132417D01*
X155963Y-132500D01*
X156470Y-132417D01*
X156977Y-132000D01*
X157293Y-131500D01*
X157357Y-131000D01*
X157230Y-130417D01*
X156787Y-130000D01*
X156343Y-129833D01*
X155773D01*
G01X156343D02*
X156723Y-129583D01*
X157040Y-129167D01*
X157167Y-128667D01*
X157040Y-128167D01*
X156723Y-127750D01*
X156153Y-127500D01*
X155583Y-127583D01*
X155013Y-127917D01*
G01X159797Y-130417D02*
X160240Y-129833D01*
X160620Y-129500D01*
X161127Y-129333D01*
X161570Y-129500D01*
X161887Y-129833D01*
X162140Y-130333D01*
X162203Y-130917D01*
X162140Y-131417D01*
X161887Y-131917D01*
X161507Y-132333D01*
X161063Y-132500D01*
X160557Y-132333D01*
X160113Y-131833D01*
X159860Y-131083D01*
X159797Y-130250D01*
X159923Y-129167D01*
X160113Y-128583D01*
X160430Y-128000D01*
X160873Y-127583D01*
X161317Y-127500D01*
X161760Y-127667D01*
X162077Y-128083D01*
G01X166100Y-132500D02*
Y-127500D01*
X165340Y-128500D01*
G01Y-132500D02*
X166860D01*
G01X171960D02*
Y-127500D01*
X169617Y-131083D01*
X172783D01*
G01X12735Y2023661D02*
Y-3610D01*
G01X20472Y1047669D02*
Y-3496D01*
X25027Y-11075D01*
G01X17139Y2285802D02*
X18069Y2284760D01*
X19154Y2284135D01*
X20549Y2283927D01*
X21944Y2284344D01*
X23029Y2285177D01*
X23804Y2286635D01*
X23959Y2288302D01*
X23649Y2289969D01*
X22874Y2291010D01*
X21789Y2291844D01*
X20704Y2292052D01*
X19619Y2291844D01*
X18224Y2291010D01*
X18689Y2296427D01*
X22874D01*
G01X28919Y2283927D02*
Y2296427D01*
X32949Y2286010D01*
X36979Y2296427D01*
Y2283927D01*
G01X41319D02*
Y2296427D01*
X45349Y2286010D01*
X49379Y2296427D01*
Y2283927D01*
G01X24783Y2374442D02*
G03I-2953J0D01*
G01Y2394127D02*
G03I-2953J0D01*
G01X75964Y2277001D02*
X44468D01*
G01D02*
X85807D01*
G01X24783Y2366940D02*
Y2296686D01*
G01X44468Y2367290D02*
Y2296686D01*
G01Y2304560D02*
X75964D01*
G01D02*
X34626D01*
G01X50374Y2371489D02*
X44468D01*
G01D02*
Y2377394D01*
G01Y2397079D02*
X50374D01*
G01Y2391174D02*
X44468D01*
G01Y2377394D02*
X50374D01*
G01X44468Y2391174D02*
Y2397079D01*
G01X50627Y-31619D02*
Y-32545D01*
G01X65354Y1861961D02*
Y-13715D01*
G01X57735Y2023661D02*
Y-5345D01*
G01X70139Y2254402D02*
X71069Y2253360D01*
X72154Y2252735D01*
X73549Y2252527D01*
X74944Y2252944D01*
X76029Y2253777D01*
X76804Y2255235D01*
X76959Y2256902D01*
X76649Y2258569D01*
X75874Y2259610D01*
X74789Y2260444D01*
X73704Y2260652D01*
X72619Y2260444D01*
X71224Y2259610D01*
X71689Y2265027D01*
X75874D01*
G01X81919Y2252527D02*
Y2265027D01*
X85949Y2254610D01*
X89979Y2265027D01*
Y2252527D01*
G01X94319D02*
Y2265027D01*
X98349Y2254610D01*
X102379Y2265027D01*
Y2252527D01*
G01X95649Y2328702D02*
X64153D01*
G01D02*
X98602D01*
G01X75964Y2371489D02*
X70059D01*
G01D02*
Y2377394D01*
G01X50374D02*
Y2371489D01*
G01X70059Y2397079D02*
X75964D01*
G01Y2391174D02*
X70059D01*
G01Y2377394D02*
X75964D01*
G01X70059Y2391174D02*
Y2397079D01*
G01X50374D02*
Y2391174D01*
G01X95649Y2367552D02*
Y2269127D01*
G01Y2277001D02*
X127145D01*
G01D02*
X85807D01*
G01X75964Y2367552D02*
Y2269127D01*
G01X95649Y2363368D02*
Y2320828D01*
G01X101555Y2371489D02*
X95649D01*
G01D02*
Y2377394D01*
G01X75964D02*
Y2371489D01*
G01X95649Y2397079D02*
X101555D01*
G01Y2391174D02*
X95649D01*
G01Y2377394D02*
X101555D01*
G01X95649Y2391174D02*
Y2397079D01*
G01X75964D02*
Y2391174D01*
G01X98425Y2083709D02*
Y2101797D01*
G01X101555Y2366867D02*
Y2320828D01*
G01X125564Y2331655D02*
Y2344155D01*
X123704Y2341655D01*
G01Y2331655D02*
X127424D01*
G01X137964Y2331238D02*
X137654Y2331447D01*
Y2331863D01*
X137964Y2332072D01*
X138274Y2331863D01*
Y2331447D01*
X137964Y2331238D01*
G01X146954Y2333530D02*
X147884Y2332488D01*
X148969Y2331863D01*
X150364Y2331655D01*
X151759Y2332072D01*
X152844Y2332905D01*
X153619Y2334363D01*
X153774Y2336030D01*
X153464Y2337697D01*
X152689Y2338738D01*
X151604Y2339572D01*
X150519Y2339780D01*
X149434Y2339572D01*
X148039Y2338738D01*
X148504Y2344155D01*
X152689D01*
G01X158734Y2331655D02*
Y2344155D01*
X162764Y2333738D01*
X166794Y2344155D01*
Y2331655D01*
G01X171134D02*
Y2344155D01*
X175164Y2333738D01*
X179194Y2344155D01*
Y2331655D01*
G01X101555Y2328702D02*
X168081D01*
G01D02*
X98602D01*
G01X101555Y2377394D02*
Y2371489D01*
G01Y2397079D02*
Y2391174D01*
G01X105492D02*
X225222D01*
G01X105492Y2397079D02*
X225222D01*
G01X163385Y1949205D02*
Y-7534D01*
G01X166385Y27205D02*
X413331D01*
G01X166385Y202205D02*
X415082D01*
G01X166385Y377205D02*
X406998D01*
G01X166386Y552205D02*
X421650D01*
G01X166386Y727205D02*
X423150D01*
G01X166385Y902205D02*
X432935D01*
G01X166385Y1077205D02*
X417658D01*
G01X166385Y1252205D02*
X456059D01*
G01X166385Y1427205D02*
X443932D01*
G01X166385Y1602205D02*
X417978D01*
G01X166385Y1777205D02*
X445280D01*
G01X166385Y1952205D02*
X430122D01*
G01X169849Y2850693D02*
X170649Y2850027D01*
X171549Y2849627D01*
X172349D01*
X173149Y2850027D01*
X173749Y2850693D01*
X174049Y2851627D01*
X173849Y2852560D01*
X173349Y2853360D01*
X172449Y2853894D01*
X171249Y2854160D01*
X170549Y2854694D01*
X170249Y2855627D01*
X170449Y2856560D01*
X170949Y2857227D01*
X171649Y2857627D01*
X172349D01*
X173049Y2857360D01*
X173649Y2856694D01*
G01X179949Y2849627D02*
X179149Y2849760D01*
X178449Y2850294D01*
X177849Y2851094D01*
X177449Y2852027D01*
X177249Y2853094D01*
Y2854160D01*
X177449Y2855227D01*
X177849Y2856160D01*
X178449Y2856960D01*
X179149Y2857494D01*
X179949Y2857627D01*
X180749Y2857494D01*
X181449Y2856960D01*
X182049Y2856160D01*
X182449Y2855227D01*
X182649Y2854160D01*
Y2853094D01*
X182449Y2852027D01*
X182049Y2851094D01*
X181449Y2850294D01*
X180749Y2849760D01*
X179949Y2849627D01*
G01X185949Y2857627D02*
Y2849627D01*
X189949D01*
G01X193749D02*
Y2857627D01*
X195749D01*
X196549Y2857227D01*
X197149Y2856694D01*
X197649Y2855894D01*
X198049Y2854960D01*
X198149Y2853627D01*
X198049Y2852294D01*
X197649Y2851360D01*
X197149Y2850560D01*
X196549Y2850027D01*
X195749Y2849627D01*
X193749D01*
G01X205949D02*
X201949D01*
Y2857627D01*
X205949D01*
G01X204349Y2853760D02*
X201949D01*
G01X209949Y2849627D02*
Y2857627D01*
X212449D01*
X213249Y2857227D01*
X213749Y2856694D01*
X213949Y2855627D01*
X213749Y2854560D01*
X213149Y2853894D01*
X212449Y2853494D01*
X209949D01*
G01X212449D02*
X213949Y2849627D01*
G01X217349D02*
Y2857627D01*
X219949Y2850960D01*
X222549Y2857627D01*
Y2849627D01*
G01X225449D02*
X227949Y2857627D01*
X230449Y2849627D01*
G01X229549Y2852427D02*
X226349D01*
G01X233849Y2850693D02*
X234649Y2850027D01*
X235549Y2849627D01*
X236349D01*
X237149Y2850027D01*
X237749Y2850693D01*
X238049Y2851627D01*
X237849Y2852560D01*
X237349Y2853360D01*
X236449Y2853894D01*
X235249Y2854160D01*
X234549Y2854694D01*
X234249Y2855627D01*
X234449Y2856560D01*
X234949Y2857227D01*
X235649Y2857627D01*
X236349D01*
X237049Y2857360D01*
X237649Y2856694D01*
G01X241749Y2849627D02*
Y2857627D01*
G01X245549D02*
X241749Y2852693D01*
G01X246149Y2849627D02*
X243449Y2854960D01*
G01X259949Y2849627D02*
X259149Y2849760D01*
X258449Y2850294D01*
X257849Y2851094D01*
X257449Y2852027D01*
X257249Y2853094D01*
Y2854160D01*
X257449Y2855227D01*
X257849Y2856160D01*
X258449Y2856960D01*
X259149Y2857494D01*
X259949Y2857627D01*
X260749Y2857494D01*
X261449Y2856960D01*
X262049Y2856160D01*
X262449Y2855227D01*
X262649Y2854160D01*
Y2853094D01*
X262449Y2852027D01*
X262049Y2851094D01*
X261449Y2850294D01*
X260749Y2849760D01*
X259949Y2849627D01*
G01X265949D02*
Y2857627D01*
X268349D01*
X269149Y2857227D01*
X269749Y2856294D01*
X269949Y2855227D01*
X269749Y2854160D01*
X269249Y2853360D01*
X268349Y2852960D01*
X265949D01*
G01X277949Y2849627D02*
X273949D01*
Y2857627D01*
X277949D01*
G01X276349Y2853760D02*
X273949D01*
G01X281649Y2849627D02*
Y2857627D01*
X286249Y2849627D01*
Y2857627D01*
G01X299949Y2849627D02*
X299149Y2849760D01*
X298449Y2850294D01*
X297849Y2851094D01*
X297449Y2852027D01*
X297249Y2853094D01*
Y2854160D01*
X297449Y2855227D01*
X297849Y2856160D01*
X298449Y2856960D01*
X299149Y2857494D01*
X299949Y2857627D01*
X300749Y2857494D01*
X301449Y2856960D01*
X302049Y2856160D01*
X302449Y2855227D01*
X302649Y2854160D01*
Y2853094D01*
X302449Y2852027D01*
X302049Y2851094D01*
X301449Y2850294D01*
X300749Y2849760D01*
X299949Y2849627D01*
G01X305649D02*
Y2857627D01*
X310249Y2849627D01*
Y2857627D01*
G01X324749Y2853894D02*
X325149Y2854294D01*
X325449Y2854960D01*
X325649Y2855894D01*
X325449Y2856694D01*
X325049Y2857227D01*
X324349Y2857627D01*
X321649D01*
Y2849627D01*
X324949D01*
X325649Y2850160D01*
X326049Y2850960D01*
X326249Y2851894D01*
X326049Y2852827D01*
X325449Y2853627D01*
X324749Y2853894D01*
X321649D01*
G01X331949Y2849627D02*
X331149Y2849760D01*
X330449Y2850294D01*
X329849Y2851094D01*
X329449Y2852027D01*
X329249Y2853094D01*
Y2854160D01*
X329449Y2855227D01*
X329849Y2856160D01*
X330449Y2856960D01*
X331149Y2857494D01*
X331949Y2857627D01*
X332749Y2857494D01*
X333449Y2856960D01*
X334049Y2856160D01*
X334449Y2855227D01*
X334649Y2854160D01*
Y2853094D01*
X334449Y2852027D01*
X334049Y2851094D01*
X333449Y2850294D01*
X332749Y2849760D01*
X331949Y2849627D01*
G01X339949Y2857627D02*
Y2849627D01*
G01X337649Y2857627D02*
X342249D01*
G01X345849Y2849627D02*
Y2857627D01*
G01X350049D02*
Y2849627D01*
G01Y2853627D02*
X345849D01*
G01X361849Y2850693D02*
X362649Y2850027D01*
X363549Y2849627D01*
X364349D01*
X365149Y2850027D01*
X365749Y2850693D01*
X366049Y2851627D01*
X365849Y2852560D01*
X365349Y2853360D01*
X364449Y2853894D01*
X363249Y2854160D01*
X362549Y2854694D01*
X362249Y2855627D01*
X362449Y2856560D01*
X362949Y2857227D01*
X363649Y2857627D01*
X364349D01*
X365049Y2857360D01*
X365649Y2856694D01*
G01X370749Y2857627D02*
X373149D01*
G01X371949D02*
Y2849627D01*
G01X370749D02*
X373149D01*
G01X377749D02*
Y2857627D01*
X379749D01*
X380549Y2857227D01*
X381149Y2856694D01*
X381649Y2855894D01*
X382049Y2854960D01*
X382149Y2853627D01*
X382049Y2852294D01*
X381649Y2851360D01*
X381149Y2850560D01*
X380549Y2850027D01*
X379749Y2849627D01*
X377749D01*
G01X389949D02*
X385949D01*
Y2857627D01*
X389949D01*
G01X388349Y2853760D02*
X385949D01*
G01X395949Y2849360D02*
X395749Y2849494D01*
Y2849760D01*
X395949Y2849894D01*
X396149Y2849760D01*
Y2849494D01*
X395949Y2849360D01*
G01X191000Y-62500D02*
Y-137500D01*
G01Y-112500D02*
X294000D01*
Y-87500D01*
G01X191000D02*
X294000D01*
G01X208490Y2282366D02*
X195990D01*
X198490Y2280506D01*
G01X208490D02*
Y2284226D01*
G01X208907Y2294766D02*
X208698Y2294456D01*
X208282D01*
X208073Y2294766D01*
X208282Y2295076D01*
X208698D01*
X208907Y2294766D01*
G01X206615Y2303756D02*
X207657Y2304686D01*
X208282Y2305771D01*
X208490Y2307166D01*
X208073Y2308561D01*
X207240Y2309646D01*
X205782Y2310421D01*
X204115Y2310576D01*
X202448Y2310266D01*
X201407Y2309491D01*
X200573Y2308406D01*
X200365Y2307321D01*
X200573Y2306236D01*
X201407Y2304841D01*
X195990Y2305306D01*
Y2309491D01*
G01X208490Y2315536D02*
X195990D01*
X206407Y2319566D01*
X195990Y2323596D01*
X208490D01*
G01Y2327936D02*
X195990D01*
X206407Y2331966D01*
X195990Y2335996D01*
X208490D01*
G01X217348Y2391174D02*
Y2295355D01*
G01D02*
Y2394127D01*
G01Y2397079D02*
Y2428575D01*
G01D02*
Y2394127D01*
G01X225183Y2541764D02*
Y2554264D01*
X223323Y2551764D01*
G01Y2541764D02*
X227043D01*
G01X237583Y2554264D02*
X236343Y2553847D01*
X235413Y2552806D01*
X234793Y2551556D01*
X234328Y2549889D01*
X234173Y2548014D01*
X234328Y2546139D01*
X234793Y2544472D01*
X235413Y2543222D01*
X236343Y2542181D01*
X237583Y2541764D01*
X238823Y2542181D01*
X239753Y2543222D01*
X240373Y2544472D01*
X240838Y2546139D01*
X240993Y2548014D01*
X240838Y2549889D01*
X240373Y2551556D01*
X239753Y2552806D01*
X238823Y2553847D01*
X237583Y2554264D01*
G01X249983D02*
X248743Y2553847D01*
X247813Y2552806D01*
X247193Y2551556D01*
X246728Y2549889D01*
X246573Y2548014D01*
X246728Y2546139D01*
X247193Y2544472D01*
X247813Y2543222D01*
X248743Y2542181D01*
X249983Y2541764D01*
X251223Y2542181D01*
X252153Y2543222D01*
X252773Y2544472D01*
X253238Y2546139D01*
X253393Y2548014D01*
X253238Y2549889D01*
X252773Y2551556D01*
X252153Y2552806D01*
X251223Y2553847D01*
X249983Y2554264D01*
G01X260368Y2545931D02*
X264398D01*
G01X274783Y2541764D02*
Y2554264D01*
X272923Y2551764D01*
G01Y2541764D02*
X276643D01*
G01X283773Y2543639D02*
X284703Y2542597D01*
X285788Y2541972D01*
X287183Y2541764D01*
X288578Y2542181D01*
X289663Y2543014D01*
X290438Y2544472D01*
X290593Y2546139D01*
X290283Y2547806D01*
X289508Y2548847D01*
X288423Y2549681D01*
X287338Y2549889D01*
X286253Y2549681D01*
X284858Y2548847D01*
X285323Y2554264D01*
X289508D01*
G01X299583D02*
X298343Y2553847D01*
X297413Y2552806D01*
X296793Y2551556D01*
X296328Y2549889D01*
X296173Y2548014D01*
X296328Y2546139D01*
X296793Y2544472D01*
X297413Y2543222D01*
X298343Y2542181D01*
X299583Y2541764D01*
X300823Y2542181D01*
X301753Y2543222D01*
X302373Y2544472D01*
X302838Y2546139D01*
X302993Y2548014D01*
X302838Y2549889D01*
X302373Y2551556D01*
X301753Y2552806D01*
X300823Y2553847D01*
X299583Y2554264D01*
G01X307953Y2541764D02*
Y2554264D01*
X311983Y2543847D01*
X316013Y2554264D01*
Y2541764D01*
G01X320353D02*
Y2554264D01*
X324383Y2543847D01*
X328413Y2554264D01*
Y2541764D01*
G01X277949Y2384427D02*
X279949D01*
Y2382027D01*
X279349Y2381227D01*
X278649Y2380694D01*
X277649Y2380427D01*
X276649Y2380694D01*
X275949Y2381227D01*
X275349Y2382027D01*
X274949Y2382960D01*
X274749Y2384027D01*
Y2384960D01*
X274949Y2385760D01*
X275349Y2386694D01*
X275949Y2387494D01*
X276549Y2388027D01*
X277349Y2388427D01*
X278049D01*
X278849Y2388160D01*
X279449Y2387627D01*
G01X283349Y2380427D02*
Y2388427D01*
X285849D01*
X286649Y2388027D01*
X287149Y2387494D01*
X287349Y2386427D01*
X287149Y2385360D01*
X286549Y2384694D01*
X285849Y2384294D01*
X283349D01*
G01X285849D02*
X287349Y2380427D01*
G01X293349D02*
X292549Y2380560D01*
X291849Y2381094D01*
X291249Y2381894D01*
X290849Y2382827D01*
X290649Y2383894D01*
Y2384960D01*
X290849Y2386027D01*
X291249Y2386960D01*
X291849Y2387760D01*
X292549Y2388294D01*
X293349Y2388427D01*
X294149Y2388294D01*
X294849Y2387760D01*
X295449Y2386960D01*
X295849Y2386027D01*
X296049Y2384960D01*
Y2383894D01*
X295849Y2382827D01*
X295449Y2381894D01*
X294849Y2381094D01*
X294149Y2380560D01*
X293349Y2380427D01*
G01X299149Y2388427D02*
Y2382694D01*
X299549Y2381493D01*
X300349Y2380694D01*
X301349Y2380427D01*
X302349Y2380694D01*
X303149Y2381493D01*
X303549Y2382694D01*
Y2388427D01*
G01X307349Y2380427D02*
Y2388427D01*
X309749D01*
X310549Y2388027D01*
X311149Y2387094D01*
X311349Y2386027D01*
X311149Y2384960D01*
X310649Y2384160D01*
X309749Y2383760D01*
X307349D01*
G01X315249Y2381493D02*
X316049Y2380827D01*
X316949Y2380427D01*
X317749D01*
X318549Y2380827D01*
X319149Y2381493D01*
X319449Y2382427D01*
X319249Y2383360D01*
X318749Y2384160D01*
X317849Y2384694D01*
X316649Y2384960D01*
X315949Y2385494D01*
X315649Y2386427D01*
X315849Y2387360D01*
X316349Y2388027D01*
X317049Y2388427D01*
X317749D01*
X318449Y2388160D01*
X319049Y2387494D01*
G01X334149Y2384694D02*
X334549Y2385094D01*
X334849Y2385760D01*
X335049Y2386694D01*
X334849Y2387494D01*
X334449Y2388027D01*
X333749Y2388427D01*
X331049D01*
Y2380427D01*
X334349D01*
X335049Y2380960D01*
X335449Y2381760D01*
X335649Y2382694D01*
X335449Y2383627D01*
X334849Y2384427D01*
X334149Y2384694D01*
X331049D01*
G01X570059Y2538812D02*
X274783D01*
G01X301507Y-122500D02*
Y-117500D01*
X302773D01*
X303280Y-117750D01*
X303660Y-118083D01*
X303977Y-118583D01*
X304230Y-119167D01*
X304293Y-120000D01*
X304230Y-120833D01*
X303977Y-121417D01*
X303660Y-121917D01*
X303280Y-122250D01*
X302773Y-122500D01*
X301507D01*
G01X306417D02*
X308000Y-117500D01*
X309583Y-122500D01*
G01X309013Y-120750D02*
X306987D01*
G01X313100Y-117500D02*
Y-122500D01*
G01X311643Y-117500D02*
X314557D01*
G01X319467Y-122500D02*
X316933D01*
Y-117500D01*
X319467D01*
G01X318453Y-119917D02*
X316933D01*
G01X323300Y-122667D02*
X323173Y-122583D01*
Y-122417D01*
X323300Y-122333D01*
X323427Y-122417D01*
Y-122583D01*
X323300Y-122667D01*
G01Y-120417D02*
X323173Y-120333D01*
Y-120167D01*
X323300Y-120083D01*
X323427Y-120167D01*
Y-120333D01*
X323300Y-120417D01*
G01X296000Y-62500D02*
Y-137500D01*
G01X294000Y-62500D02*
Y-137500D01*
G01X301633Y-97500D02*
Y-92500D01*
X303153D01*
X303660Y-92750D01*
X304040Y-93333D01*
X304167Y-94000D01*
X304040Y-94667D01*
X303723Y-95167D01*
X303153Y-95417D01*
X301633D01*
G01X306860Y-97667D02*
X309140Y-92500D01*
G01X311643Y-97500D02*
Y-92500D01*
X314557Y-97500D01*
Y-92500D01*
G01X318200Y-97667D02*
X318073Y-97583D01*
Y-97417D01*
X318200Y-97333D01*
X318327Y-97417D01*
Y-97583D01*
X318200Y-97667D01*
G01Y-95417D02*
X318073Y-95333D01*
Y-95167D01*
X318200Y-95083D01*
X318327Y-95167D01*
Y-95333D01*
X318200Y-95417D01*
G01X296000Y-112500D02*
X496000D01*
G01X301633Y-72500D02*
Y-67500D01*
X303153D01*
X303660Y-67750D01*
X304040Y-68333D01*
X304167Y-69000D01*
X304040Y-69667D01*
X303723Y-70167D01*
X303153Y-70417D01*
X301633D01*
G01X306733Y-72500D02*
Y-67500D01*
X308317D01*
X308823Y-67750D01*
X309140Y-68083D01*
X309267Y-68750D01*
X309140Y-69417D01*
X308760Y-69833D01*
X308317Y-70083D01*
X306733D01*
G01X308317D02*
X309267Y-72500D01*
G01X313100D02*
X312593Y-72417D01*
X312150Y-72083D01*
X311770Y-71583D01*
X311517Y-71000D01*
X311390Y-70333D01*
Y-69667D01*
X311517Y-69000D01*
X311770Y-68417D01*
X312150Y-67917D01*
X312593Y-67583D01*
X313100Y-67500D01*
X313607Y-67583D01*
X314050Y-67917D01*
X314430Y-68417D01*
X314683Y-69000D01*
X314810Y-69667D01*
Y-70333D01*
X314683Y-71000D01*
X314430Y-71583D01*
X314050Y-72083D01*
X313607Y-72417D01*
X313100Y-72500D01*
G01X316933Y-71500D02*
X317250Y-72000D01*
X317630Y-72333D01*
X318073Y-72500D01*
X318580Y-72333D01*
X318960Y-72000D01*
X319340Y-71500D01*
X319467Y-70833D01*
Y-67500D01*
G01X324567Y-72500D02*
X322033D01*
Y-67500D01*
X324567D01*
G01X323553Y-69917D02*
X322033D01*
G01X329793Y-67917D02*
X329413Y-67667D01*
X328970Y-67500D01*
X328463D01*
X327893Y-67750D01*
X327450Y-68167D01*
X327133Y-68667D01*
X326880Y-69500D01*
X326817Y-70250D01*
X326943Y-71000D01*
X327133Y-71500D01*
X327513Y-72000D01*
X327957Y-72333D01*
X328400Y-72500D01*
X328843D01*
X329287Y-72333D01*
X329667Y-72083D01*
X329983Y-71750D01*
G01X333500Y-67500D02*
Y-72500D01*
G01X332043Y-67500D02*
X334957D01*
G01X338600Y-72667D02*
X338473Y-72583D01*
Y-72417D01*
X338600Y-72333D01*
X338727Y-72417D01*
Y-72583D01*
X338600Y-72667D01*
G01Y-70417D02*
X338473Y-70333D01*
Y-70167D01*
X338600Y-70083D01*
X338727Y-70167D01*
Y-70333D01*
X338600Y-70417D01*
G01X296000Y-87500D02*
X496000D01*
G01X307087Y2040503D02*
Y-3491D01*
G01X310086Y127165D02*
X425869D01*
G01X310086Y477165D02*
X412724D01*
G01X310086Y827165D02*
X425524D01*
G01X310086Y1343504D02*
X486045D01*
G01X310086Y1693504D02*
X498845D01*
G01X317323Y1885039D02*
Y1881102D01*
G02X296850I-10237J0D01*
G01Y1885039D01*
G02X317323I10236J0D01*
G01X310086Y1883071D02*
X480318D01*
G01X310087Y2043503D02*
X453371D01*
G01X359842Y2000780D02*
Y-7197D01*
G01X362842Y78780D02*
X435756D01*
G01X362842Y253780D02*
X437995D01*
G01X362842Y428779D02*
X425195D01*
G01X362842Y603779D02*
X553196D01*
G01X362842Y778780D02*
X555890D01*
G01X362842Y953780D02*
X527596D01*
G01X362842Y1128779D02*
X492109D01*
G01X362842Y1303780D02*
X491435D01*
G01X362842Y1478780D02*
X494130D01*
G01X362842Y1653780D02*
X497498D01*
G01X362842Y1828779D02*
X478971D01*
G01X362842Y2003780D02*
X465834D01*
G01X373385Y1954520D02*
Y-17303D01*
X379969Y-25417D01*
G01X376385Y32520D02*
X414898D01*
X416776Y33300D01*
G01X376385Y207520D02*
X411379D01*
X412219Y207729D01*
G01X373078Y308268D02*
X433280D01*
G01X376385Y382520D02*
X406662D01*
X408115Y383111D01*
G01X376386Y557520D02*
X421651D01*
X422750Y558103D01*
G01X376386Y732520D02*
X420456D01*
X425840Y734939D01*
G01X376385Y907520D02*
X422157D01*
X447757Y920803D01*
G01X376385Y1082520D02*
X426199D01*
X429222Y1084080D01*
G01X376385Y1257520D02*
X434957D01*
X461568Y1272466D01*
X462122D01*
G01X376385Y1432520D02*
X438326D01*
X442224Y1434060D01*
G01X376385Y1607520D02*
X420793D01*
X429663Y1611569D01*
G01X376385Y1782520D02*
X428557D01*
X439721Y1787745D01*
G01X376385Y1957520D02*
X433946D01*
X441576Y1961893D01*
G01X411000Y-112500D02*
Y-137500D01*
G01X405512Y2081740D02*
Y2116592D01*
G01X416633Y-122500D02*
Y-117500D01*
X418217D01*
X418723Y-117750D01*
X419040Y-118083D01*
X419167Y-118750D01*
X419040Y-119417D01*
X418660Y-119833D01*
X418217Y-120083D01*
X416633D01*
G01X418217D02*
X419167Y-122500D01*
G01X424267D02*
X421733D01*
Y-117500D01*
X424267D01*
G01X423253Y-119917D02*
X421733D01*
G01X426517Y-117500D02*
X428100Y-122500D01*
X429683Y-117500D01*
G01X433200Y-122667D02*
X433073Y-122583D01*
Y-122417D01*
X433200Y-122333D01*
X433327Y-122417D01*
Y-122583D01*
X433200Y-122667D01*
G01Y-120417D02*
X433073Y-120333D01*
Y-120167D01*
X433200Y-120083D01*
X433327Y-120167D01*
Y-120333D01*
X433200Y-120417D01*
G01X460000Y-112500D02*
Y-137500D01*
G01X517409Y2517627D02*
Y2530127D01*
X511674Y2521169D01*
X519424D01*
G01X523919Y2517627D02*
Y2530127D01*
X527949Y2519710D01*
X531979Y2530127D01*
Y2517627D01*
G01X536319D02*
Y2530127D01*
X540349Y2519710D01*
X544379Y2530127D01*
Y2517627D01*
G01X554311Y2511253D02*
X522815D01*
G01D02*
X562185D01*
G01X535266Y39171D02*
Y1031771D01*
X812066D01*
Y39171D01*
X535266D01*
G01Y86421D02*
X812066D01*
G01X535266Y133671D02*
X812066D01*
G01X535266Y180921D02*
X812066D01*
G01X535266Y228171D02*
X812066D01*
G01X535266Y275421D02*
X812066D01*
G01X535266Y322671D02*
X812066D01*
G01X535266Y369921D02*
X812066D01*
G01X535266Y417171D02*
X812066D01*
G01X535266Y464421D02*
X812066D01*
G01X535266Y511671D02*
X812066D01*
G01X535266Y558921D02*
X812066D01*
G01X535266Y606171D02*
X812066D01*
G01X535266Y653421D02*
X812066D01*
G01X535266Y700671D02*
X812066D01*
G01X535266Y747921D02*
X812066D01*
G01X535266Y795171D02*
X812066D01*
G01X535266Y842421D02*
X812066D01*
G01X535266Y889671D02*
X812066D01*
G01X535266Y936921D02*
X812066D01*
G01X535266Y995471D02*
X812066D01*
G01X535266Y984171D02*
X812066D01*
G01X535266Y1006771D02*
X812066D01*
G01X554311Y2436449D02*
X570059Y2444323D01*
G01Y2464009D02*
X554311Y2471883D01*
G01X570059Y2444323D02*
X554311Y2452197D01*
G01Y2456134D02*
X570059Y2464009D01*
G01X554311Y2475820D02*
Y2519127D01*
G01X572266Y995471D02*
Y39171D01*
G01X605492Y2456134D02*
X562185D01*
G01X605492Y2452197D02*
X562185D01*
G01X570059Y2467945D02*
Y2519127D01*
G01Y2467945D02*
Y2546686D01*
G01Y2511253D02*
X601555D01*
G01D02*
X562185D01*
G01X610049Y2418427D02*
X597549D01*
X600049Y2416567D01*
G01X610049D02*
Y2420287D01*
G01Y2426797D02*
X597549D01*
X607966Y2430827D01*
X597549Y2434857D01*
X610049D01*
G01Y2439197D02*
X597549D01*
X607966Y2443227D01*
X597549Y2447257D01*
X610049D01*
G01X586111Y2413020D02*
Y2456327D01*
G01X630049Y2454227D02*
X632049D01*
Y2451827D01*
X631449Y2451027D01*
X630749Y2450494D01*
X629749Y2450227D01*
X628749Y2450494D01*
X628049Y2451027D01*
X627449Y2451827D01*
X627049Y2452760D01*
X626849Y2453827D01*
Y2454760D01*
X627049Y2455560D01*
X627449Y2456494D01*
X628049Y2457294D01*
X628649Y2457827D01*
X629449Y2458227D01*
X630149D01*
X630949Y2457960D01*
X631549Y2457427D01*
G01X635449Y2450227D02*
Y2458227D01*
X637949D01*
X638749Y2457827D01*
X639249Y2457294D01*
X639449Y2456227D01*
X639249Y2455160D01*
X638649Y2454494D01*
X637949Y2454094D01*
X635449D01*
G01X637949D02*
X639449Y2450227D01*
G01X645449D02*
X644649Y2450360D01*
X643949Y2450894D01*
X643349Y2451694D01*
X642949Y2452627D01*
X642749Y2453694D01*
Y2454760D01*
X642949Y2455827D01*
X643349Y2456760D01*
X643949Y2457560D01*
X644649Y2458094D01*
X645449Y2458227D01*
X646249Y2458094D01*
X646949Y2457560D01*
X647549Y2456760D01*
X647949Y2455827D01*
X648149Y2454760D01*
Y2453694D01*
X647949Y2452627D01*
X647549Y2451694D01*
X646949Y2450894D01*
X646249Y2450360D01*
X645449Y2450227D01*
G01X651249Y2458227D02*
Y2452494D01*
X651649Y2451293D01*
X652449Y2450494D01*
X653449Y2450227D01*
X654449Y2450494D01*
X655249Y2451293D01*
X655649Y2452494D01*
Y2458227D01*
G01X659449Y2450227D02*
Y2458227D01*
X661849D01*
X662649Y2457827D01*
X663249Y2456894D01*
X663449Y2455827D01*
X663249Y2454760D01*
X662749Y2453960D01*
X661849Y2453560D01*
X659449D01*
G01X667349Y2451293D02*
X668149Y2450627D01*
X669049Y2450227D01*
X669849D01*
X670649Y2450627D01*
X671249Y2451293D01*
X671549Y2452227D01*
X671349Y2453160D01*
X670849Y2453960D01*
X669949Y2454494D01*
X668749Y2454760D01*
X668049Y2455294D01*
X667749Y2456227D01*
X667949Y2457160D01*
X668449Y2457827D01*
X669149Y2458227D01*
X669849D01*
X670549Y2457960D01*
X671149Y2457294D01*
G01X682949Y2450227D02*
X685449Y2458227D01*
X687949Y2450227D01*
G01X687049Y2453027D02*
X683849D01*
G01X650066Y995471D02*
Y39171D01*
G01X727866Y995471D02*
Y39171D01*
G01X780166Y995471D02*
Y39171D01*
G01X-723776Y2987387D02*
Y-376795D01*
Y-489221D01*
X1782976D01*
Y-376795D01*
Y2987387D01*
X-723776D01*
G01X-225825Y1070699D02*
X-226455Y1071169D01*
X-226770Y1071717D01*
X-226875Y1072344D01*
X-226665Y1073127D01*
X-226140Y1073675D01*
X-225510Y1073832D01*
X-224880Y1073754D01*
X-224355Y1073440D01*
X-223305Y1071874D01*
X-222570Y1071169D01*
X-221520Y1070699D01*
X-220575Y1070542D01*
Y1073832D01*
G01X-226875Y1078487D02*
X-226665Y1077860D01*
X-226140Y1077390D01*
X-225510Y1077077D01*
X-224670Y1076842D01*
X-223725Y1076764D01*
X-222780Y1076842D01*
X-221940Y1077077D01*
X-221310Y1077390D01*
X-220785Y1077860D01*
X-220575Y1078487D01*
X-220785Y1079114D01*
X-221310Y1079584D01*
X-221940Y1079897D01*
X-222780Y1080132D01*
X-223725Y1080210D01*
X-224670Y1080132D01*
X-225510Y1079897D01*
X-226140Y1079584D01*
X-226665Y1079114D01*
X-226875Y1078487D01*
G01X-220575Y1084787D02*
X-220680Y1085335D01*
X-220995Y1085962D01*
X-221520Y1086354D01*
X-222255Y1086510D01*
X-222990Y1086354D01*
X-223620Y1085884D01*
X-223935Y1085179D01*
Y1084395D01*
X-224145Y1083925D01*
X-224670Y1083534D01*
X-225405Y1083377D01*
X-226140Y1083612D01*
X-226665Y1084160D01*
X-226875Y1084787D01*
X-226665Y1085414D01*
X-226140Y1085962D01*
X-225405Y1086197D01*
X-224670Y1086040D01*
X-224145Y1085649D01*
X-223935Y1085179D01*
Y1084395D01*
X-223620Y1083690D01*
X-222990Y1083220D01*
X-222255Y1083064D01*
X-221520Y1083220D01*
X-220995Y1083612D01*
X-220680Y1084239D01*
X-220575Y1084787D01*
G01X-223200Y1089599D02*
X-223935Y1090147D01*
X-224355Y1090617D01*
X-224565Y1091244D01*
X-224355Y1091792D01*
X-223935Y1092184D01*
X-223305Y1092497D01*
X-222570Y1092575D01*
X-221940Y1092497D01*
X-221310Y1092184D01*
X-220785Y1091714D01*
X-220575Y1091165D01*
X-220785Y1090539D01*
X-221415Y1089990D01*
X-222360Y1089677D01*
X-223410Y1089599D01*
X-224775Y1089755D01*
X-225510Y1089990D01*
X-226245Y1090382D01*
X-226770Y1090930D01*
X-226875Y1091479D01*
X-226665Y1092027D01*
X-226140Y1092419D01*
G01X-223200Y1095899D02*
X-223935Y1096447D01*
X-224355Y1096917D01*
X-224565Y1097544D01*
X-224355Y1098092D01*
X-223935Y1098484D01*
X-223305Y1098797D01*
X-222570Y1098875D01*
X-221940Y1098797D01*
X-221310Y1098484D01*
X-220785Y1098014D01*
X-220575Y1097465D01*
X-220785Y1096839D01*
X-221415Y1096290D01*
X-222360Y1095977D01*
X-223410Y1095899D01*
X-224775Y1096055D01*
X-225510Y1096290D01*
X-226245Y1096682D01*
X-226770Y1097230D01*
X-226875Y1097779D01*
X-226665Y1098327D01*
X-226140Y1098719D01*
G01X-220365Y1103687D02*
X-220470Y1103530D01*
X-220680D01*
X-220785Y1103687D01*
X-220680Y1103844D01*
X-220470D01*
X-220365Y1103687D01*
G01X-220575Y1109987D02*
X-226875D01*
X-225615Y1109047D01*
G01X-220575D02*
Y1110927D01*
G01Y1117227D02*
X-226875D01*
X-222360Y1114329D01*
Y1118245D01*
G01X-89232Y9796D02*
X-89859Y9586D01*
X-90329Y9061D01*
X-90642Y8431D01*
X-90877Y7591D01*
X-90955Y6646D01*
X-90877Y5701D01*
X-90642Y4861D01*
X-90329Y4231D01*
X-89859Y3706D01*
X-89232Y3496D01*
X-88605Y3706D01*
X-88135Y4231D01*
X-87822Y4861D01*
X-87587Y5701D01*
X-87509Y6646D01*
X-87587Y7591D01*
X-87822Y8431D01*
X-88135Y9061D01*
X-88605Y9586D01*
X-89232Y9796D01*
G01X-93016Y3150D02*
X-93643Y2940D01*
X-94113Y2415D01*
X-94426Y1785D01*
X-94661Y945D01*
X-94739Y0D01*
X-94661Y-945D01*
X-94426Y-1785D01*
X-94113Y-2415D01*
X-93643Y-2940D01*
X-93016Y-3150D01*
X-92389Y-2940D01*
X-91919Y-2415D01*
X-91606Y-1785D01*
X-91371Y-945D01*
X-91293Y0D01*
X-91371Y945D01*
X-91606Y1785D01*
X-91919Y2415D01*
X-92389Y2940D01*
X-93016Y3150D01*
G01X-81123Y111810D02*
Y118110D01*
X-82063Y116850D01*
G01Y111810D02*
X-80183D01*
G01X-74823D02*
Y118110D01*
X-75763Y116850D01*
G01Y111810D02*
X-73883D01*
G01X-67583D02*
Y118110D01*
X-70481Y113595D01*
X-66565D01*
G01X-63555Y112545D02*
X-63006Y112020D01*
X-62380Y111810D01*
X-61753Y112020D01*
X-61205Y112650D01*
X-60813Y113595D01*
X-60656Y114540D01*
Y115695D01*
X-60813Y116640D01*
X-61205Y117480D01*
X-61675Y117900D01*
X-62223Y118110D01*
X-62850Y117900D01*
X-63320Y117480D01*
X-63633Y116850D01*
X-63790Y116010D01*
X-63633Y115275D01*
X-63241Y114540D01*
X-62771Y114120D01*
X-62223Y114015D01*
X-61596Y114225D01*
X-61126Y114750D01*
X-60656Y115695D01*
G01X-55923Y111600D02*
X-56080Y111705D01*
Y111915D01*
X-55923Y112020D01*
X-55766Y111915D01*
Y111705D01*
X-55923Y111600D01*
G01X-51111Y114435D02*
X-50563Y115170D01*
X-50093Y115590D01*
X-49466Y115800D01*
X-48918Y115590D01*
X-48526Y115170D01*
X-48213Y114540D01*
X-48135Y113805D01*
X-48213Y113175D01*
X-48526Y112545D01*
X-48996Y112020D01*
X-49545Y111810D01*
X-50171Y112020D01*
X-50720Y112650D01*
X-51033Y113595D01*
X-51111Y114645D01*
X-50955Y116010D01*
X-50720Y116745D01*
X-50328Y117480D01*
X-49780Y118005D01*
X-49231Y118110D01*
X-48683Y117900D01*
X-48291Y117375D01*
G01X-43323Y118110D02*
X-43950Y117900D01*
X-44420Y117375D01*
X-44733Y116745D01*
X-44968Y115905D01*
X-45046Y114960D01*
X-44968Y114015D01*
X-44733Y113175D01*
X-44420Y112545D01*
X-43950Y112020D01*
X-43323Y111810D01*
X-42696Y112020D01*
X-42226Y112545D01*
X-41913Y113175D01*
X-41678Y114015D01*
X-41600Y114960D01*
X-41678Y115905D01*
X-41913Y116745D01*
X-42226Y117375D01*
X-42696Y117900D01*
X-43323Y118110D01*
G01X-70344Y178826D02*
Y185126D01*
X-71284Y183866D01*
G01Y178826D02*
X-69404D01*
G01X-64044D02*
X-63496Y178931D01*
X-62869Y179246D01*
X-62477Y179771D01*
X-62321Y180506D01*
X-62477Y181241D01*
X-62947Y181871D01*
X-63652Y182186D01*
X-64436D01*
X-64906Y182396D01*
X-65297Y182921D01*
X-65454Y183656D01*
X-65219Y184391D01*
X-64671Y184916D01*
X-64044Y185126D01*
X-63417Y184916D01*
X-62869Y184391D01*
X-62634Y183656D01*
X-62791Y182921D01*
X-63182Y182396D01*
X-63652Y182186D01*
X-64436D01*
X-65141Y181871D01*
X-65611Y181241D01*
X-65767Y180506D01*
X-65611Y179771D01*
X-65219Y179246D01*
X-64592Y178931D01*
X-64044Y178826D01*
G01X-57744D02*
Y185126D01*
X-58684Y183866D01*
G01Y178826D02*
X-56804D01*
G01X-52776Y179561D02*
X-52227Y179036D01*
X-51601Y178826D01*
X-50974Y179036D01*
X-50426Y179666D01*
X-50034Y180611D01*
X-49877Y181556D01*
Y182711D01*
X-50034Y183656D01*
X-50426Y184496D01*
X-50896Y184916D01*
X-51444Y185126D01*
X-52071Y184916D01*
X-52541Y184496D01*
X-52854Y183866D01*
X-53011Y183026D01*
X-52854Y182291D01*
X-52462Y181556D01*
X-51992Y181136D01*
X-51444Y181031D01*
X-50817Y181241D01*
X-50347Y181766D01*
X-49877Y182711D01*
G01X-45144Y178616D02*
X-45301Y178721D01*
Y178931D01*
X-45144Y179036D01*
X-44987Y178931D01*
Y178721D01*
X-45144Y178616D01*
G01X-39001Y178826D02*
X-38844Y180191D01*
X-38609Y181346D01*
X-38296Y182396D01*
X-37904Y183551D01*
X-37277Y185126D01*
X-40411D01*
G01X-34032Y181451D02*
X-33484Y182186D01*
X-33014Y182606D01*
X-32387Y182816D01*
X-31839Y182606D01*
X-31447Y182186D01*
X-31134Y181556D01*
X-31056Y180821D01*
X-31134Y180191D01*
X-31447Y179561D01*
X-31917Y179036D01*
X-32466Y178826D01*
X-33092Y179036D01*
X-33641Y179666D01*
X-33954Y180611D01*
X-34032Y181661D01*
X-33876Y183026D01*
X-33641Y183761D01*
X-33249Y184496D01*
X-32701Y185021D01*
X-32152Y185126D01*
X-31604Y184916D01*
X-31212Y184391D01*
G01X-88267Y461810D02*
Y468110D01*
X-91165Y463595D01*
X-87249D01*
G01X-84395Y464435D02*
X-83847Y465170D01*
X-83377Y465590D01*
X-82750Y465800D01*
X-82202Y465590D01*
X-81810Y465170D01*
X-81497Y464540D01*
X-81419Y463805D01*
X-81497Y463175D01*
X-81810Y462545D01*
X-82280Y462020D01*
X-82829Y461810D01*
X-83455Y462020D01*
X-84004Y462650D01*
X-84317Y463595D01*
X-84395Y464645D01*
X-84239Y466010D01*
X-84004Y466745D01*
X-83612Y467480D01*
X-83064Y468005D01*
X-82515Y468110D01*
X-81967Y467900D01*
X-81575Y467375D01*
G01X-75667Y461810D02*
Y468110D01*
X-78565Y463595D01*
X-74649D01*
G01X-71639Y462545D02*
X-71090Y462020D01*
X-70464Y461810D01*
X-69837Y462020D01*
X-69289Y462650D01*
X-68897Y463595D01*
X-68740Y464540D01*
Y465695D01*
X-68897Y466640D01*
X-69289Y467480D01*
X-69759Y467900D01*
X-70307Y468110D01*
X-70934Y467900D01*
X-71404Y467480D01*
X-71717Y466850D01*
X-71874Y466010D01*
X-71717Y465275D01*
X-71325Y464540D01*
X-70855Y464120D01*
X-70307Y464015D01*
X-69680Y464225D01*
X-69210Y464750D01*
X-68740Y465695D01*
G01X-64007Y461600D02*
X-64164Y461705D01*
Y461915D01*
X-64007Y462020D01*
X-63850Y461915D01*
Y461705D01*
X-64007Y461600D01*
G01X-59195Y464435D02*
X-58647Y465170D01*
X-58177Y465590D01*
X-57550Y465800D01*
X-57002Y465590D01*
X-56610Y465170D01*
X-56297Y464540D01*
X-56219Y463805D01*
X-56297Y463175D01*
X-56610Y462545D01*
X-57080Y462020D01*
X-57629Y461810D01*
X-58255Y462020D01*
X-58804Y462650D01*
X-59117Y463595D01*
X-59195Y464645D01*
X-59039Y466010D01*
X-58804Y466745D01*
X-58412Y467480D01*
X-57864Y468005D01*
X-57315Y468110D01*
X-56767Y467900D01*
X-56375Y467375D01*
G01X-51407Y468110D02*
X-52034Y467900D01*
X-52504Y467375D01*
X-52817Y466745D01*
X-53052Y465905D01*
X-53130Y464960D01*
X-53052Y464015D01*
X-52817Y463175D01*
X-52504Y462545D01*
X-52034Y462020D01*
X-51407Y461810D01*
X-50780Y462020D01*
X-50310Y462545D01*
X-49997Y463175D01*
X-49762Y464015D01*
X-49684Y464960D01*
X-49762Y465905D01*
X-49997Y466745D01*
X-50310Y467375D01*
X-50780Y467900D01*
X-51407Y468110D01*
G01X-91941Y541496D02*
X-91471Y540971D01*
X-90923Y540656D01*
X-90218Y540551D01*
X-89513Y540761D01*
X-88965Y541181D01*
X-88573Y541916D01*
X-88495Y542756D01*
X-88651Y543596D01*
X-89043Y544121D01*
X-89591Y544541D01*
X-90140Y544646D01*
X-90688Y544541D01*
X-91393Y544121D01*
X-91158Y546851D01*
X-89043D01*
G01X-82978Y540551D02*
Y546851D01*
X-85876Y542336D01*
X-81960D01*
G01X-79341Y541811D02*
X-78871Y541076D01*
X-78245Y540656D01*
X-77540Y540551D01*
X-76913Y540656D01*
X-76286Y541181D01*
X-75895Y541811D01*
X-75816Y542441D01*
X-75973Y543176D01*
X-76521Y543701D01*
X-77070Y543911D01*
X-77775D01*
G01X-77070D02*
X-76600Y544226D01*
X-76208Y544751D01*
X-76051Y545381D01*
X-76208Y546011D01*
X-76600Y546536D01*
X-77305Y546851D01*
X-78010Y546746D01*
X-78715Y546326D01*
G01X-71475Y540551D02*
X-71318Y541916D01*
X-71083Y543071D01*
X-70770Y544121D01*
X-70378Y545276D01*
X-69751Y546851D01*
X-72885D01*
G01X-65018Y540341D02*
X-65175Y540446D01*
Y540656D01*
X-65018Y540761D01*
X-64861Y540656D01*
Y540446D01*
X-65018Y540341D01*
G01X-58718Y546851D02*
X-59345Y546641D01*
X-59815Y546116D01*
X-60128Y545486D01*
X-60363Y544646D01*
X-60441Y543701D01*
X-60363Y542756D01*
X-60128Y541916D01*
X-59815Y541286D01*
X-59345Y540761D01*
X-58718Y540551D01*
X-58091Y540761D01*
X-57621Y541286D01*
X-57308Y541916D01*
X-57073Y542756D01*
X-56995Y543701D01*
X-57073Y544646D01*
X-57308Y545486D01*
X-57621Y546116D01*
X-58091Y546641D01*
X-58718Y546851D01*
G01X-52418Y540551D02*
Y546851D01*
X-53358Y545591D01*
G01Y540551D02*
X-51478D01*
G01X-73712Y811810D02*
X-73164Y811915D01*
X-72537Y812230D01*
X-72145Y812755D01*
X-71989Y813490D01*
X-72145Y814225D01*
X-72615Y814855D01*
X-73320Y815170D01*
X-74104D01*
X-74574Y815380D01*
X-74965Y815905D01*
X-75122Y816640D01*
X-74887Y817375D01*
X-74339Y817900D01*
X-73712Y818110D01*
X-73085Y817900D01*
X-72537Y817375D01*
X-72302Y816640D01*
X-72459Y815905D01*
X-72850Y815380D01*
X-73320Y815170D01*
X-74104D01*
X-74809Y814855D01*
X-75279Y814225D01*
X-75435Y813490D01*
X-75279Y812755D01*
X-74887Y812230D01*
X-74260Y811915D01*
X-73712Y811810D01*
G01X-67412D02*
Y818110D01*
X-68352Y816850D01*
G01Y811810D02*
X-66472D01*
G01X-60172D02*
Y818110D01*
X-63070Y813595D01*
X-59154D01*
G01X-56144Y812545D02*
X-55595Y812020D01*
X-54969Y811810D01*
X-54342Y812020D01*
X-53794Y812650D01*
X-53402Y813595D01*
X-53245Y814540D01*
Y815695D01*
X-53402Y816640D01*
X-53794Y817480D01*
X-54264Y817900D01*
X-54812Y818110D01*
X-55439Y817900D01*
X-55909Y817480D01*
X-56222Y816850D01*
X-56379Y816010D01*
X-56222Y815275D01*
X-55830Y814540D01*
X-55360Y814120D01*
X-54812Y814015D01*
X-54185Y814225D01*
X-53715Y814750D01*
X-53245Y815695D01*
G01X-48512Y811600D02*
X-48669Y811705D01*
Y811915D01*
X-48512Y812020D01*
X-48355Y811915D01*
Y811705D01*
X-48512Y811600D01*
G01X-43700Y814435D02*
X-43152Y815170D01*
X-42682Y815590D01*
X-42055Y815800D01*
X-41507Y815590D01*
X-41115Y815170D01*
X-40802Y814540D01*
X-40724Y813805D01*
X-40802Y813175D01*
X-41115Y812545D01*
X-41585Y812020D01*
X-42134Y811810D01*
X-42760Y812020D01*
X-43309Y812650D01*
X-43622Y813595D01*
X-43700Y814645D01*
X-43544Y816010D01*
X-43309Y816745D01*
X-42917Y817480D01*
X-42369Y818005D01*
X-41820Y818110D01*
X-41272Y817900D01*
X-40880Y817375D01*
G01X-35912Y818110D02*
X-36539Y817900D01*
X-37009Y817375D01*
X-37322Y816745D01*
X-37557Y815905D01*
X-37635Y814960D01*
X-37557Y814015D01*
X-37322Y813175D01*
X-37009Y812545D01*
X-36539Y812020D01*
X-35912Y811810D01*
X-35285Y812020D01*
X-34815Y812545D01*
X-34502Y813175D01*
X-34267Y814015D01*
X-34189Y814960D01*
X-34267Y815905D01*
X-34502Y816745D01*
X-34815Y817375D01*
X-35285Y817900D01*
X-35912Y818110D01*
G01X-78057Y1047519D02*
Y1053819D01*
X-78997Y1052559D01*
G01Y1047519D02*
X-77117D01*
G01X-71757Y1053819D02*
X-72384Y1053609D01*
X-72854Y1053084D01*
X-73167Y1052454D01*
X-73402Y1051614D01*
X-73480Y1050669D01*
X-73402Y1049724D01*
X-73167Y1048884D01*
X-72854Y1048254D01*
X-72384Y1047729D01*
X-71757Y1047519D01*
X-71130Y1047729D01*
X-70660Y1048254D01*
X-70347Y1048884D01*
X-70112Y1049724D01*
X-70034Y1050669D01*
X-70112Y1051614D01*
X-70347Y1052454D01*
X-70660Y1053084D01*
X-71130Y1053609D01*
X-71757Y1053819D01*
G01X-67180Y1048464D02*
X-66710Y1047939D01*
X-66162Y1047624D01*
X-65457Y1047519D01*
X-64752Y1047729D01*
X-64204Y1048149D01*
X-63812Y1048884D01*
X-63734Y1049724D01*
X-63890Y1050564D01*
X-64282Y1051089D01*
X-64830Y1051509D01*
X-65379Y1051614D01*
X-65927Y1051509D01*
X-66632Y1051089D01*
X-66397Y1053819D01*
X-64282D01*
G01X-59157D02*
X-59784Y1053609D01*
X-60254Y1053084D01*
X-60567Y1052454D01*
X-60802Y1051614D01*
X-60880Y1050669D01*
X-60802Y1049724D01*
X-60567Y1048884D01*
X-60254Y1048254D01*
X-59784Y1047729D01*
X-59157Y1047519D01*
X-58530Y1047729D01*
X-58060Y1048254D01*
X-57747Y1048884D01*
X-57512Y1049724D01*
X-57434Y1050669D01*
X-57512Y1051614D01*
X-57747Y1052454D01*
X-58060Y1053084D01*
X-58530Y1053609D01*
X-59157Y1053819D01*
G01X-54345Y1050144D02*
X-53797Y1050879D01*
X-53327Y1051299D01*
X-52700Y1051509D01*
X-52152Y1051299D01*
X-51760Y1050879D01*
X-51447Y1050249D01*
X-51369Y1049514D01*
X-51447Y1048884D01*
X-51760Y1048254D01*
X-52230Y1047729D01*
X-52779Y1047519D01*
X-53405Y1047729D01*
X-53954Y1048359D01*
X-54267Y1049304D01*
X-54345Y1050354D01*
X-54189Y1051719D01*
X-53954Y1052454D01*
X-53562Y1053189D01*
X-53014Y1053714D01*
X-52465Y1053819D01*
X-51917Y1053609D01*
X-51525Y1053084D01*
G01X-46557Y1047309D02*
X-46714Y1047414D01*
Y1047624D01*
X-46557Y1047729D01*
X-46400Y1047624D01*
Y1047414D01*
X-46557Y1047309D01*
G01X-41745Y1050144D02*
X-41197Y1050879D01*
X-40727Y1051299D01*
X-40100Y1051509D01*
X-39552Y1051299D01*
X-39160Y1050879D01*
X-38847Y1050249D01*
X-38769Y1049514D01*
X-38847Y1048884D01*
X-39160Y1048254D01*
X-39630Y1047729D01*
X-40179Y1047519D01*
X-40805Y1047729D01*
X-41354Y1048359D01*
X-41667Y1049304D01*
X-41745Y1050354D01*
X-41589Y1051719D01*
X-41354Y1052454D01*
X-40962Y1053189D01*
X-40414Y1053714D01*
X-39865Y1053819D01*
X-39317Y1053609D01*
X-38925Y1053084D01*
G01X-35289Y1048254D02*
X-34740Y1047729D01*
X-34114Y1047519D01*
X-33487Y1047729D01*
X-32939Y1048359D01*
X-32547Y1049304D01*
X-32390Y1050249D01*
Y1051404D01*
X-32547Y1052349D01*
X-32939Y1053189D01*
X-33409Y1053609D01*
X-33957Y1053819D01*
X-34584Y1053609D01*
X-35054Y1053189D01*
X-35367Y1052559D01*
X-35524Y1051719D01*
X-35367Y1050984D01*
X-34975Y1050249D01*
X-34505Y1049829D01*
X-33957Y1049724D01*
X-33330Y1049934D01*
X-32860Y1050459D01*
X-32390Y1051404D01*
G01X-71810Y1161810D02*
Y1168110D01*
X-72750Y1166850D01*
G01Y1161810D02*
X-70870D01*
G01X-65510D02*
Y1168110D01*
X-66450Y1166850D01*
G01Y1161810D02*
X-64570D01*
G01X-60698Y1164435D02*
X-60150Y1165170D01*
X-59680Y1165590D01*
X-59053Y1165800D01*
X-58505Y1165590D01*
X-58113Y1165170D01*
X-57800Y1164540D01*
X-57722Y1163805D01*
X-57800Y1163175D01*
X-58113Y1162545D01*
X-58583Y1162020D01*
X-59132Y1161810D01*
X-59758Y1162020D01*
X-60307Y1162650D01*
X-60620Y1163595D01*
X-60698Y1164645D01*
X-60542Y1166010D01*
X-60307Y1166745D01*
X-59915Y1167480D01*
X-59367Y1168005D01*
X-58818Y1168110D01*
X-58270Y1167900D01*
X-57878Y1167375D01*
G01X-51970Y1161810D02*
Y1168110D01*
X-54868Y1163595D01*
X-50952D01*
G01X-47942Y1162545D02*
X-47393Y1162020D01*
X-46767Y1161810D01*
X-46140Y1162020D01*
X-45592Y1162650D01*
X-45200Y1163595D01*
X-45043Y1164540D01*
Y1165695D01*
X-45200Y1166640D01*
X-45592Y1167480D01*
X-46062Y1167900D01*
X-46610Y1168110D01*
X-47237Y1167900D01*
X-47707Y1167480D01*
X-48020Y1166850D01*
X-48177Y1166010D01*
X-48020Y1165275D01*
X-47628Y1164540D01*
X-47158Y1164120D01*
X-46610Y1164015D01*
X-45983Y1164225D01*
X-45513Y1164750D01*
X-45043Y1165695D01*
G01X-40310Y1161600D02*
X-40467Y1161705D01*
Y1161915D01*
X-40310Y1162020D01*
X-40153Y1161915D01*
Y1161705D01*
X-40310Y1161600D01*
G01X-35498Y1164435D02*
X-34950Y1165170D01*
X-34480Y1165590D01*
X-33853Y1165800D01*
X-33305Y1165590D01*
X-32913Y1165170D01*
X-32600Y1164540D01*
X-32522Y1163805D01*
X-32600Y1163175D01*
X-32913Y1162545D01*
X-33383Y1162020D01*
X-33932Y1161810D01*
X-34558Y1162020D01*
X-35107Y1162650D01*
X-35420Y1163595D01*
X-35498Y1164645D01*
X-35342Y1166010D01*
X-35107Y1166745D01*
X-34715Y1167480D01*
X-34167Y1168005D01*
X-33618Y1168110D01*
X-33070Y1167900D01*
X-32678Y1167375D01*
G01X-27710Y1168110D02*
X-28337Y1167900D01*
X-28807Y1167375D01*
X-29120Y1166745D01*
X-29355Y1165905D01*
X-29433Y1164960D01*
X-29355Y1164015D01*
X-29120Y1163175D01*
X-28807Y1162545D01*
X-28337Y1162020D01*
X-27710Y1161810D01*
X-27083Y1162020D01*
X-26613Y1162545D01*
X-26300Y1163175D01*
X-26065Y1164015D01*
X-25987Y1164960D01*
X-26065Y1165905D01*
X-26300Y1166745D01*
X-26613Y1167375D01*
X-27083Y1167900D01*
X-27710Y1168110D01*
G01X-72162Y1511810D02*
Y1518110D01*
X-73102Y1516850D01*
G01Y1511810D02*
X-71222D01*
G01X-67585Y1512755D02*
X-67115Y1512230D01*
X-66567Y1511915D01*
X-65862Y1511810D01*
X-65157Y1512020D01*
X-64609Y1512440D01*
X-64217Y1513175D01*
X-64139Y1514015D01*
X-64295Y1514855D01*
X-64687Y1515380D01*
X-65235Y1515800D01*
X-65784Y1515905D01*
X-66332Y1515800D01*
X-67037Y1515380D01*
X-66802Y1518110D01*
X-64687D01*
G01X-59562Y1511810D02*
Y1518110D01*
X-60502Y1516850D01*
G01Y1511810D02*
X-58622D01*
G01X-52322D02*
Y1518110D01*
X-55220Y1513595D01*
X-51304D01*
G01X-48294Y1512545D02*
X-47745Y1512020D01*
X-47119Y1511810D01*
X-46492Y1512020D01*
X-45944Y1512650D01*
X-45552Y1513595D01*
X-45395Y1514540D01*
Y1515695D01*
X-45552Y1516640D01*
X-45944Y1517480D01*
X-46414Y1517900D01*
X-46962Y1518110D01*
X-47589Y1517900D01*
X-48059Y1517480D01*
X-48372Y1516850D01*
X-48529Y1516010D01*
X-48372Y1515275D01*
X-47980Y1514540D01*
X-47510Y1514120D01*
X-46962Y1514015D01*
X-46335Y1514225D01*
X-45865Y1514750D01*
X-45395Y1515695D01*
G01X-40662Y1511600D02*
X-40819Y1511705D01*
Y1511915D01*
X-40662Y1512020D01*
X-40505Y1511915D01*
Y1511705D01*
X-40662Y1511600D01*
G01X-35850Y1514435D02*
X-35302Y1515170D01*
X-34832Y1515590D01*
X-34205Y1515800D01*
X-33657Y1515590D01*
X-33265Y1515170D01*
X-32952Y1514540D01*
X-32874Y1513805D01*
X-32952Y1513175D01*
X-33265Y1512545D01*
X-33735Y1512020D01*
X-34284Y1511810D01*
X-34910Y1512020D01*
X-35459Y1512650D01*
X-35772Y1513595D01*
X-35850Y1514645D01*
X-35694Y1516010D01*
X-35459Y1516745D01*
X-35067Y1517480D01*
X-34519Y1518005D01*
X-33970Y1518110D01*
X-33422Y1517900D01*
X-33030Y1517375D01*
G01X-28062Y1518110D02*
X-28689Y1517900D01*
X-29159Y1517375D01*
X-29472Y1516745D01*
X-29707Y1515905D01*
X-29785Y1514960D01*
X-29707Y1514015D01*
X-29472Y1513175D01*
X-29159Y1512545D01*
X-28689Y1512020D01*
X-28062Y1511810D01*
X-27435Y1512020D01*
X-26965Y1512545D01*
X-26652Y1513175D01*
X-26417Y1514015D01*
X-26339Y1514960D01*
X-26417Y1515905D01*
X-26652Y1516745D01*
X-26965Y1517375D01*
X-27435Y1517900D01*
X-28062Y1518110D01*
G01X-82267Y1584842D02*
Y1591142D01*
X-83207Y1589882D01*
G01Y1584842D02*
X-81327D01*
G01X-77690Y1585787D02*
X-77220Y1585262D01*
X-76672Y1584947D01*
X-75967Y1584842D01*
X-75262Y1585052D01*
X-74714Y1585472D01*
X-74322Y1586207D01*
X-74244Y1587047D01*
X-74400Y1587887D01*
X-74792Y1588412D01*
X-75340Y1588832D01*
X-75889Y1588937D01*
X-76437Y1588832D01*
X-77142Y1588412D01*
X-76907Y1591142D01*
X-74792D01*
G01X-69667Y1584842D02*
X-69119Y1584947D01*
X-68492Y1585262D01*
X-68100Y1585787D01*
X-67944Y1586522D01*
X-68100Y1587257D01*
X-68570Y1587887D01*
X-69275Y1588202D01*
X-70059D01*
X-70529Y1588412D01*
X-70920Y1588937D01*
X-71077Y1589672D01*
X-70842Y1590407D01*
X-70294Y1590932D01*
X-69667Y1591142D01*
X-69040Y1590932D01*
X-68492Y1590407D01*
X-68257Y1589672D01*
X-68414Y1588937D01*
X-68805Y1588412D01*
X-69275Y1588202D01*
X-70059D01*
X-70764Y1587887D01*
X-71234Y1587257D01*
X-71390Y1586522D01*
X-71234Y1585787D01*
X-70842Y1585262D01*
X-70215Y1584947D01*
X-69667Y1584842D01*
G01X-63524D02*
X-63367Y1586207D01*
X-63132Y1587362D01*
X-62819Y1588412D01*
X-62427Y1589567D01*
X-61800Y1591142D01*
X-64934D01*
G01X-58399Y1585577D02*
X-57850Y1585052D01*
X-57224Y1584842D01*
X-56597Y1585052D01*
X-56049Y1585682D01*
X-55657Y1586627D01*
X-55500Y1587572D01*
Y1588727D01*
X-55657Y1589672D01*
X-56049Y1590512D01*
X-56519Y1590932D01*
X-57067Y1591142D01*
X-57694Y1590932D01*
X-58164Y1590512D01*
X-58477Y1589882D01*
X-58634Y1589042D01*
X-58477Y1588307D01*
X-58085Y1587572D01*
X-57615Y1587152D01*
X-57067Y1587047D01*
X-56440Y1587257D01*
X-55970Y1587782D01*
X-55500Y1588727D01*
G01X-50767Y1584632D02*
X-50924Y1584737D01*
Y1584947D01*
X-50767Y1585052D01*
X-50610Y1584947D01*
Y1584737D01*
X-50767Y1584632D01*
G01X-45799Y1585577D02*
X-45250Y1585052D01*
X-44624Y1584842D01*
X-43997Y1585052D01*
X-43449Y1585682D01*
X-43057Y1586627D01*
X-42900Y1587572D01*
Y1588727D01*
X-43057Y1589672D01*
X-43449Y1590512D01*
X-43919Y1590932D01*
X-44467Y1591142D01*
X-45094Y1590932D01*
X-45564Y1590512D01*
X-45877Y1589882D01*
X-46034Y1589042D01*
X-45877Y1588307D01*
X-45485Y1587572D01*
X-45015Y1587152D01*
X-44467Y1587047D01*
X-43840Y1587257D01*
X-43370Y1587782D01*
X-42900Y1588727D01*
G01X-39655Y1590092D02*
X-39185Y1590722D01*
X-38637Y1591037D01*
X-38010Y1591142D01*
X-37227Y1590932D01*
X-36679Y1590407D01*
X-36522Y1589777D01*
X-36600Y1589147D01*
X-36914Y1588622D01*
X-38480Y1587572D01*
X-39185Y1586837D01*
X-39655Y1585787D01*
X-39812Y1584842D01*
X-36522D01*
G01X-72821Y1861811D02*
Y1868111D01*
X-73761Y1866851D01*
G01Y1861811D02*
X-71881D01*
G01X-66521D02*
X-65973Y1861916D01*
X-65346Y1862231D01*
X-64954Y1862756D01*
X-64798Y1863491D01*
X-64954Y1864226D01*
X-65424Y1864856D01*
X-66129Y1865171D01*
X-66913D01*
X-67383Y1865381D01*
X-67774Y1865906D01*
X-67931Y1866641D01*
X-67696Y1867376D01*
X-67148Y1867901D01*
X-66521Y1868111D01*
X-65894Y1867901D01*
X-65346Y1867376D01*
X-65111Y1866641D01*
X-65268Y1865906D01*
X-65659Y1865381D01*
X-66129Y1865171D01*
X-66913D01*
X-67618Y1864856D01*
X-68088Y1864226D01*
X-68244Y1863491D01*
X-68088Y1862756D01*
X-67696Y1862231D01*
X-67069Y1861916D01*
X-66521Y1861811D01*
G01X-61709Y1864436D02*
X-61161Y1865171D01*
X-60691Y1865591D01*
X-60064Y1865801D01*
X-59516Y1865591D01*
X-59124Y1865171D01*
X-58811Y1864541D01*
X-58733Y1863806D01*
X-58811Y1863176D01*
X-59124Y1862546D01*
X-59594Y1862021D01*
X-60143Y1861811D01*
X-60769Y1862021D01*
X-61318Y1862651D01*
X-61631Y1863596D01*
X-61709Y1864646D01*
X-61553Y1866011D01*
X-61318Y1866746D01*
X-60926Y1867481D01*
X-60378Y1868006D01*
X-59829Y1868111D01*
X-59281Y1867901D01*
X-58889Y1867376D01*
G01X-52981Y1861811D02*
Y1868111D01*
X-55879Y1863596D01*
X-51963D01*
G01X-48953Y1862546D02*
X-48404Y1862021D01*
X-47778Y1861811D01*
X-47151Y1862021D01*
X-46603Y1862651D01*
X-46211Y1863596D01*
X-46054Y1864541D01*
Y1865696D01*
X-46211Y1866641D01*
X-46603Y1867481D01*
X-47073Y1867901D01*
X-47621Y1868111D01*
X-48248Y1867901D01*
X-48718Y1867481D01*
X-49031Y1866851D01*
X-49188Y1866011D01*
X-49031Y1865276D01*
X-48639Y1864541D01*
X-48169Y1864121D01*
X-47621Y1864016D01*
X-46994Y1864226D01*
X-46524Y1864751D01*
X-46054Y1865696D01*
G01X-41321Y1861601D02*
X-41478Y1861706D01*
Y1861916D01*
X-41321Y1862021D01*
X-41164Y1861916D01*
Y1861706D01*
X-41321Y1861601D01*
G01X-36509Y1864436D02*
X-35961Y1865171D01*
X-35491Y1865591D01*
X-34864Y1865801D01*
X-34316Y1865591D01*
X-33924Y1865171D01*
X-33611Y1864541D01*
X-33533Y1863806D01*
X-33611Y1863176D01*
X-33924Y1862546D01*
X-34394Y1862021D01*
X-34943Y1861811D01*
X-35569Y1862021D01*
X-36118Y1862651D01*
X-36431Y1863596D01*
X-36509Y1864646D01*
X-36353Y1866011D01*
X-36118Y1866746D01*
X-35726Y1867481D01*
X-35178Y1868006D01*
X-34629Y1868111D01*
X-34081Y1867901D01*
X-33689Y1867376D01*
G01X-28721Y1861811D02*
Y1868111D01*
X-29661Y1866851D01*
G01Y1861811D02*
X-27781D01*
G01X-85283Y1919141D02*
Y1925441D01*
X-86223Y1924181D01*
G01Y1919141D02*
X-84343D01*
G01X-80315Y1919876D02*
X-79766Y1919351D01*
X-79140Y1919141D01*
X-78513Y1919351D01*
X-77965Y1919981D01*
X-77573Y1920926D01*
X-77416Y1921871D01*
Y1923026D01*
X-77573Y1923971D01*
X-77965Y1924811D01*
X-78435Y1925231D01*
X-78983Y1925441D01*
X-79610Y1925231D01*
X-80080Y1924811D01*
X-80393Y1924181D01*
X-80550Y1923341D01*
X-80393Y1922606D01*
X-80001Y1921871D01*
X-79531Y1921451D01*
X-78983Y1921346D01*
X-78356Y1921556D01*
X-77886Y1922081D01*
X-77416Y1923026D01*
G01X-74171Y1924391D02*
X-73701Y1925021D01*
X-73153Y1925336D01*
X-72526Y1925441D01*
X-71743Y1925231D01*
X-71195Y1924706D01*
X-71038Y1924076D01*
X-71116Y1923446D01*
X-71430Y1922921D01*
X-72996Y1921871D01*
X-73701Y1921136D01*
X-74171Y1920086D01*
X-74328Y1919141D01*
X-71038D01*
G01X-67871Y1924391D02*
X-67401Y1925021D01*
X-66853Y1925336D01*
X-66226Y1925441D01*
X-65443Y1925231D01*
X-64895Y1924706D01*
X-64738Y1924076D01*
X-64816Y1923446D01*
X-65130Y1922921D01*
X-66696Y1921871D01*
X-67401Y1921136D01*
X-67871Y1920086D01*
X-68028Y1919141D01*
X-64738D01*
G01X-61571Y1924391D02*
X-61101Y1925021D01*
X-60553Y1925336D01*
X-59926Y1925441D01*
X-59143Y1925231D01*
X-58595Y1924706D01*
X-58438Y1924076D01*
X-58516Y1923446D01*
X-58830Y1922921D01*
X-60396Y1921871D01*
X-61101Y1921136D01*
X-61571Y1920086D01*
X-61728Y1919141D01*
X-58438D01*
G01X-53783Y1918931D02*
X-53940Y1919036D01*
Y1919246D01*
X-53783Y1919351D01*
X-53626Y1919246D01*
Y1919036D01*
X-53783Y1918931D01*
G01X-48815Y1919876D02*
X-48266Y1919351D01*
X-47640Y1919141D01*
X-47013Y1919351D01*
X-46465Y1919981D01*
X-46073Y1920926D01*
X-45916Y1921871D01*
Y1923026D01*
X-46073Y1923971D01*
X-46465Y1924811D01*
X-46935Y1925231D01*
X-47483Y1925441D01*
X-48110Y1925231D01*
X-48580Y1924811D01*
X-48893Y1924181D01*
X-49050Y1923341D01*
X-48893Y1922606D01*
X-48501Y1921871D01*
X-48031Y1921451D01*
X-47483Y1921346D01*
X-46856Y1921556D01*
X-46386Y1922081D01*
X-45916Y1923026D01*
G01X-41183Y1919141D02*
Y1925441D01*
X-42123Y1924181D01*
G01Y1919141D02*
X-40243D01*
G01X-89466Y2028761D02*
X-88996Y2029391D01*
X-88448Y2029706D01*
X-87821Y2029811D01*
X-87038Y2029601D01*
X-86490Y2029076D01*
X-86333Y2028446D01*
X-86411Y2027816D01*
X-86725Y2027291D01*
X-88291Y2026241D01*
X-88996Y2025506D01*
X-89466Y2024456D01*
X-89623Y2023511D01*
X-86333D01*
G01X-81678Y2029811D02*
X-82305Y2029601D01*
X-82775Y2029076D01*
X-83088Y2028446D01*
X-83323Y2027606D01*
X-83401Y2026661D01*
X-83323Y2025716D01*
X-83088Y2024876D01*
X-82775Y2024246D01*
X-82305Y2023721D01*
X-81678Y2023511D01*
X-81051Y2023721D01*
X-80581Y2024246D01*
X-80268Y2024876D01*
X-80033Y2025716D01*
X-79955Y2026661D01*
X-80033Y2027606D01*
X-80268Y2028446D01*
X-80581Y2029076D01*
X-81051Y2029601D01*
X-81678Y2029811D01*
G01X-76866Y2028761D02*
X-76396Y2029391D01*
X-75848Y2029706D01*
X-75221Y2029811D01*
X-74438Y2029601D01*
X-73890Y2029076D01*
X-73733Y2028446D01*
X-73811Y2027816D01*
X-74125Y2027291D01*
X-75691Y2026241D01*
X-76396Y2025506D01*
X-76866Y2024456D01*
X-77023Y2023511D01*
X-73733D01*
G01X-70566Y2026136D02*
X-70018Y2026871D01*
X-69548Y2027291D01*
X-68921Y2027501D01*
X-68373Y2027291D01*
X-67981Y2026871D01*
X-67668Y2026241D01*
X-67590Y2025506D01*
X-67668Y2024876D01*
X-67981Y2024246D01*
X-68451Y2023721D01*
X-69000Y2023511D01*
X-69626Y2023721D01*
X-70175Y2024351D01*
X-70488Y2025296D01*
X-70566Y2026346D01*
X-70410Y2027711D01*
X-70175Y2028446D01*
X-69783Y2029181D01*
X-69235Y2029706D01*
X-68686Y2029811D01*
X-68138Y2029601D01*
X-67746Y2029076D01*
G01X-64266Y2026136D02*
X-63718Y2026871D01*
X-63248Y2027291D01*
X-62621Y2027501D01*
X-62073Y2027291D01*
X-61681Y2026871D01*
X-61368Y2026241D01*
X-61290Y2025506D01*
X-61368Y2024876D01*
X-61681Y2024246D01*
X-62151Y2023721D01*
X-62700Y2023511D01*
X-63326Y2023721D01*
X-63875Y2024351D01*
X-64188Y2025296D01*
X-64266Y2026346D01*
X-64110Y2027711D01*
X-63875Y2028446D01*
X-63483Y2029181D01*
X-62935Y2029706D01*
X-62386Y2029811D01*
X-61838Y2029601D01*
X-61446Y2029076D01*
G01X-56478Y2023301D02*
X-56635Y2023406D01*
Y2023616D01*
X-56478Y2023721D01*
X-56321Y2023616D01*
Y2023406D01*
X-56478Y2023301D01*
G01X-51666Y2026136D02*
X-51118Y2026871D01*
X-50648Y2027291D01*
X-50021Y2027501D01*
X-49473Y2027291D01*
X-49081Y2026871D01*
X-48768Y2026241D01*
X-48690Y2025506D01*
X-48768Y2024876D01*
X-49081Y2024246D01*
X-49551Y2023721D01*
X-50100Y2023511D01*
X-50726Y2023721D01*
X-51275Y2024351D01*
X-51588Y2025296D01*
X-51666Y2026346D01*
X-51510Y2027711D01*
X-51275Y2028446D01*
X-50883Y2029181D01*
X-50335Y2029706D01*
X-49786Y2029811D01*
X-49238Y2029601D01*
X-48846Y2029076D01*
G01X-43878Y2023511D02*
Y2029811D01*
X-44818Y2028551D01*
G01Y2023511D02*
X-42938D01*
G01X-61506Y57748D02*
X-61036Y57223D01*
X-60488Y56908D01*
X-59783Y56803D01*
X-59078Y57013D01*
X-58530Y57433D01*
X-58138Y58168D01*
X-58060Y59008D01*
X-58216Y59848D01*
X-58608Y60373D01*
X-59156Y60793D01*
X-59705Y60898D01*
X-60253Y60793D01*
X-60958Y60373D01*
X-60723Y63103D01*
X-58608D01*
G01X-54815Y57538D02*
X-54266Y57013D01*
X-53640Y56803D01*
X-53013Y57013D01*
X-52465Y57643D01*
X-52073Y58588D01*
X-51916Y59533D01*
Y60688D01*
X-52073Y61633D01*
X-52465Y62473D01*
X-52935Y62893D01*
X-53483Y63103D01*
X-54110Y62893D01*
X-54580Y62473D01*
X-54893Y61843D01*
X-55050Y61003D01*
X-54893Y60268D01*
X-54501Y59533D01*
X-54031Y59113D01*
X-53483Y59008D01*
X-52856Y59218D01*
X-52386Y59743D01*
X-51916Y60688D01*
G01X-48515Y57538D02*
X-47966Y57013D01*
X-47340Y56803D01*
X-46713Y57013D01*
X-46165Y57643D01*
X-45773Y58588D01*
X-45616Y59533D01*
Y60688D01*
X-45773Y61633D01*
X-46165Y62473D01*
X-46635Y62893D01*
X-47183Y63103D01*
X-47810Y62893D01*
X-48280Y62473D01*
X-48593Y61843D01*
X-48750Y61003D01*
X-48593Y60268D01*
X-48201Y59533D01*
X-47731Y59113D01*
X-47183Y59008D01*
X-46556Y59218D01*
X-46086Y59743D01*
X-45616Y60688D01*
G01X-40883Y56593D02*
X-41040Y56698D01*
Y56908D01*
X-40883Y57013D01*
X-40726Y56908D01*
Y56698D01*
X-40883Y56593D01*
G01X-36306Y57748D02*
X-35836Y57223D01*
X-35288Y56908D01*
X-34583Y56803D01*
X-33878Y57013D01*
X-33330Y57433D01*
X-32938Y58168D01*
X-32860Y59008D01*
X-33016Y59848D01*
X-33408Y60373D01*
X-33956Y60793D01*
X-34505Y60898D01*
X-35053Y60793D01*
X-35758Y60373D01*
X-35523Y63103D01*
X-33408D01*
G01X-30006Y58063D02*
X-29536Y57328D01*
X-28910Y56908D01*
X-28205Y56803D01*
X-27578Y56908D01*
X-26951Y57433D01*
X-26560Y58063D01*
X-26481Y58693D01*
X-26638Y59428D01*
X-27186Y59953D01*
X-27735Y60163D01*
X-28440D01*
G01X-27735D02*
X-27265Y60478D01*
X-26873Y61003D01*
X-26716Y61633D01*
X-26873Y62263D01*
X-27265Y62788D01*
X-27970Y63103D01*
X-28675Y62998D01*
X-29380Y62578D01*
G01X-54990Y270911D02*
X-54520Y271541D01*
X-53972Y271856D01*
X-53345Y271961D01*
X-52562Y271751D01*
X-52014Y271226D01*
X-51857Y270596D01*
X-51935Y269966D01*
X-52249Y269441D01*
X-53815Y268391D01*
X-54520Y267656D01*
X-54990Y266606D01*
X-55147Y265661D01*
X-51857D01*
G01X-48690Y268286D02*
X-48142Y269021D01*
X-47672Y269441D01*
X-47045Y269651D01*
X-46497Y269441D01*
X-46105Y269021D01*
X-45792Y268391D01*
X-45714Y267656D01*
X-45792Y267026D01*
X-46105Y266396D01*
X-46575Y265871D01*
X-47124Y265661D01*
X-47750Y265871D01*
X-48299Y266501D01*
X-48612Y267446D01*
X-48690Y268496D01*
X-48534Y269861D01*
X-48299Y270596D01*
X-47907Y271331D01*
X-47359Y271856D01*
X-46810Y271961D01*
X-46262Y271751D01*
X-45870Y271226D01*
G01X-40902Y265661D02*
X-40354Y265766D01*
X-39727Y266081D01*
X-39335Y266606D01*
X-39179Y267341D01*
X-39335Y268076D01*
X-39805Y268706D01*
X-40510Y269021D01*
X-41294D01*
X-41764Y269231D01*
X-42155Y269756D01*
X-42312Y270491D01*
X-42077Y271226D01*
X-41529Y271751D01*
X-40902Y271961D01*
X-40275Y271751D01*
X-39727Y271226D01*
X-39492Y270491D01*
X-39649Y269756D01*
X-40040Y269231D01*
X-40510Y269021D01*
X-41294D01*
X-41999Y268706D01*
X-42469Y268076D01*
X-42625Y267341D01*
X-42469Y266606D01*
X-42077Y266081D01*
X-41450Y265766D01*
X-40902Y265661D01*
G01X-34602D02*
X-34054Y265766D01*
X-33427Y266081D01*
X-33035Y266606D01*
X-32879Y267341D01*
X-33035Y268076D01*
X-33505Y268706D01*
X-34210Y269021D01*
X-34994D01*
X-35464Y269231D01*
X-35855Y269756D01*
X-36012Y270491D01*
X-35777Y271226D01*
X-35229Y271751D01*
X-34602Y271961D01*
X-33975Y271751D01*
X-33427Y271226D01*
X-33192Y270491D01*
X-33349Y269756D01*
X-33740Y269231D01*
X-34210Y269021D01*
X-34994D01*
X-35699Y268706D01*
X-36169Y268076D01*
X-36325Y267341D01*
X-36169Y266606D01*
X-35777Y266081D01*
X-35150Y265766D01*
X-34602Y265661D01*
G01X-28302Y265451D02*
X-28459Y265556D01*
Y265766D01*
X-28302Y265871D01*
X-28145Y265766D01*
Y265556D01*
X-28302Y265451D01*
G01X-22002Y265661D02*
Y271961D01*
X-22942Y270701D01*
G01Y265661D02*
X-21062D01*
G01X-15702D02*
Y271961D01*
X-16642Y270701D01*
G01Y265661D02*
X-14762D01*
G01X-70382Y388944D02*
X-69912Y388209D01*
X-69286Y387789D01*
X-68581Y387684D01*
X-67954Y387789D01*
X-67327Y388314D01*
X-66936Y388944D01*
X-66857Y389574D01*
X-67014Y390309D01*
X-67562Y390834D01*
X-68111Y391044D01*
X-68816D01*
G01X-68111D02*
X-67641Y391359D01*
X-67249Y391884D01*
X-67092Y392514D01*
X-67249Y393144D01*
X-67641Y393669D01*
X-68346Y393984D01*
X-69051Y393879D01*
X-69756Y393459D01*
G01X-63691Y388419D02*
X-63142Y387894D01*
X-62516Y387684D01*
X-61889Y387894D01*
X-61341Y388524D01*
X-60949Y389469D01*
X-60792Y390414D01*
Y391569D01*
X-60949Y392514D01*
X-61341Y393354D01*
X-61811Y393774D01*
X-62359Y393984D01*
X-62986Y393774D01*
X-63456Y393354D01*
X-63769Y392724D01*
X-63926Y391884D01*
X-63769Y391149D01*
X-63377Y390414D01*
X-62907Y389994D01*
X-62359Y389889D01*
X-61732Y390099D01*
X-61262Y390624D01*
X-60792Y391569D01*
G01X-56059Y393984D02*
X-56686Y393774D01*
X-57156Y393249D01*
X-57469Y392619D01*
X-57704Y391779D01*
X-57782Y390834D01*
X-57704Y389889D01*
X-57469Y389049D01*
X-57156Y388419D01*
X-56686Y387894D01*
X-56059Y387684D01*
X-55432Y387894D01*
X-54962Y388419D01*
X-54649Y389049D01*
X-54414Y389889D01*
X-54336Y390834D01*
X-54414Y391779D01*
X-54649Y392619D01*
X-54962Y393249D01*
X-55432Y393774D01*
X-56059Y393984D01*
G01X-49759Y387684D02*
X-49211Y387789D01*
X-48584Y388104D01*
X-48192Y388629D01*
X-48036Y389364D01*
X-48192Y390099D01*
X-48662Y390729D01*
X-49367Y391044D01*
X-50151D01*
X-50621Y391254D01*
X-51012Y391779D01*
X-51169Y392514D01*
X-50934Y393249D01*
X-50386Y393774D01*
X-49759Y393984D01*
X-49132Y393774D01*
X-48584Y393249D01*
X-48349Y392514D01*
X-48506Y391779D01*
X-48897Y391254D01*
X-49367Y391044D01*
X-50151D01*
X-50856Y390729D01*
X-51326Y390099D01*
X-51482Y389364D01*
X-51326Y388629D01*
X-50934Y388104D01*
X-50307Y387789D01*
X-49759Y387684D01*
G01X-43459Y387474D02*
X-43616Y387579D01*
Y387789D01*
X-43459Y387894D01*
X-43302Y387789D01*
Y387579D01*
X-43459Y387474D01*
G01X-38882Y388944D02*
X-38412Y388209D01*
X-37786Y387789D01*
X-37081Y387684D01*
X-36454Y387789D01*
X-35827Y388314D01*
X-35436Y388944D01*
X-35357Y389574D01*
X-35514Y390309D01*
X-36062Y390834D01*
X-36611Y391044D01*
X-37316D01*
G01X-36611D02*
X-36141Y391359D01*
X-35749Y391884D01*
X-35592Y392514D01*
X-35749Y393144D01*
X-36141Y393669D01*
X-36846Y393984D01*
X-37551Y393879D01*
X-38256Y393459D01*
G01X-29919Y387684D02*
Y393984D01*
X-32817Y389469D01*
X-28901D01*
G01X0Y-31358D02*
X-627Y-31568D01*
X-1097Y-32093D01*
X-1410Y-32723D01*
X-1645Y-33563D01*
X-1723Y-34508D01*
X-1645Y-35453D01*
X-1410Y-36293D01*
X-1097Y-36923D01*
X-627Y-37448D01*
X0Y-37658D01*
X627Y-37448D01*
X1097Y-36923D01*
X1410Y-36293D01*
X1645Y-35453D01*
X1723Y-34508D01*
X1645Y-33563D01*
X1410Y-32723D01*
X1097Y-32093D01*
X627Y-31568D01*
X0Y-31358D01*
G01X6705Y-124160D02*
X7332Y-124685D01*
X8037Y-125000D01*
X8663D01*
X9290Y-124685D01*
X9760Y-124160D01*
X9995Y-123425D01*
X9838Y-122690D01*
X9447Y-122060D01*
X8742Y-121640D01*
X7802Y-121430D01*
X7253Y-121010D01*
X7018Y-120275D01*
X7175Y-119540D01*
X7567Y-119015D01*
X8115Y-118700D01*
X8663D01*
X9212Y-118910D01*
X9682Y-119435D01*
G01X13005Y-125000D02*
Y-118700D01*
G01X16295D02*
Y-125000D01*
G01Y-121850D02*
X13005D01*
G01X20010Y-118700D02*
X21890D01*
G01X20950D02*
Y-125000D01*
G01X20010D02*
X21890D01*
G01X28817D02*
X25683D01*
Y-118700D01*
X28817D01*
G01X27563Y-121745D02*
X25683D01*
G01X31748Y-125000D02*
Y-118700D01*
X35352Y-125000D01*
Y-118700D01*
G01X39693Y-126155D02*
X40007Y-124790D01*
G01X46150Y-118700D02*
Y-125000D01*
G01X44348Y-118700D02*
X47952D01*
G01X50492Y-125000D02*
X52450Y-118700D01*
X54408Y-125000D01*
G01X53703Y-122795D02*
X51197D01*
G01X57810Y-118700D02*
X59690D01*
G01X58750D02*
Y-125000D01*
G01X57810D02*
X59690D01*
G01X62700Y-118700D02*
X63797Y-125000D01*
X65050Y-118700D01*
X66303Y-125000D01*
X67400Y-118700D01*
G01X69392Y-125000D02*
X71350Y-118700D01*
X73308Y-125000D01*
G01X72603Y-122795D02*
X70097D01*
G01X75848Y-125000D02*
Y-118700D01*
X79452Y-125000D01*
Y-118700D01*
G01X88683Y-125000D02*
Y-118700D01*
X90642D01*
X91268Y-119015D01*
X91660Y-119435D01*
X91817Y-120275D01*
X91660Y-121115D01*
X91190Y-121640D01*
X90642Y-121955D01*
X88683D01*
G01X90642D02*
X91817Y-125000D01*
G01X96550Y-125210D02*
X96393Y-125105D01*
Y-124895D01*
X96550Y-124790D01*
X96707Y-124895D01*
Y-125105D01*
X96550Y-125210D01*
G01X102850Y-125000D02*
X102223Y-124895D01*
X101675Y-124475D01*
X101205Y-123845D01*
X100892Y-123110D01*
X100735Y-122270D01*
Y-121430D01*
X100892Y-120590D01*
X101205Y-119855D01*
X101675Y-119225D01*
X102223Y-118805D01*
X102850Y-118700D01*
X103477Y-118805D01*
X104025Y-119225D01*
X104495Y-119855D01*
X104808Y-120590D01*
X104965Y-121430D01*
Y-122270D01*
X104808Y-123110D01*
X104495Y-123845D01*
X104025Y-124475D01*
X103477Y-124895D01*
X102850Y-125000D01*
G01X109150Y-125210D02*
X108993Y-125105D01*
Y-124895D01*
X109150Y-124790D01*
X109307Y-124895D01*
Y-125105D01*
X109150Y-125210D01*
G01X117173Y-119225D02*
X116703Y-118910D01*
X116155Y-118700D01*
X115528D01*
X114823Y-119015D01*
X114275Y-119540D01*
X113883Y-120170D01*
X113570Y-121220D01*
X113492Y-122165D01*
X113648Y-123110D01*
X113883Y-123740D01*
X114353Y-124370D01*
X114902Y-124790D01*
X115450Y-125000D01*
X115998D01*
X116547Y-124790D01*
X117017Y-124475D01*
X117408Y-124055D01*
G01X121750Y-125210D02*
X121593Y-125105D01*
Y-124895D01*
X121750Y-124790D01*
X121907Y-124895D01*
Y-125105D01*
X121750Y-125210D01*
G01X6627Y-115000D02*
Y-108700D01*
G01X9603D02*
X6627Y-112585D01*
G01X10073Y-115000D02*
X7958Y-110800D01*
G01X12927Y-108700D02*
Y-113215D01*
X13240Y-114160D01*
X13867Y-114790D01*
X14650Y-115000D01*
X15433Y-114790D01*
X16060Y-114160D01*
X16373Y-113215D01*
Y-108700D01*
G01X22517Y-115000D02*
X19383D01*
Y-108700D01*
X22517D01*
G01X21263Y-111745D02*
X19383D01*
G01X26310Y-108700D02*
X28190D01*
G01X27250D02*
Y-115000D01*
G01X26310D02*
X28190D01*
G01X38205Y-114160D02*
X38832Y-114685D01*
X39537Y-115000D01*
X40163D01*
X40790Y-114685D01*
X41260Y-114160D01*
X41495Y-113425D01*
X41338Y-112690D01*
X40947Y-112060D01*
X40242Y-111640D01*
X39302Y-111430D01*
X38753Y-111010D01*
X38518Y-110275D01*
X38675Y-109540D01*
X39067Y-109015D01*
X39615Y-108700D01*
X40163D01*
X40712Y-108910D01*
X41182Y-109435D01*
G01X44505Y-115000D02*
Y-108700D01*
G01X47795D02*
Y-115000D01*
G01Y-111850D02*
X44505D01*
G01X50492Y-115000D02*
X52450Y-108700D01*
X54408Y-115000D01*
G01X53703Y-112795D02*
X51197D01*
G01X56948Y-115000D02*
Y-108700D01*
X60552Y-115000D01*
Y-108700D01*
G01X69705Y-115000D02*
Y-108700D01*
G01X72995D02*
Y-115000D01*
G01Y-111850D02*
X69705D01*
G01X76005Y-114160D02*
X76632Y-114685D01*
X77337Y-115000D01*
X77963D01*
X78590Y-114685D01*
X79060Y-114160D01*
X79295Y-113425D01*
X79138Y-112690D01*
X78747Y-112060D01*
X78042Y-111640D01*
X77102Y-111430D01*
X76553Y-111010D01*
X76318Y-110275D01*
X76475Y-109540D01*
X76867Y-109015D01*
X77415Y-108700D01*
X77963D01*
X78512Y-108910D01*
X78982Y-109435D01*
G01X83010Y-108700D02*
X84890D01*
G01X83950D02*
Y-115000D01*
G01X83010D02*
X84890D01*
G01X88292D02*
X90250Y-108700D01*
X92208Y-115000D01*
G01X91503Y-112795D02*
X88997D01*
G01X94748Y-115000D02*
Y-108700D01*
X98352Y-115000D01*
Y-108700D01*
G01X103320Y-111850D02*
X104887D01*
Y-113740D01*
X104417Y-114370D01*
X103868Y-114790D01*
X103085Y-115000D01*
X102302Y-114790D01*
X101753Y-114370D01*
X101283Y-113740D01*
X100970Y-113005D01*
X100813Y-112165D01*
Y-111430D01*
X100970Y-110800D01*
X101283Y-110065D01*
X101753Y-109435D01*
X102223Y-109015D01*
X102850Y-108700D01*
X103398D01*
X104025Y-108910D01*
X104495Y-109330D01*
G01X108993Y-116155D02*
X109307Y-114790D01*
G01X115450Y-108700D02*
Y-115000D01*
G01X113648Y-108700D02*
X117252D01*
G01X119792Y-115000D02*
X121750Y-108700D01*
X123708Y-115000D01*
G01X123003Y-112795D02*
X120497D01*
G01X128050Y-115000D02*
X127423Y-114895D01*
X126875Y-114475D01*
X126405Y-113845D01*
X126092Y-113110D01*
X125935Y-112270D01*
Y-111430D01*
X126092Y-110590D01*
X126405Y-109855D01*
X126875Y-109225D01*
X127423Y-108805D01*
X128050Y-108700D01*
X128677Y-108805D01*
X129225Y-109225D01*
X129695Y-109855D01*
X130008Y-110590D01*
X130165Y-111430D01*
Y-112270D01*
X130008Y-113110D01*
X129695Y-113845D01*
X129225Y-114475D01*
X128677Y-114895D01*
X128050Y-115000D01*
G01X140650D02*
Y-112165D01*
X139083Y-108700D01*
G01X142217D02*
X140650Y-112165D01*
G01X145227Y-108700D02*
Y-113215D01*
X145540Y-114160D01*
X146167Y-114790D01*
X146950Y-115000D01*
X147733Y-114790D01*
X148360Y-114160D01*
X148673Y-113215D01*
Y-108700D01*
G01X151292Y-115000D02*
X153250Y-108700D01*
X155208Y-115000D01*
G01X154503Y-112795D02*
X151997D01*
G01X157748Y-115000D02*
Y-108700D01*
X161352Y-115000D01*
Y-108700D01*
G01X30650Y-92300D02*
X28130Y-91883D01*
X25925Y-90217D01*
X24035Y-87717D01*
X22775Y-84800D01*
X22145Y-81467D01*
Y-78133D01*
X22775Y-74800D01*
X24035Y-71883D01*
X25925Y-69384D01*
X28130Y-67717D01*
X30650Y-67300D01*
X33170Y-67717D01*
X35375Y-69384D01*
X37265Y-71883D01*
X38525Y-74800D01*
X39155Y-78133D01*
Y-81467D01*
X38525Y-84800D01*
X37265Y-87717D01*
X35375Y-90217D01*
X33170Y-91883D01*
X30650Y-92300D01*
G01X33170Y-85633D02*
X36950Y-92300D01*
G01X50495Y-75634D02*
Y-87300D01*
X51755Y-90217D01*
X53645Y-91883D01*
X55850Y-92300D01*
X58055Y-91883D01*
X59945Y-90217D01*
X61205Y-87300D01*
G01Y-92300D02*
Y-75634D01*
G01X86720Y-92300D02*
Y-75634D01*
G01Y-78550D02*
X85460Y-76884D01*
X83570Y-76050D01*
X81365Y-75634D01*
X79160Y-76467D01*
X77270Y-78133D01*
X76010Y-80634D01*
X75380Y-83967D01*
X76010Y-87300D01*
X77270Y-89801D01*
X79160Y-91467D01*
X81365Y-92300D01*
X83570Y-91883D01*
X85460Y-90634D01*
X86720Y-88967D01*
G01X100895Y-92300D02*
Y-75634D01*
G01Y-79800D02*
X102155Y-77717D01*
X104045Y-76050D01*
X106565Y-75634D01*
X108770Y-76050D01*
X110660Y-77717D01*
X111605Y-80634D01*
Y-92300D01*
G01X131450Y-67300D02*
Y-92300D01*
G01X127040Y-75634D02*
X135860D01*
G01X162320Y-92300D02*
Y-75634D01*
G01Y-78550D02*
X161060Y-76884D01*
X159170Y-76050D01*
X156965Y-75634D01*
X154760Y-76467D01*
X152870Y-78133D01*
X151610Y-80634D01*
X150980Y-83967D01*
X151610Y-87300D01*
X152870Y-89801D01*
X154760Y-91467D01*
X156965Y-92300D01*
X159170Y-91883D01*
X161060Y-90634D01*
X162320Y-88967D01*
G01X6548Y-105000D02*
Y-98700D01*
X10152Y-105000D01*
Y-98700D01*
G01X14650Y-105000D02*
X14023Y-104895D01*
X13475Y-104475D01*
X13005Y-103845D01*
X12692Y-103110D01*
X12535Y-102270D01*
Y-101430D01*
X12692Y-100590D01*
X13005Y-99855D01*
X13475Y-99225D01*
X14023Y-98805D01*
X14650Y-98700D01*
X15277Y-98805D01*
X15825Y-99225D01*
X16295Y-99855D01*
X16608Y-100590D01*
X16765Y-101430D01*
Y-102270D01*
X16608Y-103110D01*
X16295Y-103845D01*
X15825Y-104475D01*
X15277Y-104895D01*
X14650Y-105000D01*
G01X20950Y-105210D02*
X20793Y-105105D01*
Y-104895D01*
X20950Y-104790D01*
X21107Y-104895D01*
Y-105105D01*
X20950Y-105210D01*
G01X27250Y-105000D02*
Y-98700D01*
X26310Y-99960D01*
G01Y-105000D02*
X28190D01*
G01X33550D02*
X34098Y-104895D01*
X34725Y-104580D01*
X35117Y-104055D01*
X35273Y-103320D01*
X35117Y-102585D01*
X34647Y-101955D01*
X33942Y-101640D01*
X33158D01*
X32688Y-101430D01*
X32297Y-100905D01*
X32140Y-100170D01*
X32375Y-99435D01*
X32923Y-98910D01*
X33550Y-98700D01*
X34177Y-98910D01*
X34725Y-99435D01*
X34960Y-100170D01*
X34803Y-100905D01*
X34412Y-101430D01*
X33942Y-101640D01*
X33158D01*
X32453Y-101955D01*
X31983Y-102585D01*
X31827Y-103320D01*
X31983Y-104055D01*
X32375Y-104580D01*
X33002Y-104895D01*
X33550Y-105000D01*
G01X39850D02*
X40398Y-104895D01*
X41025Y-104580D01*
X41417Y-104055D01*
X41573Y-103320D01*
X41417Y-102585D01*
X40947Y-101955D01*
X40242Y-101640D01*
X39458D01*
X38988Y-101430D01*
X38597Y-100905D01*
X38440Y-100170D01*
X38675Y-99435D01*
X39223Y-98910D01*
X39850Y-98700D01*
X40477Y-98910D01*
X41025Y-99435D01*
X41260Y-100170D01*
X41103Y-100905D01*
X40712Y-101430D01*
X40242Y-101640D01*
X39458D01*
X38753Y-101955D01*
X38283Y-102585D01*
X38127Y-103320D01*
X38283Y-104055D01*
X38675Y-104580D01*
X39302Y-104895D01*
X39850Y-105000D01*
G01X45993Y-106155D02*
X46307Y-104790D01*
G01X50100Y-98700D02*
X51197Y-105000D01*
X52450Y-98700D01*
X53703Y-105000D01*
X54800Y-98700D01*
G01X60317Y-105000D02*
X57183D01*
Y-98700D01*
X60317D01*
G01X59063Y-101745D02*
X57183D01*
G01X63248Y-105000D02*
Y-98700D01*
X66852Y-105000D01*
Y-98700D01*
G01X76005Y-105000D02*
Y-98700D01*
G01X79295D02*
Y-105000D01*
G01Y-101850D02*
X76005D01*
G01X81600Y-98700D02*
X82697Y-105000D01*
X83950Y-98700D01*
X85203Y-105000D01*
X86300Y-98700D01*
G01X88292Y-105000D02*
X90250Y-98700D01*
X92208Y-105000D01*
G01X91503Y-102795D02*
X88997D01*
G01X101362Y-99750D02*
X101832Y-99120D01*
X102380Y-98805D01*
X103007Y-98700D01*
X103790Y-98910D01*
X104338Y-99435D01*
X104495Y-100065D01*
X104417Y-100695D01*
X104103Y-101220D01*
X102537Y-102270D01*
X101832Y-103005D01*
X101362Y-104055D01*
X101205Y-105000D01*
X104495D01*
G01X107348D02*
Y-98700D01*
X110952Y-105000D01*
Y-98700D01*
G01X113727Y-105000D02*
Y-98700D01*
X115293D01*
X115920Y-99015D01*
X116390Y-99435D01*
X116782Y-100065D01*
X117095Y-100800D01*
X117173Y-101850D01*
X117095Y-102900D01*
X116782Y-103635D01*
X116390Y-104265D01*
X115920Y-104685D01*
X115293Y-105000D01*
X113727D01*
G01X126483D02*
Y-98700D01*
X128442D01*
X129068Y-99015D01*
X129460Y-99435D01*
X129617Y-100275D01*
X129460Y-101115D01*
X128990Y-101640D01*
X128442Y-101955D01*
X126483D01*
G01X128442D02*
X129617Y-105000D01*
G01X132627D02*
Y-98700D01*
X134193D01*
X134820Y-99015D01*
X135290Y-99435D01*
X135682Y-100065D01*
X135995Y-100800D01*
X136073Y-101850D01*
X135995Y-102900D01*
X135682Y-103635D01*
X135290Y-104265D01*
X134820Y-104685D01*
X134193Y-105000D01*
X132627D01*
G01X140650Y-105210D02*
X140493Y-105105D01*
Y-104895D01*
X140650Y-104790D01*
X140807Y-104895D01*
Y-105105D01*
X140650Y-105210D01*
G01X15885Y-42485D02*
X9585D01*
X10845Y-43425D01*
G01X15885D02*
Y-41545D01*
G01X10635Y-37673D02*
X10005Y-37203D01*
X9690Y-36655D01*
X9585Y-36028D01*
X9795Y-35245D01*
X10320Y-34697D01*
X10950Y-34540D01*
X11580Y-34618D01*
X12105Y-34932D01*
X13155Y-36498D01*
X13890Y-37203D01*
X14940Y-37673D01*
X15885Y-37830D01*
Y-34540D01*
G01Y-30042D02*
X14520Y-29885D01*
X13365Y-29650D01*
X12315Y-29337D01*
X11160Y-28945D01*
X9585Y-28318D01*
Y-31452D01*
G01X16095Y-23585D02*
X15990Y-23742D01*
X15780D01*
X15675Y-23585D01*
X15780Y-23428D01*
X15990D01*
X16095Y-23585D01*
G01X14625Y-19008D02*
X15360Y-18538D01*
X15780Y-17912D01*
X15885Y-17207D01*
X15780Y-16580D01*
X15255Y-15953D01*
X14625Y-15562D01*
X13995Y-15483D01*
X13260Y-15640D01*
X12735Y-16188D01*
X12525Y-16737D01*
Y-17442D01*
G01Y-16737D02*
X12210Y-16267D01*
X11685Y-15875D01*
X11055Y-15718D01*
X10425Y-15875D01*
X9900Y-16267D01*
X9585Y-16972D01*
X9690Y-17677D01*
X10110Y-18382D01*
G01X14940Y-12708D02*
X15465Y-12238D01*
X15780Y-11690D01*
X15885Y-10985D01*
X15675Y-10280D01*
X15255Y-9732D01*
X14520Y-9340D01*
X13680Y-9262D01*
X12840Y-9418D01*
X12315Y-9810D01*
X11895Y-10358D01*
X11790Y-10907D01*
X11895Y-11455D01*
X12315Y-12160D01*
X9585Y-11925D01*
Y-9810D01*
G01X22927Y-44986D02*
X22297Y-44516D01*
X21982Y-43968D01*
X21877Y-43341D01*
X22087Y-42558D01*
X22612Y-42010D01*
X23242Y-41853D01*
X23872Y-41931D01*
X24397Y-42245D01*
X25447Y-43811D01*
X26182Y-44516D01*
X27232Y-44986D01*
X28177Y-45143D01*
Y-41853D01*
G01X21877Y-37198D02*
X22087Y-37825D01*
X22612Y-38295D01*
X23242Y-38608D01*
X24082Y-38843D01*
X25027Y-38921D01*
X25972Y-38843D01*
X26812Y-38608D01*
X27442Y-38295D01*
X27967Y-37825D01*
X28177Y-37198D01*
X27967Y-36571D01*
X27442Y-36101D01*
X26812Y-35788D01*
X25972Y-35553D01*
X25027Y-35475D01*
X24082Y-35553D01*
X23242Y-35788D01*
X22612Y-36101D01*
X22087Y-36571D01*
X21877Y-37198D01*
G01X28177Y-29958D02*
X21877D01*
X26392Y-32856D01*
Y-28940D01*
G01X28387Y-24598D02*
X28282Y-24755D01*
X28072D01*
X27967Y-24598D01*
X28072Y-24441D01*
X28282D01*
X28387Y-24598D01*
G01X28177Y-18455D02*
X26812Y-18298D01*
X25657Y-18063D01*
X24607Y-17750D01*
X23452Y-17358D01*
X21877Y-16731D01*
Y-19865D01*
G01X22927Y-13486D02*
X22297Y-13016D01*
X21982Y-12468D01*
X21877Y-11841D01*
X22087Y-11058D01*
X22612Y-10510D01*
X23242Y-10353D01*
X23872Y-10431D01*
X24397Y-10745D01*
X25447Y-12311D01*
X26182Y-13016D01*
X27232Y-13486D01*
X28177Y-13643D01*
Y-10353D01*
G01X65879Y-54078D02*
X65144Y-53530D01*
X64724Y-53060D01*
X64514Y-52433D01*
X64724Y-51885D01*
X65144Y-51493D01*
X65774Y-51180D01*
X66509Y-51102D01*
X67139Y-51180D01*
X67769Y-51493D01*
X68294Y-51963D01*
X68504Y-52512D01*
X68294Y-53138D01*
X67664Y-53687D01*
X66719Y-54000D01*
X65669Y-54078D01*
X64304Y-53922D01*
X63569Y-53687D01*
X62834Y-53295D01*
X62309Y-52747D01*
X62204Y-52198D01*
X62414Y-51650D01*
X62939Y-51258D01*
G01X67559Y-48013D02*
X68084Y-47543D01*
X68399Y-46995D01*
X68504Y-46290D01*
X68294Y-45585D01*
X67874Y-45037D01*
X67139Y-44645D01*
X66299Y-44567D01*
X65459Y-44723D01*
X64934Y-45115D01*
X64514Y-45663D01*
X64409Y-46212D01*
X64514Y-46760D01*
X64934Y-47465D01*
X62204Y-47230D01*
Y-45115D01*
G01X67244Y-41713D02*
X67979Y-41243D01*
X68399Y-40617D01*
X68504Y-39912D01*
X68399Y-39285D01*
X67874Y-38658D01*
X67244Y-38267D01*
X66614Y-38188D01*
X65879Y-38345D01*
X65354Y-38893D01*
X65144Y-39442D01*
Y-40147D01*
G01Y-39442D02*
X64829Y-38972D01*
X64304Y-38580D01*
X63674Y-38423D01*
X63044Y-38580D01*
X62519Y-38972D01*
X62204Y-39677D01*
X62309Y-40382D01*
X62729Y-41087D01*
G01X68714Y-33690D02*
X68609Y-33847D01*
X68399D01*
X68294Y-33690D01*
X68399Y-33533D01*
X68609D01*
X68714Y-33690D01*
G01X67559Y-29113D02*
X68084Y-28643D01*
X68399Y-28095D01*
X68504Y-27390D01*
X68294Y-26685D01*
X67874Y-26137D01*
X67139Y-25745D01*
X66299Y-25667D01*
X65459Y-25823D01*
X64934Y-26215D01*
X64514Y-26763D01*
X64409Y-27312D01*
X64514Y-27860D01*
X64934Y-28565D01*
X62204Y-28330D01*
Y-26215D01*
G01X68504Y-20150D02*
X62204D01*
X66719Y-23048D01*
Y-19132D01*
G01X57092Y-51204D02*
X57617Y-50734D01*
X57932Y-50186D01*
X58037Y-49481D01*
X57827Y-48776D01*
X57407Y-48228D01*
X56672Y-47836D01*
X55832Y-47758D01*
X54992Y-47914D01*
X54467Y-48306D01*
X54047Y-48854D01*
X53942Y-49403D01*
X54047Y-49951D01*
X54467Y-50656D01*
X51737Y-50421D01*
Y-48306D01*
G01X58037Y-43338D02*
X56672Y-43181D01*
X55517Y-42946D01*
X54467Y-42633D01*
X53312Y-42241D01*
X51737Y-41614D01*
Y-44748D01*
G01X58037Y-37038D02*
X56672Y-36881D01*
X55517Y-36646D01*
X54467Y-36333D01*
X53312Y-35941D01*
X51737Y-35314D01*
Y-38448D01*
G01X58247Y-30581D02*
X58142Y-30738D01*
X57932D01*
X57827Y-30581D01*
X57932Y-30424D01*
X58142D01*
X58247Y-30581D01*
G01X56777Y-26004D02*
X57512Y-25534D01*
X57932Y-24908D01*
X58037Y-24203D01*
X57932Y-23576D01*
X57407Y-22949D01*
X56777Y-22558D01*
X56147Y-22479D01*
X55412Y-22636D01*
X54887Y-23184D01*
X54677Y-23733D01*
Y-24438D01*
G01Y-23733D02*
X54362Y-23263D01*
X53837Y-22871D01*
X53207Y-22714D01*
X52577Y-22871D01*
X52052Y-23263D01*
X51737Y-23968D01*
X51842Y-24673D01*
X52262Y-25378D01*
G01X57092Y-19704D02*
X57617Y-19234D01*
X57932Y-18686D01*
X58037Y-17981D01*
X57827Y-17276D01*
X57407Y-16728D01*
X56672Y-16336D01*
X55832Y-16258D01*
X54992Y-16414D01*
X54467Y-16806D01*
X54047Y-17354D01*
X53942Y-17903D01*
X54047Y-18451D01*
X54467Y-19156D01*
X51737Y-18921D01*
Y-16806D01*
G01X100840Y2107840D02*
X101365Y2108389D01*
X101575Y2109015D01*
X101365Y2109642D01*
X100735Y2110190D01*
X99790Y2110582D01*
X98845Y2110739D01*
X97690D01*
X96745Y2110582D01*
X95905Y2110190D01*
X95485Y2109720D01*
X95275Y2109172D01*
X95485Y2108545D01*
X95905Y2108075D01*
X96535Y2107762D01*
X97375Y2107605D01*
X98110Y2107762D01*
X98845Y2108154D01*
X99265Y2108624D01*
X99370Y2109172D01*
X99160Y2109799D01*
X98635Y2110269D01*
X97690Y2110739D01*
G01X101575Y2115472D02*
X101470Y2116020D01*
X101155Y2116647D01*
X100630Y2117039D01*
X99895Y2117195D01*
X99160Y2117039D01*
X98530Y2116569D01*
X98215Y2115864D01*
Y2115080D01*
X98005Y2114610D01*
X97480Y2114219D01*
X96745Y2114062D01*
X96010Y2114297D01*
X95485Y2114845D01*
X95275Y2115472D01*
X95485Y2116099D01*
X96010Y2116647D01*
X96745Y2116882D01*
X97480Y2116725D01*
X98005Y2116334D01*
X98215Y2115864D01*
Y2115080D01*
X98530Y2114375D01*
X99160Y2113905D01*
X99895Y2113749D01*
X100630Y2113905D01*
X101155Y2114297D01*
X101470Y2114924D01*
X101575Y2115472D01*
G01Y2122712D02*
X95275D01*
X99790Y2119814D01*
Y2123730D01*
G01X101785Y2128072D02*
X101680Y2127915D01*
X101470D01*
X101365Y2128072D01*
X101470Y2128229D01*
X101680D01*
X101785Y2128072D01*
G01X96325Y2132884D02*
X95695Y2133354D01*
X95380Y2133902D01*
X95275Y2134529D01*
X95485Y2135312D01*
X96010Y2135860D01*
X96640Y2136017D01*
X97270Y2135939D01*
X97795Y2135625D01*
X98845Y2134059D01*
X99580Y2133354D01*
X100630Y2132884D01*
X101575Y2132727D01*
Y2136017D01*
G01X100630Y2138949D02*
X101155Y2139419D01*
X101470Y2139967D01*
X101575Y2140672D01*
X101365Y2141377D01*
X100945Y2141925D01*
X100210Y2142317D01*
X99370Y2142395D01*
X98530Y2142239D01*
X98005Y2141847D01*
X97585Y2141299D01*
X97480Y2140750D01*
X97585Y2140202D01*
X98005Y2139497D01*
X95275Y2139732D01*
Y2141847D01*
G01X166535Y-52709D02*
X160235D01*
X161495Y-53649D01*
G01X166535D02*
Y-51769D01*
G01X163910Y-47897D02*
X163175Y-47349D01*
X162755Y-46879D01*
X162545Y-46252D01*
X162755Y-45704D01*
X163175Y-45312D01*
X163805Y-44999D01*
X164540Y-44921D01*
X165170Y-44999D01*
X165800Y-45312D01*
X166325Y-45782D01*
X166535Y-46331D01*
X166325Y-46957D01*
X165695Y-47506D01*
X164750Y-47819D01*
X163700Y-47897D01*
X162335Y-47741D01*
X161600Y-47506D01*
X160865Y-47114D01*
X160340Y-46566D01*
X160235Y-46017D01*
X160445Y-45469D01*
X160970Y-45077D01*
G01X165275Y-41832D02*
X166010Y-41362D01*
X166430Y-40736D01*
X166535Y-40031D01*
X166430Y-39404D01*
X165905Y-38777D01*
X165275Y-38386D01*
X164645Y-38307D01*
X163910Y-38464D01*
X163385Y-39012D01*
X163175Y-39561D01*
Y-40266D01*
G01Y-39561D02*
X162860Y-39091D01*
X162335Y-38699D01*
X161705Y-38542D01*
X161075Y-38699D01*
X160550Y-39091D01*
X160235Y-39796D01*
X160340Y-40501D01*
X160760Y-41206D01*
G01X165275Y-35532D02*
X166010Y-35062D01*
X166430Y-34436D01*
X166535Y-33731D01*
X166430Y-33104D01*
X165905Y-32477D01*
X165275Y-32086D01*
X164645Y-32007D01*
X163910Y-32164D01*
X163385Y-32712D01*
X163175Y-33261D01*
Y-33966D01*
G01Y-33261D02*
X162860Y-32791D01*
X162335Y-32399D01*
X161705Y-32242D01*
X161075Y-32399D01*
X160550Y-32791D01*
X160235Y-33496D01*
X160340Y-34201D01*
X160760Y-34906D01*
G01X166745Y-27509D02*
X166640Y-27666D01*
X166430D01*
X166325Y-27509D01*
X166430Y-27352D01*
X166640D01*
X166745Y-27509D01*
G01X166535Y-21209D02*
X166430Y-20661D01*
X166115Y-20034D01*
X165590Y-19642D01*
X164855Y-19486D01*
X164120Y-19642D01*
X163490Y-20112D01*
X163175Y-20817D01*
Y-21601D01*
X162965Y-22071D01*
X162440Y-22462D01*
X161705Y-22619D01*
X160970Y-22384D01*
X160445Y-21836D01*
X160235Y-21209D01*
X160445Y-20582D01*
X160970Y-20034D01*
X161705Y-19799D01*
X162440Y-19956D01*
X162965Y-20347D01*
X163175Y-20817D01*
Y-21601D01*
X163490Y-22306D01*
X164120Y-22776D01*
X164855Y-22932D01*
X165590Y-22776D01*
X166115Y-22384D01*
X166430Y-21757D01*
X166535Y-21209D01*
G01X165590Y-16632D02*
X166115Y-16162D01*
X166430Y-15614D01*
X166535Y-14909D01*
X166325Y-14204D01*
X165905Y-13656D01*
X165170Y-13264D01*
X164330Y-13186D01*
X163490Y-13342D01*
X162965Y-13734D01*
X162545Y-14282D01*
X162440Y-14831D01*
X162545Y-15379D01*
X162965Y-16084D01*
X160235Y-15849D01*
Y-13734D01*
G01X202000Y-72000D02*
Y-80000D01*
X206000D01*
G01X213800D02*
Y-74667D01*
G01Y-75600D02*
X213400Y-75067D01*
X212800Y-74800D01*
X212100Y-74667D01*
X211400Y-74933D01*
X210800Y-75467D01*
X210400Y-76267D01*
X210200Y-77333D01*
X210400Y-78400D01*
X210800Y-79200D01*
X211400Y-79733D01*
X212100Y-80000D01*
X212800Y-79867D01*
X213400Y-79467D01*
X213800Y-78934D01*
G01X217900Y-82400D02*
X218500Y-82667D01*
X219300Y-82400D01*
X219800Y-81867D01*
X220200Y-81200D01*
X220800Y-79067D01*
X222100Y-74667D01*
G01X218900D02*
X220800Y-79067D01*
G01X226500Y-76400D02*
X229700D01*
X229400Y-75467D01*
X228900Y-74933D01*
X228200Y-74667D01*
X227500Y-74800D01*
X226900Y-75200D01*
X226500Y-76133D01*
X226300Y-76934D01*
Y-77733D01*
X226500Y-78533D01*
X227000Y-79333D01*
X227600Y-79867D01*
X228300Y-80000D01*
X229000Y-79733D01*
X229700Y-78934D01*
G01X234600Y-80000D02*
Y-74667D01*
G01Y-75733D02*
X235100Y-75200D01*
X235600Y-74800D01*
X236300Y-74667D01*
X236800Y-74800D01*
X237400Y-75200D01*
G01X223400Y-128934D02*
X224200Y-129600D01*
X225100Y-130000D01*
X225900D01*
X226700Y-129600D01*
X227300Y-128934D01*
X227600Y-128000D01*
X227400Y-127067D01*
X226900Y-126267D01*
X226000Y-125733D01*
X224800Y-125467D01*
X224100Y-124933D01*
X223800Y-124000D01*
X224000Y-123067D01*
X224500Y-122400D01*
X225200Y-122000D01*
X225900D01*
X226600Y-122267D01*
X227200Y-122933D01*
G01X235300Y-130000D02*
Y-124667D01*
G01Y-125600D02*
X234900Y-125067D01*
X234300Y-124800D01*
X233600Y-124667D01*
X232900Y-124933D01*
X232300Y-125467D01*
X231900Y-126267D01*
X231700Y-127333D01*
X231900Y-128400D01*
X232300Y-129200D01*
X232900Y-129733D01*
X233600Y-130000D01*
X234300Y-129867D01*
X234900Y-129467D01*
X235300Y-128934D01*
G01X239800Y-130000D02*
Y-124667D01*
G01Y-126000D02*
X240200Y-125333D01*
X240800Y-124800D01*
X241600Y-124667D01*
X242300Y-124800D01*
X242900Y-125333D01*
X243200Y-126267D01*
Y-130000D01*
G01X251300Y-122000D02*
Y-130000D01*
G01Y-128800D02*
X250900Y-129467D01*
X250300Y-129867D01*
X249600Y-130000D01*
X248800Y-129733D01*
X248200Y-129067D01*
X247800Y-128267D01*
X247700Y-127333D01*
X247800Y-126400D01*
X248200Y-125600D01*
X248800Y-124933D01*
X249600Y-124667D01*
X250300Y-124800D01*
X250800Y-125067D01*
X251300Y-125600D01*
G01X255400Y-132400D02*
X256000Y-132667D01*
X256800Y-132400D01*
X257300Y-131867D01*
X257700Y-131200D01*
X258300Y-129067D01*
X259600Y-124667D01*
G01X256400D02*
X258300Y-129067D01*
G01X226100Y-105000D02*
Y-97000D01*
X229900D01*
G01X228500Y-100867D02*
X226100D01*
G01X233500Y-105000D02*
X236000Y-97000D01*
X238500Y-105000D01*
G01X237600Y-102200D02*
X234400D01*
G01X244800Y-100733D02*
X245200Y-100333D01*
X245500Y-99667D01*
X245700Y-98733D01*
X245500Y-97933D01*
X245100Y-97400D01*
X244400Y-97000D01*
X241700D01*
Y-105000D01*
X245000D01*
X245700Y-104467D01*
X246100Y-103667D01*
X246300Y-102733D01*
X246100Y-101800D01*
X245500Y-101000D01*
X244800Y-100733D01*
X241700D01*
G01X308977Y-50389D02*
X309712Y-49919D01*
X310132Y-49293D01*
X310237Y-48588D01*
X310132Y-47961D01*
X309607Y-47334D01*
X308977Y-46943D01*
X308347Y-46864D01*
X307612Y-47021D01*
X307087Y-47569D01*
X306877Y-48118D01*
Y-48823D01*
G01Y-48118D02*
X306562Y-47648D01*
X306037Y-47256D01*
X305407Y-47099D01*
X304777Y-47256D01*
X304252Y-47648D01*
X303937Y-48353D01*
X304042Y-49058D01*
X304462Y-49763D01*
G01X303937Y-42366D02*
X304147Y-42993D01*
X304672Y-43463D01*
X305302Y-43776D01*
X306142Y-44011D01*
X307087Y-44089D01*
X308032Y-44011D01*
X308872Y-43776D01*
X309502Y-43463D01*
X310027Y-42993D01*
X310237Y-42366D01*
X310027Y-41739D01*
X309502Y-41269D01*
X308872Y-40956D01*
X308032Y-40721D01*
X307087Y-40643D01*
X306142Y-40721D01*
X305302Y-40956D01*
X304672Y-41269D01*
X304147Y-41739D01*
X303937Y-42366D01*
G01X310237Y-36223D02*
X308872Y-36066D01*
X307717Y-35831D01*
X306667Y-35518D01*
X305512Y-35126D01*
X303937Y-34499D01*
Y-37633D01*
G01Y-29766D02*
X304147Y-30393D01*
X304672Y-30863D01*
X305302Y-31176D01*
X306142Y-31411D01*
X307087Y-31489D01*
X308032Y-31411D01*
X308872Y-31176D01*
X309502Y-30863D01*
X310027Y-30393D01*
X310237Y-29766D01*
X310027Y-29139D01*
X309502Y-28669D01*
X308872Y-28356D01*
X308032Y-28121D01*
X307087Y-28043D01*
X306142Y-28121D01*
X305302Y-28356D01*
X304672Y-28669D01*
X304147Y-29139D01*
X303937Y-29766D01*
G01X310447Y-23466D02*
X310342Y-23623D01*
X310132D01*
X310027Y-23466D01*
X310132Y-23309D01*
X310342D01*
X310447Y-23466D01*
G01X310237Y-17166D02*
X310132Y-16618D01*
X309817Y-15991D01*
X309292Y-15599D01*
X308557Y-15443D01*
X307822Y-15599D01*
X307192Y-16069D01*
X306877Y-16774D01*
Y-17558D01*
X306667Y-18028D01*
X306142Y-18419D01*
X305407Y-18576D01*
X304672Y-18341D01*
X304147Y-17793D01*
X303937Y-17166D01*
X304147Y-16539D01*
X304672Y-15991D01*
X305407Y-15756D01*
X306142Y-15913D01*
X306667Y-16304D01*
X306877Y-16774D01*
Y-17558D01*
X307192Y-18263D01*
X307822Y-18733D01*
X308557Y-18889D01*
X309292Y-18733D01*
X309817Y-18341D01*
X310132Y-17714D01*
X310237Y-17166D01*
G01Y-11023D02*
X308872Y-10866D01*
X307717Y-10631D01*
X306667Y-10318D01*
X305512Y-9926D01*
X303937Y-9299D01*
Y-12433D01*
G01X328600Y-123333D02*
X329200Y-122533D01*
X329900Y-122133D01*
X330700Y-122000D01*
X331700Y-122267D01*
X332400Y-122933D01*
X332600Y-123733D01*
X332500Y-124534D01*
X332100Y-125200D01*
X330100Y-126533D01*
X329200Y-127467D01*
X328600Y-128800D01*
X328400Y-130000D01*
X332600D01*
G01X338500Y-122000D02*
X337700Y-122267D01*
X337100Y-122933D01*
X336700Y-123733D01*
X336400Y-124800D01*
X336300Y-126000D01*
X336400Y-127200D01*
X336700Y-128267D01*
X337100Y-129067D01*
X337700Y-129733D01*
X338500Y-130000D01*
X339300Y-129733D01*
X339900Y-129067D01*
X340300Y-128267D01*
X340600Y-127200D01*
X340700Y-126000D01*
X340600Y-124800D01*
X340300Y-123733D01*
X339900Y-122933D01*
X339300Y-122267D01*
X338500Y-122000D01*
G01X346500Y-130000D02*
Y-122000D01*
X345300Y-123600D01*
G01Y-130000D02*
X347700D01*
G01X352600Y-123333D02*
X353200Y-122533D01*
X353900Y-122133D01*
X354700Y-122000D01*
X355700Y-122267D01*
X356400Y-122933D01*
X356600Y-123733D01*
X356500Y-124534D01*
X356100Y-125200D01*
X354100Y-126533D01*
X353200Y-127467D01*
X352600Y-128800D01*
X352400Y-130000D01*
X356600D01*
G01X360700Y-130267D02*
X364300Y-122000D01*
G01X370500D02*
X369700Y-122267D01*
X369100Y-122933D01*
X368700Y-123733D01*
X368400Y-124800D01*
X368300Y-126000D01*
X368400Y-127200D01*
X368700Y-128267D01*
X369100Y-129067D01*
X369700Y-129733D01*
X370500Y-130000D01*
X371300Y-129733D01*
X371900Y-129067D01*
X372300Y-128267D01*
X372600Y-127200D01*
X372700Y-126000D01*
X372600Y-124800D01*
X372300Y-123733D01*
X371900Y-122933D01*
X371300Y-122267D01*
X370500Y-122000D01*
G01X376800Y-129067D02*
X377500Y-129733D01*
X378300Y-130000D01*
X379100Y-129733D01*
X379800Y-128934D01*
X380300Y-127733D01*
X380500Y-126533D01*
Y-125067D01*
X380300Y-123867D01*
X379800Y-122800D01*
X379200Y-122267D01*
X378500Y-122000D01*
X377700Y-122267D01*
X377100Y-122800D01*
X376700Y-123600D01*
X376500Y-124667D01*
X376700Y-125600D01*
X377200Y-126533D01*
X377800Y-127067D01*
X378500Y-127200D01*
X379300Y-126934D01*
X379900Y-126267D01*
X380500Y-125067D01*
G01X384700Y-130267D02*
X388300Y-122000D01*
G01X392600Y-123333D02*
X393200Y-122533D01*
X393900Y-122133D01*
X394700Y-122000D01*
X395700Y-122267D01*
X396400Y-122933D01*
X396600Y-123733D01*
X396500Y-124534D01*
X396100Y-125200D01*
X394100Y-126533D01*
X393200Y-127467D01*
X392600Y-128800D01*
X392400Y-130000D01*
X396600D01*
G01X402500D02*
X403200Y-129867D01*
X404000Y-129467D01*
X404500Y-128800D01*
X404700Y-127867D01*
X404500Y-126934D01*
X403900Y-126133D01*
X403000Y-125733D01*
X402000D01*
X401400Y-125467D01*
X400900Y-124800D01*
X400700Y-123867D01*
X401000Y-122933D01*
X401700Y-122267D01*
X402500Y-122000D01*
X403300Y-122267D01*
X404000Y-122933D01*
X404300Y-123867D01*
X404100Y-124800D01*
X403600Y-125467D01*
X403000Y-125733D01*
X402000D01*
X401100Y-126133D01*
X400500Y-126934D01*
X400300Y-127867D01*
X400500Y-128800D01*
X401000Y-129467D01*
X401800Y-129867D01*
X402500Y-130000D01*
G01X328300Y-105000D02*
Y-97000D01*
X330300D01*
X331100Y-97400D01*
X331700Y-97933D01*
X332200Y-98733D01*
X332600Y-99667D01*
X332700Y-101000D01*
X332600Y-102333D01*
X332200Y-103267D01*
X331700Y-104067D01*
X331100Y-104600D01*
X330300Y-105000D01*
X328300D01*
G01X336000D02*
X338500Y-97000D01*
X341000Y-105000D01*
G01X340100Y-102200D02*
X336900D01*
G01X346500Y-97000D02*
X345700Y-97267D01*
X345100Y-97933D01*
X344700Y-98733D01*
X344400Y-99800D01*
X344300Y-101000D01*
X344400Y-102200D01*
X344700Y-103267D01*
X345100Y-104067D01*
X345700Y-104733D01*
X346500Y-105000D01*
X347300Y-104733D01*
X347900Y-104067D01*
X348300Y-103267D01*
X348600Y-102200D01*
X348700Y-101000D01*
X348600Y-99800D01*
X348300Y-98733D01*
X347900Y-97933D01*
X347300Y-97267D01*
X346500Y-97000D01*
G01X354500D02*
Y-105000D01*
G01X352200Y-97000D02*
X356800D01*
G01X360600Y-101667D02*
X361300Y-100733D01*
X361900Y-100200D01*
X362700Y-99933D01*
X363400Y-100200D01*
X363900Y-100733D01*
X364300Y-101533D01*
X364400Y-102467D01*
X364300Y-103267D01*
X363900Y-104067D01*
X363300Y-104733D01*
X362600Y-105000D01*
X361800Y-104733D01*
X361100Y-103934D01*
X360700Y-102733D01*
X360600Y-101400D01*
X360800Y-99667D01*
X361100Y-98733D01*
X361600Y-97800D01*
X362300Y-97133D01*
X363000Y-97000D01*
X363700Y-97267D01*
X364200Y-97933D01*
G01X367900Y-105000D02*
Y-97000D01*
X370500Y-103667D01*
X373100Y-97000D01*
Y-105000D01*
G01X378500Y-97000D02*
Y-105000D01*
G01X376200Y-97000D02*
X380800D01*
G01X387300Y-100733D02*
X387700Y-100333D01*
X388000Y-99667D01*
X388200Y-98733D01*
X388000Y-97933D01*
X387600Y-97400D01*
X386900Y-97000D01*
X384200D01*
Y-105000D01*
X387500D01*
X388200Y-104467D01*
X388600Y-103667D01*
X388800Y-102733D01*
X388600Y-101800D01*
X388000Y-101000D01*
X387300Y-100733D01*
X384200D01*
G01X394500Y-105000D02*
X395200Y-104867D01*
X396000Y-104467D01*
X396500Y-103800D01*
X396700Y-102867D01*
X396500Y-101934D01*
X395900Y-101133D01*
X395000Y-100733D01*
X394000D01*
X393400Y-100467D01*
X392900Y-99800D01*
X392700Y-98867D01*
X393000Y-97933D01*
X393700Y-97267D01*
X394500Y-97000D01*
X395300Y-97267D01*
X396000Y-97933D01*
X396300Y-98867D01*
X396100Y-99800D01*
X395600Y-100467D01*
X395000Y-100733D01*
X394000D01*
X393100Y-101133D01*
X392500Y-101934D01*
X392300Y-102867D01*
X392500Y-103800D01*
X393000Y-104467D01*
X393800Y-104867D01*
X394500Y-105000D01*
G01X400300D02*
Y-97000D01*
X402300D01*
X403100Y-97400D01*
X403700Y-97933D01*
X404200Y-98733D01*
X404600Y-99667D01*
X404700Y-101000D01*
X404600Y-102333D01*
X404200Y-103267D01*
X403700Y-104067D01*
X403100Y-104600D01*
X402300Y-105000D01*
X400300D01*
G01X410500Y-97000D02*
X409700Y-97267D01*
X409100Y-97933D01*
X408700Y-98733D01*
X408400Y-99800D01*
X408300Y-101000D01*
X408400Y-102200D01*
X408700Y-103267D01*
X409100Y-104067D01*
X409700Y-104733D01*
X410500Y-105000D01*
X411300Y-104733D01*
X411900Y-104067D01*
X412300Y-103267D01*
X412600Y-102200D01*
X412700Y-101000D01*
X412600Y-99800D01*
X412300Y-98733D01*
X411900Y-97933D01*
X411300Y-97267D01*
X410500Y-97000D01*
G01X350500Y-72000D02*
Y-80000D01*
G01X348200Y-72000D02*
X352800D01*
G01X356600Y-76667D02*
X357300Y-75733D01*
X357900Y-75200D01*
X358700Y-74933D01*
X359400Y-75200D01*
X359900Y-75733D01*
X360300Y-76533D01*
X360400Y-77467D01*
X360300Y-78267D01*
X359900Y-79067D01*
X359300Y-79733D01*
X358600Y-80000D01*
X357800Y-79733D01*
X357100Y-78934D01*
X356700Y-77733D01*
X356600Y-76400D01*
X356800Y-74667D01*
X357100Y-73733D01*
X357600Y-72800D01*
X358300Y-72133D01*
X359000Y-72000D01*
X359700Y-72267D01*
X360200Y-72933D01*
G01X363900Y-80000D02*
Y-72000D01*
X366500Y-78667D01*
X369100Y-72000D01*
Y-80000D01*
G01X371500Y-82667D02*
X377500D01*
G01X380500Y-80000D02*
Y-72000D01*
X382900D01*
X383700Y-72400D01*
X384300Y-73333D01*
X384500Y-74400D01*
X384300Y-75467D01*
X383800Y-76267D01*
X382900Y-76667D01*
X380500D01*
G01X388300Y-80000D02*
Y-72000D01*
X390300D01*
X391100Y-72400D01*
X391700Y-72933D01*
X392200Y-73733D01*
X392600Y-74667D01*
X392700Y-76000D01*
X392600Y-77333D01*
X392200Y-78267D01*
X391700Y-79067D01*
X391100Y-79600D01*
X390300Y-80000D01*
X388300D01*
G01X399300Y-75733D02*
X399700Y-75333D01*
X400000Y-74667D01*
X400200Y-73733D01*
X400000Y-72933D01*
X399600Y-72400D01*
X398900Y-72000D01*
X396200D01*
Y-80000D01*
X399500D01*
X400200Y-79467D01*
X400600Y-78667D01*
X400800Y-77733D01*
X400600Y-76800D01*
X400000Y-76000D01*
X399300Y-75733D01*
X396200D01*
G01X403500Y-82667D02*
X409500D01*
G01X412300Y-80000D02*
Y-72000D01*
X414300D01*
X415100Y-72400D01*
X415700Y-72933D01*
X416200Y-73733D01*
X416600Y-74667D01*
X416700Y-76000D01*
X416600Y-77333D01*
X416200Y-78267D01*
X415700Y-79067D01*
X415100Y-79600D01*
X414300Y-80000D01*
X412300D01*
G01X419500Y-82667D02*
X425500D01*
G01X431300Y-75733D02*
X431700Y-75333D01*
X432000Y-74667D01*
X432200Y-73733D01*
X432000Y-72933D01*
X431600Y-72400D01*
X430900Y-72000D01*
X428200D01*
Y-80000D01*
X431500D01*
X432200Y-79467D01*
X432600Y-78667D01*
X432800Y-77733D01*
X432600Y-76800D01*
X432000Y-76000D01*
X431300Y-75733D01*
X428200D01*
G01X436300Y-80000D02*
Y-72000D01*
X438300D01*
X439100Y-72400D01*
X439700Y-72933D01*
X440200Y-73733D01*
X440600Y-74667D01*
X440700Y-76000D01*
X440600Y-77333D01*
X440200Y-78267D01*
X439700Y-79067D01*
X439100Y-79600D01*
X438300Y-80000D01*
X436300D01*
G01X361732Y-54095D02*
X362467Y-53625D01*
X362887Y-52999D01*
X362992Y-52294D01*
X362887Y-51667D01*
X362362Y-51040D01*
X361732Y-50649D01*
X361102Y-50570D01*
X360367Y-50727D01*
X359842Y-51275D01*
X359632Y-51824D01*
Y-52529D01*
G01Y-51824D02*
X359317Y-51354D01*
X358792Y-50962D01*
X358162Y-50805D01*
X357532Y-50962D01*
X357007Y-51354D01*
X356692Y-52059D01*
X356797Y-52764D01*
X357217Y-53469D01*
G01X362047Y-47795D02*
X362572Y-47325D01*
X362887Y-46777D01*
X362992Y-46072D01*
X362782Y-45367D01*
X362362Y-44819D01*
X361627Y-44427D01*
X360787Y-44349D01*
X359947Y-44505D01*
X359422Y-44897D01*
X359002Y-45445D01*
X358897Y-45994D01*
X359002Y-46542D01*
X359422Y-47247D01*
X356692Y-47012D01*
Y-44897D01*
G01X362257Y-41104D02*
X362782Y-40555D01*
X362992Y-39929D01*
X362782Y-39302D01*
X362152Y-38754D01*
X361207Y-38362D01*
X360262Y-38205D01*
X359107D01*
X358162Y-38362D01*
X357322Y-38754D01*
X356902Y-39224D01*
X356692Y-39772D01*
X356902Y-40399D01*
X357322Y-40869D01*
X357952Y-41182D01*
X358792Y-41339D01*
X359527Y-41182D01*
X360262Y-40790D01*
X360682Y-40320D01*
X360787Y-39772D01*
X360577Y-39145D01*
X360052Y-38675D01*
X359107Y-38205D01*
G01X362992Y-33472D02*
X362887Y-32924D01*
X362572Y-32297D01*
X362047Y-31905D01*
X361312Y-31749D01*
X360577Y-31905D01*
X359947Y-32375D01*
X359632Y-33080D01*
Y-33864D01*
X359422Y-34334D01*
X358897Y-34725D01*
X358162Y-34882D01*
X357427Y-34647D01*
X356902Y-34099D01*
X356692Y-33472D01*
X356902Y-32845D01*
X357427Y-32297D01*
X358162Y-32062D01*
X358897Y-32219D01*
X359422Y-32610D01*
X359632Y-33080D01*
Y-33864D01*
X359947Y-34569D01*
X360577Y-35039D01*
X361312Y-35195D01*
X362047Y-35039D01*
X362572Y-34647D01*
X362887Y-34020D01*
X362992Y-33472D01*
G01X363202Y-27172D02*
X363097Y-27329D01*
X362887D01*
X362782Y-27172D01*
X362887Y-27015D01*
X363097D01*
X363202Y-27172D01*
G01X362992Y-19932D02*
X356692D01*
X361207Y-22830D01*
Y-18914D01*
G01X357742Y-16060D02*
X357112Y-15590D01*
X356797Y-15042D01*
X356692Y-14415D01*
X356902Y-13632D01*
X357427Y-13084D01*
X358057Y-12927D01*
X358687Y-13005D01*
X359212Y-13319D01*
X360262Y-14885D01*
X360997Y-15590D01*
X362047Y-16060D01*
X362992Y-16217D01*
Y-12927D01*
G01X390034Y-56115D02*
X390769Y-55645D01*
X391189Y-55019D01*
X391294Y-54314D01*
X391189Y-53687D01*
X390664Y-53060D01*
X390034Y-52669D01*
X389404Y-52590D01*
X388669Y-52747D01*
X388144Y-53295D01*
X387934Y-53844D01*
Y-54549D01*
G01Y-53844D02*
X387619Y-53374D01*
X387094Y-52982D01*
X386464Y-52825D01*
X385834Y-52982D01*
X385309Y-53374D01*
X384994Y-54079D01*
X385099Y-54784D01*
X385519Y-55489D01*
G01X391294Y-48249D02*
X389929Y-48092D01*
X388774Y-47857D01*
X387724Y-47544D01*
X386569Y-47152D01*
X384994Y-46525D01*
Y-49659D01*
G01X390034Y-43515D02*
X390769Y-43045D01*
X391189Y-42419D01*
X391294Y-41714D01*
X391189Y-41087D01*
X390664Y-40460D01*
X390034Y-40069D01*
X389404Y-39990D01*
X388669Y-40147D01*
X388144Y-40695D01*
X387934Y-41244D01*
Y-41949D01*
G01Y-41244D02*
X387619Y-40774D01*
X387094Y-40382D01*
X386464Y-40225D01*
X385834Y-40382D01*
X385309Y-40774D01*
X384994Y-41479D01*
X385099Y-42184D01*
X385519Y-42889D01*
G01X390034Y-37215D02*
X390769Y-36745D01*
X391189Y-36119D01*
X391294Y-35414D01*
X391189Y-34787D01*
X390664Y-34160D01*
X390034Y-33769D01*
X389404Y-33690D01*
X388669Y-33847D01*
X388144Y-34395D01*
X387934Y-34944D01*
Y-35649D01*
G01Y-34944D02*
X387619Y-34474D01*
X387094Y-34082D01*
X386464Y-33925D01*
X385834Y-34082D01*
X385309Y-34474D01*
X384994Y-35179D01*
X385099Y-35884D01*
X385519Y-36589D01*
G01X391504Y-29192D02*
X391399Y-29349D01*
X391189D01*
X391084Y-29192D01*
X391189Y-29035D01*
X391399D01*
X391504Y-29192D01*
G01X391294Y-22892D02*
X391189Y-22344D01*
X390874Y-21717D01*
X390349Y-21325D01*
X389614Y-21169D01*
X388879Y-21325D01*
X388249Y-21795D01*
X387934Y-22500D01*
Y-23284D01*
X387724Y-23754D01*
X387199Y-24145D01*
X386464Y-24302D01*
X385729Y-24067D01*
X385204Y-23519D01*
X384994Y-22892D01*
X385204Y-22265D01*
X385729Y-21717D01*
X386464Y-21482D01*
X387199Y-21639D01*
X387724Y-22030D01*
X387934Y-22500D01*
Y-23284D01*
X388249Y-23989D01*
X388879Y-24459D01*
X389614Y-24615D01*
X390349Y-24459D01*
X390874Y-24067D01*
X391189Y-23440D01*
X391294Y-22892D01*
G01X390349Y-18315D02*
X390874Y-17845D01*
X391189Y-17297D01*
X391294Y-16592D01*
X391084Y-15887D01*
X390664Y-15339D01*
X389929Y-14947D01*
X389089Y-14869D01*
X388249Y-15025D01*
X387724Y-15417D01*
X387304Y-15965D01*
X387199Y-16514D01*
X387304Y-17062D01*
X387724Y-17767D01*
X384994Y-17532D01*
Y-15417D01*
G01X407597Y389396D02*
X408067Y388661D01*
X408693Y388241D01*
X409398Y388136D01*
X410025Y388241D01*
X410652Y388766D01*
X411043Y389396D01*
X411122Y390026D01*
X410965Y390761D01*
X410417Y391286D01*
X409868Y391496D01*
X409163D01*
G01X409868D02*
X410338Y391811D01*
X410730Y392336D01*
X410887Y392966D01*
X410730Y393596D01*
X410338Y394121D01*
X409633Y394436D01*
X408928Y394331D01*
X408223Y393911D01*
G01X415620Y388136D02*
X416168Y388241D01*
X416795Y388556D01*
X417187Y389081D01*
X417343Y389816D01*
X417187Y390551D01*
X416717Y391181D01*
X416012Y391496D01*
X415228D01*
X414758Y391706D01*
X414367Y392231D01*
X414210Y392966D01*
X414445Y393701D01*
X414993Y394226D01*
X415620Y394436D01*
X416247Y394226D01*
X416795Y393701D01*
X417030Y392966D01*
X416873Y392231D01*
X416482Y391706D01*
X416012Y391496D01*
X415228D01*
X414523Y391181D01*
X414053Y390551D01*
X413897Y389816D01*
X414053Y389081D01*
X414445Y388556D01*
X415072Y388241D01*
X415620Y388136D01*
G01X420432Y393386D02*
X420902Y394016D01*
X421450Y394331D01*
X422077Y394436D01*
X422860Y394226D01*
X423408Y393701D01*
X423565Y393071D01*
X423487Y392441D01*
X423173Y391916D01*
X421607Y390866D01*
X420902Y390131D01*
X420432Y389081D01*
X420275Y388136D01*
X423565D01*
G01X426497Y389081D02*
X426967Y388556D01*
X427515Y388241D01*
X428220Y388136D01*
X428925Y388346D01*
X429473Y388766D01*
X429865Y389501D01*
X429943Y390341D01*
X429787Y391181D01*
X429395Y391706D01*
X428847Y392126D01*
X428298Y392231D01*
X427750Y392126D01*
X427045Y391706D01*
X427280Y394436D01*
X429395D01*
G01X434520Y387926D02*
X434363Y388031D01*
Y388241D01*
X434520Y388346D01*
X434677Y388241D01*
Y388031D01*
X434520Y387926D01*
G01X439332Y393386D02*
X439802Y394016D01*
X440350Y394331D01*
X440977Y394436D01*
X441760Y394226D01*
X442308Y393701D01*
X442465Y393071D01*
X442387Y392441D01*
X442073Y391916D01*
X440507Y390866D01*
X439802Y390131D01*
X439332Y389081D01*
X439175Y388136D01*
X442465D01*
G01X447120Y394436D02*
X446493Y394226D01*
X446023Y393701D01*
X445710Y393071D01*
X445475Y392231D01*
X445397Y391286D01*
X445475Y390341D01*
X445710Y389501D01*
X446023Y388871D01*
X446493Y388346D01*
X447120Y388136D01*
X447747Y388346D01*
X448217Y388871D01*
X448530Y389501D01*
X448765Y390341D01*
X448843Y391286D01*
X448765Y392231D01*
X448530Y393071D01*
X448217Y393701D01*
X447747Y394226D01*
X447120Y394436D01*
G01X408662Y2124907D02*
X402362D01*
X406877Y2122009D01*
Y2125925D01*
G01X402362Y2130267D02*
X402572Y2129640D01*
X403097Y2129170D01*
X403727Y2128857D01*
X404567Y2128622D01*
X405512Y2128544D01*
X406457Y2128622D01*
X407297Y2128857D01*
X407927Y2129170D01*
X408452Y2129640D01*
X408662Y2130267D01*
X408452Y2130894D01*
X407927Y2131364D01*
X407297Y2131677D01*
X406457Y2131912D01*
X405512Y2131990D01*
X404567Y2131912D01*
X403727Y2131677D01*
X403097Y2131364D01*
X402572Y2130894D01*
X402362Y2130267D01*
G01X407717Y2134844D02*
X408242Y2135314D01*
X408557Y2135862D01*
X408662Y2136567D01*
X408452Y2137272D01*
X408032Y2137820D01*
X407297Y2138212D01*
X406457Y2138290D01*
X405617Y2138134D01*
X405092Y2137742D01*
X404672Y2137194D01*
X404567Y2136645D01*
X404672Y2136097D01*
X405092Y2135392D01*
X402362Y2135627D01*
Y2137742D01*
G01X407717Y2141144D02*
X408242Y2141614D01*
X408557Y2142162D01*
X408662Y2142867D01*
X408452Y2143572D01*
X408032Y2144120D01*
X407297Y2144512D01*
X406457Y2144590D01*
X405617Y2144434D01*
X405092Y2144042D01*
X404672Y2143494D01*
X404567Y2142945D01*
X404672Y2142397D01*
X405092Y2141692D01*
X402362Y2141927D01*
Y2144042D01*
G01X408872Y2149167D02*
X408767Y2149010D01*
X408557D01*
X408452Y2149167D01*
X408557Y2149324D01*
X408767D01*
X408872Y2149167D01*
G01X408662Y2155467D02*
X402362D01*
X403622Y2154527D01*
G01X408662D02*
Y2156407D01*
G01X403412Y2160279D02*
X402782Y2160749D01*
X402467Y2161297D01*
X402362Y2161924D01*
X402572Y2162707D01*
X403097Y2163255D01*
X403727Y2163412D01*
X404357Y2163334D01*
X404882Y2163020D01*
X405932Y2161454D01*
X406667Y2160749D01*
X407717Y2160279D01*
X408662Y2160122D01*
Y2163412D01*
G01X419218Y29305D02*
X419688Y29935D01*
X420236Y30250D01*
X420863Y30355D01*
X421646Y30145D01*
X422194Y29620D01*
X422351Y28990D01*
X422273Y28360D01*
X421959Y27835D01*
X420393Y26785D01*
X419688Y26050D01*
X419218Y25000D01*
X419061Y24055D01*
X422351D01*
G01X426849D02*
X427006Y25420D01*
X427241Y26575D01*
X427554Y27625D01*
X427946Y28780D01*
X428573Y30355D01*
X425439D01*
G01X431818Y29305D02*
X432288Y29935D01*
X432836Y30250D01*
X433463Y30355D01*
X434246Y30145D01*
X434794Y29620D01*
X434951Y28990D01*
X434873Y28360D01*
X434559Y27835D01*
X432993Y26785D01*
X432288Y26050D01*
X431818Y25000D01*
X431661Y24055D01*
X434951D01*
G01X439606Y23845D02*
X439449Y23950D01*
Y24160D01*
X439606Y24265D01*
X439763Y24160D01*
Y23950D01*
X439606Y23845D01*
G01X445906Y30355D02*
X445279Y30145D01*
X444809Y29620D01*
X444496Y28990D01*
X444261Y28150D01*
X444183Y27205D01*
X444261Y26260D01*
X444496Y25420D01*
X444809Y24790D01*
X445279Y24265D01*
X445906Y24055D01*
X446533Y24265D01*
X447003Y24790D01*
X447316Y25420D01*
X447551Y26260D01*
X447629Y27205D01*
X447551Y28150D01*
X447316Y28990D01*
X447003Y29620D01*
X446533Y30145D01*
X445906Y30355D01*
G01X450483Y25000D02*
X450953Y24475D01*
X451501Y24160D01*
X452206Y24055D01*
X452911Y24265D01*
X453459Y24685D01*
X453851Y25420D01*
X453929Y26260D01*
X453773Y27100D01*
X453381Y27625D01*
X452833Y28045D01*
X452284Y28150D01*
X451736Y28045D01*
X451031Y27625D01*
X451266Y30355D01*
X453381D01*
G01X418983Y39585D02*
X419453Y38850D01*
X420079Y38430D01*
X420784Y38325D01*
X421411Y38430D01*
X422038Y38955D01*
X422429Y39585D01*
X422508Y40215D01*
X422351Y40950D01*
X421803Y41475D01*
X421254Y41685D01*
X420549D01*
G01X421254D02*
X421724Y42000D01*
X422116Y42525D01*
X422273Y43155D01*
X422116Y43785D01*
X421724Y44310D01*
X421019Y44625D01*
X420314Y44520D01*
X419609Y44100D01*
G01X425518Y43575D02*
X425988Y44205D01*
X426536Y44520D01*
X427163Y44625D01*
X427946Y44415D01*
X428494Y43890D01*
X428651Y43260D01*
X428573Y42630D01*
X428259Y42105D01*
X426693Y41055D01*
X425988Y40320D01*
X425518Y39270D01*
X425361Y38325D01*
X428651D01*
G01X431583Y39270D02*
X432053Y38745D01*
X432601Y38430D01*
X433306Y38325D01*
X434011Y38535D01*
X434559Y38955D01*
X434951Y39690D01*
X435029Y40530D01*
X434873Y41370D01*
X434481Y41895D01*
X433933Y42315D01*
X433384Y42420D01*
X432836Y42315D01*
X432131Y41895D01*
X432366Y44625D01*
X434481D01*
G01X439606Y38115D02*
X439449Y38220D01*
Y38430D01*
X439606Y38535D01*
X439763Y38430D01*
Y38220D01*
X439606Y38115D01*
G01X444418Y43575D02*
X444888Y44205D01*
X445436Y44520D01*
X446063Y44625D01*
X446846Y44415D01*
X447394Y43890D01*
X447551Y43260D01*
X447473Y42630D01*
X447159Y42105D01*
X445593Y41055D01*
X444888Y40320D01*
X444418Y39270D01*
X444261Y38325D01*
X447551D01*
G01X452206Y44625D02*
X451579Y44415D01*
X451109Y43890D01*
X450796Y43260D01*
X450561Y42420D01*
X450483Y41475D01*
X450561Y40530D01*
X450796Y39690D01*
X451109Y39060D01*
X451579Y38535D01*
X452206Y38325D01*
X452833Y38535D01*
X453303Y39060D01*
X453616Y39690D01*
X453851Y40530D01*
X453929Y41475D01*
X453851Y42420D01*
X453616Y43260D01*
X453303Y43890D01*
X452833Y44415D01*
X452206Y44625D01*
G01X433244Y124015D02*
Y130315D01*
X432304Y129055D01*
G01Y124015D02*
X434184D01*
G01X438056Y129265D02*
X438526Y129895D01*
X439074Y130210D01*
X439701Y130315D01*
X440484Y130105D01*
X441032Y129580D01*
X441189Y128950D01*
X441111Y128320D01*
X440797Y127795D01*
X439231Y126745D01*
X438526Y126010D01*
X438056Y124960D01*
X437899Y124015D01*
X441189D01*
G01X445687D02*
X445844Y125380D01*
X446079Y126535D01*
X446392Y127585D01*
X446784Y128740D01*
X447411Y130315D01*
X444277D01*
G01X452144Y124015D02*
Y130315D01*
X451204Y129055D01*
G01Y124015D02*
X453084D01*
G01X458444Y123805D02*
X458287Y123910D01*
Y124120D01*
X458444Y124225D01*
X458601Y124120D01*
Y123910D01*
X458444Y123805D01*
G01X463256Y126640D02*
X463804Y127375D01*
X464274Y127795D01*
X464901Y128005D01*
X465449Y127795D01*
X465841Y127375D01*
X466154Y126745D01*
X466232Y126010D01*
X466154Y125380D01*
X465841Y124750D01*
X465371Y124225D01*
X464822Y124015D01*
X464196Y124225D01*
X463647Y124855D01*
X463334Y125800D01*
X463256Y126850D01*
X463412Y128215D01*
X463647Y128950D01*
X464039Y129685D01*
X464587Y130210D01*
X465136Y130315D01*
X465684Y130105D01*
X466076Y129580D01*
G01X469321Y124960D02*
X469791Y124435D01*
X470339Y124120D01*
X471044Y124015D01*
X471749Y124225D01*
X472297Y124645D01*
X472689Y125380D01*
X472767Y126220D01*
X472611Y127060D01*
X472219Y127585D01*
X471671Y128005D01*
X471122Y128110D01*
X470574Y128005D01*
X469869Y127585D01*
X470104Y130315D01*
X472219D01*
G01X420969Y204305D02*
X421439Y204935D01*
X421987Y205250D01*
X422614Y205355D01*
X423397Y205145D01*
X423945Y204620D01*
X424102Y203990D01*
X424024Y203360D01*
X423710Y202835D01*
X422144Y201785D01*
X421439Y201050D01*
X420969Y200000D01*
X420812Y199055D01*
X424102D01*
G01X428757Y205355D02*
X428130Y205145D01*
X427660Y204620D01*
X427347Y203990D01*
X427112Y203150D01*
X427034Y202205D01*
X427112Y201260D01*
X427347Y200420D01*
X427660Y199790D01*
X428130Y199265D01*
X428757Y199055D01*
X429384Y199265D01*
X429854Y199790D01*
X430167Y200420D01*
X430402Y201260D01*
X430480Y202205D01*
X430402Y203150D01*
X430167Y203990D01*
X429854Y204620D01*
X429384Y205145D01*
X428757Y205355D01*
G01X433569Y204305D02*
X434039Y204935D01*
X434587Y205250D01*
X435214Y205355D01*
X435997Y205145D01*
X436545Y204620D01*
X436702Y203990D01*
X436624Y203360D01*
X436310Y202835D01*
X434744Y201785D01*
X434039Y201050D01*
X433569Y200000D01*
X433412Y199055D01*
X436702D01*
G01X439869Y204305D02*
X440339Y204935D01*
X440887Y205250D01*
X441514Y205355D01*
X442297Y205145D01*
X442845Y204620D01*
X443002Y203990D01*
X442924Y203360D01*
X442610Y202835D01*
X441044Y201785D01*
X440339Y201050D01*
X439869Y200000D01*
X439712Y199055D01*
X443002D01*
G01X447657Y198845D02*
X447500Y198950D01*
Y199160D01*
X447657Y199265D01*
X447814Y199160D01*
Y198950D01*
X447657Y198845D01*
G01X453957Y205355D02*
X453330Y205145D01*
X452860Y204620D01*
X452547Y203990D01*
X452312Y203150D01*
X452234Y202205D01*
X452312Y201260D01*
X452547Y200420D01*
X452860Y199790D01*
X453330Y199265D01*
X453957Y199055D01*
X454584Y199265D01*
X455054Y199790D01*
X455367Y200420D01*
X455602Y201260D01*
X455680Y202205D01*
X455602Y203150D01*
X455367Y203990D01*
X455054Y204620D01*
X454584Y205145D01*
X453957Y205355D01*
G01X458534Y200000D02*
X459004Y199475D01*
X459552Y199160D01*
X460257Y199055D01*
X460962Y199265D01*
X461510Y199685D01*
X461902Y200420D01*
X461980Y201260D01*
X461824Y202100D01*
X461432Y202625D01*
X460884Y203045D01*
X460335Y203150D01*
X459787Y203045D01*
X459082Y202625D01*
X459317Y205355D01*
X461432D01*
G01X418106Y216374D02*
X418576Y217004D01*
X419124Y217319D01*
X419751Y217424D01*
X420534Y217214D01*
X421082Y216689D01*
X421239Y216059D01*
X421161Y215429D01*
X420847Y214904D01*
X419281Y213854D01*
X418576Y213119D01*
X418106Y212069D01*
X417949Y211124D01*
X421239D01*
G01X425894Y217424D02*
X425267Y217214D01*
X424797Y216689D01*
X424484Y216059D01*
X424249Y215219D01*
X424171Y214274D01*
X424249Y213329D01*
X424484Y212489D01*
X424797Y211859D01*
X425267Y211334D01*
X425894Y211124D01*
X426521Y211334D01*
X426991Y211859D01*
X427304Y212489D01*
X427539Y213329D01*
X427617Y214274D01*
X427539Y215219D01*
X427304Y216059D01*
X426991Y216689D01*
X426521Y217214D01*
X425894Y217424D01*
G01X432037Y211124D02*
X432194Y212489D01*
X432429Y213644D01*
X432742Y214694D01*
X433134Y215849D01*
X433761Y217424D01*
X430627D01*
G01X436771Y212069D02*
X437241Y211544D01*
X437789Y211229D01*
X438494Y211124D01*
X439199Y211334D01*
X439747Y211754D01*
X440139Y212489D01*
X440217Y213329D01*
X440061Y214169D01*
X439669Y214694D01*
X439121Y215114D01*
X438572Y215219D01*
X438024Y215114D01*
X437319Y214694D01*
X437554Y217424D01*
X439669D01*
G01X444794Y210914D02*
X444637Y211019D01*
Y211229D01*
X444794Y211334D01*
X444951Y211229D01*
Y211019D01*
X444794Y210914D01*
G01X449606Y216374D02*
X450076Y217004D01*
X450624Y217319D01*
X451251Y217424D01*
X452034Y217214D01*
X452582Y216689D01*
X452739Y216059D01*
X452661Y215429D01*
X452347Y214904D01*
X450781Y213854D01*
X450076Y213119D01*
X449606Y212069D01*
X449449Y211124D01*
X452739D01*
G01X457394Y217424D02*
X456767Y217214D01*
X456297Y216689D01*
X455984Y216059D01*
X455749Y215219D01*
X455671Y214274D01*
X455749Y213329D01*
X455984Y212489D01*
X456297Y211859D01*
X456767Y211334D01*
X457394Y211124D01*
X458021Y211334D01*
X458491Y211859D01*
X458804Y212489D01*
X459039Y213329D01*
X459117Y214274D01*
X459039Y215219D01*
X458804Y216059D01*
X458491Y216689D01*
X458021Y217214D01*
X457394Y217424D01*
G01X412650Y375315D02*
X413120Y374580D01*
X413746Y374160D01*
X414451Y374055D01*
X415078Y374160D01*
X415705Y374685D01*
X416096Y375315D01*
X416175Y375945D01*
X416018Y376680D01*
X415470Y377205D01*
X414921Y377415D01*
X414216D01*
G01X414921D02*
X415391Y377730D01*
X415783Y378255D01*
X415940Y378885D01*
X415783Y379515D01*
X415391Y380040D01*
X414686Y380355D01*
X413981Y380250D01*
X413276Y379830D01*
G01X420516Y374055D02*
X420673Y375420D01*
X420908Y376575D01*
X421221Y377625D01*
X421613Y378780D01*
X422240Y380355D01*
X419106D01*
G01X426816Y374055D02*
X426973Y375420D01*
X427208Y376575D01*
X427521Y377625D01*
X427913Y378780D01*
X428540Y380355D01*
X425406D01*
G01X431785Y379305D02*
X432255Y379935D01*
X432803Y380250D01*
X433430Y380355D01*
X434213Y380145D01*
X434761Y379620D01*
X434918Y378990D01*
X434840Y378360D01*
X434526Y377835D01*
X432960Y376785D01*
X432255Y376050D01*
X431785Y375000D01*
X431628Y374055D01*
X434918D01*
G01X439573Y373845D02*
X439416Y373950D01*
Y374160D01*
X439573Y374265D01*
X439730Y374160D01*
Y373950D01*
X439573Y373845D01*
G01X445873Y380355D02*
X445246Y380145D01*
X444776Y379620D01*
X444463Y378990D01*
X444228Y378150D01*
X444150Y377205D01*
X444228Y376260D01*
X444463Y375420D01*
X444776Y374790D01*
X445246Y374265D01*
X445873Y374055D01*
X446500Y374265D01*
X446970Y374790D01*
X447283Y375420D01*
X447518Y376260D01*
X447596Y377205D01*
X447518Y378150D01*
X447283Y378990D01*
X446970Y379620D01*
X446500Y380145D01*
X445873Y380355D01*
G01X450450Y375000D02*
X450920Y374475D01*
X451468Y374160D01*
X452173Y374055D01*
X452878Y374265D01*
X453426Y374685D01*
X453818Y375420D01*
X453896Y376260D01*
X453740Y377100D01*
X453348Y377625D01*
X452800Y378045D01*
X452251Y378150D01*
X451703Y378045D01*
X450998Y377625D01*
X451233Y380355D01*
X453348D01*
G01X433510Y425629D02*
Y431929D01*
X430612Y427414D01*
X434528D01*
G01X437382Y430879D02*
X437852Y431509D01*
X438400Y431824D01*
X439027Y431929D01*
X439810Y431719D01*
X440358Y431194D01*
X440515Y430564D01*
X440437Y429934D01*
X440123Y429409D01*
X438557Y428359D01*
X437852Y427624D01*
X437382Y426574D01*
X437225Y425629D01*
X440515D01*
G01X445170D02*
X445718Y425734D01*
X446345Y426049D01*
X446737Y426574D01*
X446893Y427309D01*
X446737Y428044D01*
X446267Y428674D01*
X445562Y428989D01*
X444778D01*
X444308Y429199D01*
X443917Y429724D01*
X443760Y430459D01*
X443995Y431194D01*
X444543Y431719D01*
X445170Y431929D01*
X445797Y431719D01*
X446345Y431194D01*
X446580Y430459D01*
X446423Y429724D01*
X446032Y429199D01*
X445562Y428989D01*
X444778D01*
X444073Y428674D01*
X443603Y428044D01*
X443447Y427309D01*
X443603Y426574D01*
X443995Y426049D01*
X444622Y425734D01*
X445170Y425629D01*
G01X451313D02*
X451470Y426994D01*
X451705Y428149D01*
X452018Y429199D01*
X452410Y430354D01*
X453037Y431929D01*
X449903D01*
G01X457770Y425419D02*
X457613Y425524D01*
Y425734D01*
X457770Y425839D01*
X457927Y425734D01*
Y425524D01*
X457770Y425419D01*
G01X463913Y425629D02*
X464070Y426994D01*
X464305Y428149D01*
X464618Y429199D01*
X465010Y430354D01*
X465637Y431929D01*
X462503D01*
G01X469038Y426364D02*
X469587Y425839D01*
X470213Y425629D01*
X470840Y425839D01*
X471388Y426469D01*
X471780Y427414D01*
X471937Y428359D01*
Y429514D01*
X471780Y430459D01*
X471388Y431299D01*
X470918Y431719D01*
X470370Y431929D01*
X469743Y431719D01*
X469273Y431299D01*
X468960Y430669D01*
X468803Y429829D01*
X468960Y429094D01*
X469352Y428359D01*
X469822Y427939D01*
X470370Y427834D01*
X470997Y428044D01*
X471467Y428569D01*
X471937Y429514D01*
G01X421039Y474015D02*
Y480315D01*
X418141Y475800D01*
X422057D01*
G01X426242Y474015D02*
X426399Y475380D01*
X426634Y476535D01*
X426947Y477585D01*
X427339Y478740D01*
X427966Y480315D01*
X424832D01*
G01X432542Y474015D02*
X432699Y475380D01*
X432934Y476535D01*
X433247Y477585D01*
X433639Y478740D01*
X434266Y480315D01*
X431132D01*
G01X438999Y474015D02*
Y480315D01*
X438059Y479055D01*
G01Y474015D02*
X439939D01*
G01X445299Y473805D02*
X445142Y473910D01*
Y474120D01*
X445299Y474225D01*
X445456Y474120D01*
Y473910D01*
X445299Y473805D01*
G01X450111Y476640D02*
X450659Y477375D01*
X451129Y477795D01*
X451756Y478005D01*
X452304Y477795D01*
X452696Y477375D01*
X453009Y476745D01*
X453087Y476010D01*
X453009Y475380D01*
X452696Y474750D01*
X452226Y474225D01*
X451677Y474015D01*
X451051Y474225D01*
X450502Y474855D01*
X450189Y475800D01*
X450111Y476850D01*
X450267Y478215D01*
X450502Y478950D01*
X450894Y479685D01*
X451442Y480210D01*
X451991Y480315D01*
X452539Y480105D01*
X452931Y479580D01*
G01X456176Y474960D02*
X456646Y474435D01*
X457194Y474120D01*
X457899Y474015D01*
X458604Y474225D01*
X459152Y474645D01*
X459544Y475380D01*
X459622Y476220D01*
X459466Y477060D01*
X459074Y477585D01*
X458526Y478005D01*
X457977Y478110D01*
X457429Y478005D01*
X456724Y477585D01*
X456959Y480315D01*
X459074D01*
G01X427302Y550000D02*
X427772Y549475D01*
X428320Y549160D01*
X429025Y549055D01*
X429730Y549265D01*
X430278Y549685D01*
X430670Y550420D01*
X430748Y551260D01*
X430592Y552100D01*
X430200Y552625D01*
X429652Y553045D01*
X429103Y553150D01*
X428555Y553045D01*
X427850Y552625D01*
X428085Y555355D01*
X430200D01*
G01X433602Y550000D02*
X434072Y549475D01*
X434620Y549160D01*
X435325Y549055D01*
X436030Y549265D01*
X436578Y549685D01*
X436970Y550420D01*
X437048Y551260D01*
X436892Y552100D01*
X436500Y552625D01*
X435952Y553045D01*
X435403Y553150D01*
X434855Y553045D01*
X434150Y552625D01*
X434385Y555355D01*
X436500D01*
G01X440137Y554305D02*
X440607Y554935D01*
X441155Y555250D01*
X441782Y555355D01*
X442565Y555145D01*
X443113Y554620D01*
X443270Y553990D01*
X443192Y553360D01*
X442878Y552835D01*
X441312Y551785D01*
X440607Y551050D01*
X440137Y550000D01*
X439980Y549055D01*
X443270D01*
G01X446437Y554305D02*
X446907Y554935D01*
X447455Y555250D01*
X448082Y555355D01*
X448865Y555145D01*
X449413Y554620D01*
X449570Y553990D01*
X449492Y553360D01*
X449178Y552835D01*
X447612Y551785D01*
X446907Y551050D01*
X446437Y550000D01*
X446280Y549055D01*
X449570D01*
G01X454225Y548845D02*
X454068Y548950D01*
Y549160D01*
X454225Y549265D01*
X454382Y549160D01*
Y548950D01*
X454225Y548845D01*
G01X460525Y555355D02*
X459898Y555145D01*
X459428Y554620D01*
X459115Y553990D01*
X458880Y553150D01*
X458802Y552205D01*
X458880Y551260D01*
X459115Y550420D01*
X459428Y549790D01*
X459898Y549265D01*
X460525Y549055D01*
X461152Y549265D01*
X461622Y549790D01*
X461935Y550420D01*
X462170Y551260D01*
X462248Y552205D01*
X462170Y553150D01*
X461935Y553990D01*
X461622Y554620D01*
X461152Y555145D01*
X460525Y555355D01*
G01X465102Y550000D02*
X465572Y549475D01*
X466120Y549160D01*
X466825Y549055D01*
X467530Y549265D01*
X468078Y549685D01*
X468470Y550420D01*
X468548Y551260D01*
X468392Y552100D01*
X468000Y552625D01*
X467452Y553045D01*
X466903Y553150D01*
X466355Y553045D01*
X465650Y552625D01*
X465885Y555355D01*
X468000D01*
G01X417533Y564073D02*
X418003Y563548D01*
X418551Y563233D01*
X419256Y563128D01*
X419961Y563338D01*
X420509Y563758D01*
X420901Y564493D01*
X420979Y565333D01*
X420823Y566173D01*
X420431Y566698D01*
X419883Y567118D01*
X419334Y567223D01*
X418786Y567118D01*
X418081Y566698D01*
X418316Y569428D01*
X420431D01*
G01X423833Y564073D02*
X424303Y563548D01*
X424851Y563233D01*
X425556Y563128D01*
X426261Y563338D01*
X426809Y563758D01*
X427201Y564493D01*
X427279Y565333D01*
X427123Y566173D01*
X426731Y566698D01*
X426183Y567118D01*
X425634Y567223D01*
X425086Y567118D01*
X424381Y566698D01*
X424616Y569428D01*
X426731D01*
G01X431699Y563128D02*
X431856Y564493D01*
X432091Y565648D01*
X432404Y566698D01*
X432796Y567853D01*
X433423Y569428D01*
X430289D01*
G01X436433Y564073D02*
X436903Y563548D01*
X437451Y563233D01*
X438156Y563128D01*
X438861Y563338D01*
X439409Y563758D01*
X439801Y564493D01*
X439879Y565333D01*
X439723Y566173D01*
X439331Y566698D01*
X438783Y567118D01*
X438234Y567223D01*
X437686Y567118D01*
X436981Y566698D01*
X437216Y569428D01*
X439331D01*
G01X444456Y562918D02*
X444299Y563023D01*
Y563233D01*
X444456Y563338D01*
X444613Y563233D01*
Y563023D01*
X444456Y562918D01*
G01X449268Y568378D02*
X449738Y569008D01*
X450286Y569323D01*
X450913Y569428D01*
X451696Y569218D01*
X452244Y568693D01*
X452401Y568063D01*
X452323Y567433D01*
X452009Y566908D01*
X450443Y565858D01*
X449738Y565123D01*
X449268Y564073D01*
X449111Y563128D01*
X452401D01*
G01X457056Y569428D02*
X456429Y569218D01*
X455959Y568693D01*
X455646Y568063D01*
X455411Y567223D01*
X455333Y566278D01*
X455411Y565333D01*
X455646Y564493D01*
X455959Y563863D01*
X456429Y563338D01*
X457056Y563128D01*
X457683Y563338D01*
X458153Y563863D01*
X458466Y564493D01*
X458701Y565333D01*
X458779Y566278D01*
X458701Y567223D01*
X458466Y568063D01*
X458153Y568693D01*
X457683Y569218D01*
X457056Y569428D01*
G01X430368Y724055D02*
X430525Y725420D01*
X430760Y726575D01*
X431073Y727625D01*
X431465Y728780D01*
X432092Y730355D01*
X428958D01*
G01X435337Y729305D02*
X435807Y729935D01*
X436355Y730250D01*
X436982Y730355D01*
X437765Y730145D01*
X438313Y729620D01*
X438470Y728990D01*
X438392Y728360D01*
X438078Y727835D01*
X436512Y726785D01*
X435807Y726050D01*
X435337Y725000D01*
X435180Y724055D01*
X438470D01*
G01X442968D02*
X443125Y725420D01*
X443360Y726575D01*
X443673Y727625D01*
X444065Y728780D01*
X444692Y730355D01*
X441558D01*
G01X447937Y729305D02*
X448407Y729935D01*
X448955Y730250D01*
X449582Y730355D01*
X450365Y730145D01*
X450913Y729620D01*
X451070Y728990D01*
X450992Y728360D01*
X450678Y727835D01*
X449112Y726785D01*
X448407Y726050D01*
X447937Y725000D01*
X447780Y724055D01*
X451070D01*
G01X455725Y723845D02*
X455568Y723950D01*
Y724160D01*
X455725Y724265D01*
X455882Y724160D01*
Y723950D01*
X455725Y723845D01*
G01X462025Y730355D02*
X461398Y730145D01*
X460928Y729620D01*
X460615Y728990D01*
X460380Y728150D01*
X460302Y727205D01*
X460380Y726260D01*
X460615Y725420D01*
X460928Y724790D01*
X461398Y724265D01*
X462025Y724055D01*
X462652Y724265D01*
X463122Y724790D01*
X463435Y725420D01*
X463670Y726260D01*
X463748Y727205D01*
X463670Y728150D01*
X463435Y728990D01*
X463122Y729620D01*
X462652Y730145D01*
X462025Y730355D01*
G01X466602Y725000D02*
X467072Y724475D01*
X467620Y724160D01*
X468325Y724055D01*
X469030Y724265D01*
X469578Y724685D01*
X469970Y725420D01*
X470048Y726260D01*
X469892Y727100D01*
X469500Y727625D01*
X468952Y728045D01*
X468403Y728150D01*
X467855Y728045D01*
X467150Y727625D01*
X467385Y730355D01*
X469500D01*
G01X424978Y739964D02*
X425135Y741329D01*
X425370Y742484D01*
X425683Y743534D01*
X426075Y744689D01*
X426702Y746264D01*
X423568D01*
G01X429712Y741224D02*
X430182Y740489D01*
X430808Y740069D01*
X431513Y739964D01*
X432140Y740069D01*
X432767Y740594D01*
X433158Y741224D01*
X433237Y741854D01*
X433080Y742589D01*
X432532Y743114D01*
X431983Y743324D01*
X431278D01*
G01X431983D02*
X432453Y743639D01*
X432845Y744164D01*
X433002Y744794D01*
X432845Y745424D01*
X432453Y745949D01*
X431748Y746264D01*
X431043Y746159D01*
X430338Y745739D01*
G01X436247Y745214D02*
X436717Y745844D01*
X437265Y746159D01*
X437892Y746264D01*
X438675Y746054D01*
X439223Y745529D01*
X439380Y744899D01*
X439302Y744269D01*
X438988Y743744D01*
X437422Y742694D01*
X436717Y741959D01*
X436247Y740909D01*
X436090Y739964D01*
X439380D01*
G01X442312Y740909D02*
X442782Y740384D01*
X443330Y740069D01*
X444035Y739964D01*
X444740Y740174D01*
X445288Y740594D01*
X445680Y741329D01*
X445758Y742169D01*
X445602Y743009D01*
X445210Y743534D01*
X444662Y743954D01*
X444113Y744059D01*
X443565Y743954D01*
X442860Y743534D01*
X443095Y746264D01*
X445210D01*
G01X450335Y739754D02*
X450178Y739859D01*
Y740069D01*
X450335Y740174D01*
X450492Y740069D01*
Y739859D01*
X450335Y739754D01*
G01X455147Y745214D02*
X455617Y745844D01*
X456165Y746159D01*
X456792Y746264D01*
X457575Y746054D01*
X458123Y745529D01*
X458280Y744899D01*
X458202Y744269D01*
X457888Y743744D01*
X456322Y742694D01*
X455617Y741959D01*
X455147Y740909D01*
X454990Y739964D01*
X458280D01*
G01X462935Y746264D02*
X462308Y746054D01*
X461838Y745529D01*
X461525Y744899D01*
X461290Y744059D01*
X461212Y743114D01*
X461290Y742169D01*
X461525Y741329D01*
X461838Y740699D01*
X462308Y740174D01*
X462935Y739964D01*
X463562Y740174D01*
X464032Y740699D01*
X464345Y741329D01*
X464580Y742169D01*
X464658Y743114D01*
X464580Y744059D01*
X464345Y744899D01*
X464032Y745529D01*
X463562Y746054D01*
X462935Y746264D01*
G01X432899Y824015D02*
X433447Y824120D01*
X434074Y824435D01*
X434466Y824960D01*
X434622Y825695D01*
X434466Y826430D01*
X433996Y827060D01*
X433291Y827375D01*
X432507D01*
X432037Y827585D01*
X431646Y828110D01*
X431489Y828845D01*
X431724Y829580D01*
X432272Y830105D01*
X432899Y830315D01*
X433526Y830105D01*
X434074Y829580D01*
X434309Y828845D01*
X434152Y828110D01*
X433761Y827585D01*
X433291Y827375D01*
X432507D01*
X431802Y827060D01*
X431332Y826430D01*
X431176Y825695D01*
X431332Y824960D01*
X431724Y824435D01*
X432351Y824120D01*
X432899Y824015D01*
G01X437711Y829265D02*
X438181Y829895D01*
X438729Y830210D01*
X439356Y830315D01*
X440139Y830105D01*
X440687Y829580D01*
X440844Y828950D01*
X440766Y828320D01*
X440452Y827795D01*
X438886Y826745D01*
X438181Y826010D01*
X437711Y824960D01*
X437554Y824015D01*
X440844D01*
G01X445342D02*
X445499Y825380D01*
X445734Y826535D01*
X446047Y827585D01*
X446439Y828740D01*
X447066Y830315D01*
X443932D01*
G01X451799Y824015D02*
Y830315D01*
X450859Y829055D01*
G01Y824015D02*
X452739D01*
G01X458099Y823805D02*
X457942Y823910D01*
Y824120D01*
X458099Y824225D01*
X458256Y824120D01*
Y823910D01*
X458099Y823805D01*
G01X462911Y826640D02*
X463459Y827375D01*
X463929Y827795D01*
X464556Y828005D01*
X465104Y827795D01*
X465496Y827375D01*
X465809Y826745D01*
X465887Y826010D01*
X465809Y825380D01*
X465496Y824750D01*
X465026Y824225D01*
X464477Y824015D01*
X463851Y824225D01*
X463302Y824855D01*
X462989Y825800D01*
X462911Y826850D01*
X463067Y828215D01*
X463302Y828950D01*
X463694Y829685D01*
X464242Y830210D01*
X464791Y830315D01*
X465339Y830105D01*
X465731Y829580D01*
G01X468976Y824960D02*
X469446Y824435D01*
X469994Y824120D01*
X470699Y824015D01*
X471404Y824225D01*
X471952Y824645D01*
X472344Y825380D01*
X472422Y826220D01*
X472266Y827060D01*
X471874Y827585D01*
X471326Y828005D01*
X470777Y828110D01*
X470229Y828005D01*
X469524Y827585D01*
X469759Y830315D01*
X471874D01*
G01X425033Y1074055D02*
Y1080355D01*
X424093Y1079095D01*
G01Y1074055D02*
X425973D01*
G01X431333Y1080355D02*
X430706Y1080145D01*
X430236Y1079620D01*
X429923Y1078990D01*
X429688Y1078150D01*
X429610Y1077205D01*
X429688Y1076260D01*
X429923Y1075420D01*
X430236Y1074790D01*
X430706Y1074265D01*
X431333Y1074055D01*
X431960Y1074265D01*
X432430Y1074790D01*
X432743Y1075420D01*
X432978Y1076260D01*
X433056Y1077205D01*
X432978Y1078150D01*
X432743Y1078990D01*
X432430Y1079620D01*
X431960Y1080145D01*
X431333Y1080355D01*
G01X437476Y1074055D02*
X437633Y1075420D01*
X437868Y1076575D01*
X438181Y1077625D01*
X438573Y1078780D01*
X439200Y1080355D01*
X436066D01*
G01X443776Y1074055D02*
X443933Y1075420D01*
X444168Y1076575D01*
X444481Y1077625D01*
X444873Y1078780D01*
X445500Y1080355D01*
X442366D01*
G01X448745Y1079305D02*
X449215Y1079935D01*
X449763Y1080250D01*
X450390Y1080355D01*
X451173Y1080145D01*
X451721Y1079620D01*
X451878Y1078990D01*
X451800Y1078360D01*
X451486Y1077835D01*
X449920Y1076785D01*
X449215Y1076050D01*
X448745Y1075000D01*
X448588Y1074055D01*
X451878D01*
G01X456533Y1073845D02*
X456376Y1073950D01*
Y1074160D01*
X456533Y1074265D01*
X456690Y1074160D01*
Y1073950D01*
X456533Y1073845D01*
G01X462833Y1080355D02*
X462206Y1080145D01*
X461736Y1079620D01*
X461423Y1078990D01*
X461188Y1078150D01*
X461110Y1077205D01*
X461188Y1076260D01*
X461423Y1075420D01*
X461736Y1074790D01*
X462206Y1074265D01*
X462833Y1074055D01*
X463460Y1074265D01*
X463930Y1074790D01*
X464243Y1075420D01*
X464478Y1076260D01*
X464556Y1077205D01*
X464478Y1078150D01*
X464243Y1078990D01*
X463930Y1079620D01*
X463460Y1080145D01*
X462833Y1080355D01*
G01X467410Y1075000D02*
X467880Y1074475D01*
X468428Y1074160D01*
X469133Y1074055D01*
X469838Y1074265D01*
X470386Y1074685D01*
X470778Y1075420D01*
X470856Y1076260D01*
X470700Y1077100D01*
X470308Y1077625D01*
X469760Y1078045D01*
X469211Y1078150D01*
X468663Y1078045D01*
X467958Y1077625D01*
X468193Y1080355D01*
X470308D01*
G01X423012Y1089105D02*
Y1095405D01*
X422072Y1094145D01*
G01Y1089105D02*
X423952D01*
G01X429312Y1095405D02*
X428685Y1095195D01*
X428215Y1094670D01*
X427902Y1094040D01*
X427667Y1093200D01*
X427589Y1092255D01*
X427667Y1091310D01*
X427902Y1090470D01*
X428215Y1089840D01*
X428685Y1089315D01*
X429312Y1089105D01*
X429939Y1089315D01*
X430409Y1089840D01*
X430722Y1090470D01*
X430957Y1091310D01*
X431035Y1092255D01*
X430957Y1093200D01*
X430722Y1094040D01*
X430409Y1094670D01*
X429939Y1095195D01*
X429312Y1095405D01*
G01X435612Y1089105D02*
X436160Y1089210D01*
X436787Y1089525D01*
X437179Y1090050D01*
X437335Y1090785D01*
X437179Y1091520D01*
X436709Y1092150D01*
X436004Y1092465D01*
X435220D01*
X434750Y1092675D01*
X434359Y1093200D01*
X434202Y1093935D01*
X434437Y1094670D01*
X434985Y1095195D01*
X435612Y1095405D01*
X436239Y1095195D01*
X436787Y1094670D01*
X437022Y1093935D01*
X436865Y1093200D01*
X436474Y1092675D01*
X436004Y1092465D01*
X435220D01*
X434515Y1092150D01*
X434045Y1091520D01*
X433889Y1090785D01*
X434045Y1090050D01*
X434437Y1089525D01*
X435064Y1089210D01*
X435612Y1089105D01*
G01X440424Y1094355D02*
X440894Y1094985D01*
X441442Y1095300D01*
X442069Y1095405D01*
X442852Y1095195D01*
X443400Y1094670D01*
X443557Y1094040D01*
X443479Y1093410D01*
X443165Y1092885D01*
X441599Y1091835D01*
X440894Y1091100D01*
X440424Y1090050D01*
X440267Y1089105D01*
X443557D01*
G01X446489Y1090050D02*
X446959Y1089525D01*
X447507Y1089210D01*
X448212Y1089105D01*
X448917Y1089315D01*
X449465Y1089735D01*
X449857Y1090470D01*
X449935Y1091310D01*
X449779Y1092150D01*
X449387Y1092675D01*
X448839Y1093095D01*
X448290Y1093200D01*
X447742Y1093095D01*
X447037Y1092675D01*
X447272Y1095405D01*
X449387D01*
G01X454512Y1088895D02*
X454355Y1089000D01*
Y1089210D01*
X454512Y1089315D01*
X454669Y1089210D01*
Y1089000D01*
X454512Y1088895D01*
G01X459324Y1094355D02*
X459794Y1094985D01*
X460342Y1095300D01*
X460969Y1095405D01*
X461752Y1095195D01*
X462300Y1094670D01*
X462457Y1094040D01*
X462379Y1093410D01*
X462065Y1092885D01*
X460499Y1091835D01*
X459794Y1091100D01*
X459324Y1090050D01*
X459167Y1089105D01*
X462457D01*
G01X467112Y1095405D02*
X466485Y1095195D01*
X466015Y1094670D01*
X465702Y1094040D01*
X465467Y1093200D01*
X465389Y1092255D01*
X465467Y1091310D01*
X465702Y1090470D01*
X466015Y1089840D01*
X466485Y1089315D01*
X467112Y1089105D01*
X467739Y1089315D01*
X468209Y1089840D01*
X468522Y1090470D01*
X468757Y1091310D01*
X468835Y1092255D01*
X468757Y1093200D01*
X468522Y1094040D01*
X468209Y1094670D01*
X467739Y1095195D01*
X467112Y1095405D01*
G01X425353Y1599055D02*
Y1605355D01*
X424413Y1604095D01*
G01Y1599055D02*
X426293D01*
G01X430165Y1601680D02*
X430713Y1602415D01*
X431183Y1602835D01*
X431810Y1603045D01*
X432358Y1602835D01*
X432750Y1602415D01*
X433063Y1601785D01*
X433141Y1601050D01*
X433063Y1600420D01*
X432750Y1599790D01*
X432280Y1599265D01*
X431731Y1599055D01*
X431105Y1599265D01*
X430556Y1599895D01*
X430243Y1600840D01*
X430165Y1601890D01*
X430321Y1603255D01*
X430556Y1603990D01*
X430948Y1604725D01*
X431496Y1605250D01*
X432045Y1605355D01*
X432593Y1605145D01*
X432985Y1604620D01*
G01X437953Y1605355D02*
X437326Y1605145D01*
X436856Y1604620D01*
X436543Y1603990D01*
X436308Y1603150D01*
X436230Y1602205D01*
X436308Y1601260D01*
X436543Y1600420D01*
X436856Y1599790D01*
X437326Y1599265D01*
X437953Y1599055D01*
X438580Y1599265D01*
X439050Y1599790D01*
X439363Y1600420D01*
X439598Y1601260D01*
X439676Y1602205D01*
X439598Y1603150D01*
X439363Y1603990D01*
X439050Y1604620D01*
X438580Y1605145D01*
X437953Y1605355D01*
G01X442765Y1604305D02*
X443235Y1604935D01*
X443783Y1605250D01*
X444410Y1605355D01*
X445193Y1605145D01*
X445741Y1604620D01*
X445898Y1603990D01*
X445820Y1603360D01*
X445506Y1602835D01*
X443940Y1601785D01*
X443235Y1601050D01*
X442765Y1600000D01*
X442608Y1599055D01*
X445898D01*
G01X449065Y1604305D02*
X449535Y1604935D01*
X450083Y1605250D01*
X450710Y1605355D01*
X451493Y1605145D01*
X452041Y1604620D01*
X452198Y1603990D01*
X452120Y1603360D01*
X451806Y1602835D01*
X450240Y1601785D01*
X449535Y1601050D01*
X449065Y1600000D01*
X448908Y1599055D01*
X452198D01*
G01X456853Y1598845D02*
X456696Y1598950D01*
Y1599160D01*
X456853Y1599265D01*
X457010Y1599160D01*
Y1598950D01*
X456853Y1598845D01*
G01X463153Y1605355D02*
X462526Y1605145D01*
X462056Y1604620D01*
X461743Y1603990D01*
X461508Y1603150D01*
X461430Y1602205D01*
X461508Y1601260D01*
X461743Y1600420D01*
X462056Y1599790D01*
X462526Y1599265D01*
X463153Y1599055D01*
X463780Y1599265D01*
X464250Y1599790D01*
X464563Y1600420D01*
X464798Y1601260D01*
X464876Y1602205D01*
X464798Y1603150D01*
X464563Y1603990D01*
X464250Y1604620D01*
X463780Y1605145D01*
X463153Y1605355D01*
G01X467730Y1600000D02*
X468200Y1599475D01*
X468748Y1599160D01*
X469453Y1599055D01*
X470158Y1599265D01*
X470706Y1599685D01*
X471098Y1600420D01*
X471176Y1601260D01*
X471020Y1602100D01*
X470628Y1602625D01*
X470080Y1603045D01*
X469531Y1603150D01*
X468983Y1603045D01*
X468278Y1602625D01*
X468513Y1605355D01*
X470628D01*
G01X425522Y1616594D02*
Y1622894D01*
X424582Y1621634D01*
G01Y1616594D02*
X426462D01*
G01X430334Y1619219D02*
X430882Y1619954D01*
X431352Y1620374D01*
X431979Y1620584D01*
X432527Y1620374D01*
X432919Y1619954D01*
X433232Y1619324D01*
X433310Y1618589D01*
X433232Y1617959D01*
X432919Y1617329D01*
X432449Y1616804D01*
X431900Y1616594D01*
X431274Y1616804D01*
X430725Y1617434D01*
X430412Y1618379D01*
X430334Y1619429D01*
X430490Y1620794D01*
X430725Y1621529D01*
X431117Y1622264D01*
X431665Y1622789D01*
X432214Y1622894D01*
X432762Y1622684D01*
X433154Y1622159D01*
G01X438122Y1622894D02*
X437495Y1622684D01*
X437025Y1622159D01*
X436712Y1621529D01*
X436477Y1620689D01*
X436399Y1619744D01*
X436477Y1618799D01*
X436712Y1617959D01*
X437025Y1617329D01*
X437495Y1616804D01*
X438122Y1616594D01*
X438749Y1616804D01*
X439219Y1617329D01*
X439532Y1617959D01*
X439767Y1618799D01*
X439845Y1619744D01*
X439767Y1620689D01*
X439532Y1621529D01*
X439219Y1622159D01*
X438749Y1622684D01*
X438122Y1622894D01*
G01X444265Y1616594D02*
X444422Y1617959D01*
X444657Y1619114D01*
X444970Y1620164D01*
X445362Y1621319D01*
X445989Y1622894D01*
X442855D01*
G01X448999Y1617539D02*
X449469Y1617014D01*
X450017Y1616699D01*
X450722Y1616594D01*
X451427Y1616804D01*
X451975Y1617224D01*
X452367Y1617959D01*
X452445Y1618799D01*
X452289Y1619639D01*
X451897Y1620164D01*
X451349Y1620584D01*
X450800Y1620689D01*
X450252Y1620584D01*
X449547Y1620164D01*
X449782Y1622894D01*
X451897D01*
G01X457022Y1616384D02*
X456865Y1616489D01*
Y1616699D01*
X457022Y1616804D01*
X457179Y1616699D01*
Y1616489D01*
X457022Y1616384D01*
G01X461834Y1621844D02*
X462304Y1622474D01*
X462852Y1622789D01*
X463479Y1622894D01*
X464262Y1622684D01*
X464810Y1622159D01*
X464967Y1621529D01*
X464889Y1620899D01*
X464575Y1620374D01*
X463009Y1619324D01*
X462304Y1618589D01*
X461834Y1617539D01*
X461677Y1616594D01*
X464967D01*
G01X469622Y1622894D02*
X468995Y1622684D01*
X468525Y1622159D01*
X468212Y1621529D01*
X467977Y1620689D01*
X467899Y1619744D01*
X467977Y1618799D01*
X468212Y1617959D01*
X468525Y1617329D01*
X468995Y1616804D01*
X469622Y1616594D01*
X470249Y1616804D01*
X470719Y1617329D01*
X471032Y1617959D01*
X471267Y1618799D01*
X471345Y1619744D01*
X471267Y1620689D01*
X471032Y1621529D01*
X470719Y1622159D01*
X470249Y1622684D01*
X469622Y1622894D01*
G01X435139Y1792770D02*
Y1799070D01*
X434199Y1797810D01*
G01Y1792770D02*
X436079D01*
G01X441282D02*
X441439Y1794135D01*
X441674Y1795290D01*
X441987Y1796340D01*
X442379Y1797495D01*
X443006Y1799070D01*
X439872D01*
G01X447739Y1792770D02*
X448287Y1792875D01*
X448914Y1793190D01*
X449306Y1793715D01*
X449462Y1794450D01*
X449306Y1795185D01*
X448836Y1795815D01*
X448131Y1796130D01*
X447347D01*
X446877Y1796340D01*
X446486Y1796865D01*
X446329Y1797600D01*
X446564Y1798335D01*
X447112Y1798860D01*
X447739Y1799070D01*
X448366Y1798860D01*
X448914Y1798335D01*
X449149Y1797600D01*
X448992Y1796865D01*
X448601Y1796340D01*
X448131Y1796130D01*
X447347D01*
X446642Y1795815D01*
X446172Y1795185D01*
X446016Y1794450D01*
X446172Y1793715D01*
X446564Y1793190D01*
X447191Y1792875D01*
X447739Y1792770D01*
G01X452551Y1798020D02*
X453021Y1798650D01*
X453569Y1798965D01*
X454196Y1799070D01*
X454979Y1798860D01*
X455527Y1798335D01*
X455684Y1797705D01*
X455606Y1797075D01*
X455292Y1796550D01*
X453726Y1795500D01*
X453021Y1794765D01*
X452551Y1793715D01*
X452394Y1792770D01*
X455684D01*
G01X458616Y1793715D02*
X459086Y1793190D01*
X459634Y1792875D01*
X460339Y1792770D01*
X461044Y1792980D01*
X461592Y1793400D01*
X461984Y1794135D01*
X462062Y1794975D01*
X461906Y1795815D01*
X461514Y1796340D01*
X460966Y1796760D01*
X460417Y1796865D01*
X459869Y1796760D01*
X459164Y1796340D01*
X459399Y1799070D01*
X461514D01*
G01X466639Y1792560D02*
X466482Y1792665D01*
Y1792875D01*
X466639Y1792980D01*
X466796Y1792875D01*
Y1792665D01*
X466639Y1792560D01*
G01X471451Y1798020D02*
X471921Y1798650D01*
X472469Y1798965D01*
X473096Y1799070D01*
X473879Y1798860D01*
X474427Y1798335D01*
X474584Y1797705D01*
X474506Y1797075D01*
X474192Y1796550D01*
X472626Y1795500D01*
X471921Y1794765D01*
X471451Y1793715D01*
X471294Y1792770D01*
X474584D01*
G01X479239Y1799070D02*
X478612Y1798860D01*
X478142Y1798335D01*
X477829Y1797705D01*
X477594Y1796865D01*
X477516Y1795920D01*
X477594Y1794975D01*
X477829Y1794135D01*
X478142Y1793505D01*
X478612Y1792980D01*
X479239Y1792770D01*
X479866Y1792980D01*
X480336Y1793505D01*
X480649Y1794135D01*
X480884Y1794975D01*
X480962Y1795920D01*
X480884Y1796865D01*
X480649Y1797705D01*
X480336Y1798335D01*
X479866Y1798860D01*
X479239Y1799070D01*
G01X437497Y1949055D02*
Y1955355D01*
X436557Y1954095D01*
G01Y1949055D02*
X438437D01*
G01X442465Y1949790D02*
X443014Y1949265D01*
X443640Y1949055D01*
X444267Y1949265D01*
X444815Y1949895D01*
X445207Y1950840D01*
X445364Y1951785D01*
Y1952940D01*
X445207Y1953885D01*
X444815Y1954725D01*
X444345Y1955145D01*
X443797Y1955355D01*
X443170Y1955145D01*
X442700Y1954725D01*
X442387Y1954095D01*
X442230Y1953255D01*
X442387Y1952520D01*
X442779Y1951785D01*
X443249Y1951365D01*
X443797Y1951260D01*
X444424Y1951470D01*
X444894Y1951995D01*
X445364Y1952940D01*
G01X448374Y1950000D02*
X448844Y1949475D01*
X449392Y1949160D01*
X450097Y1949055D01*
X450802Y1949265D01*
X451350Y1949685D01*
X451742Y1950420D01*
X451820Y1951260D01*
X451664Y1952100D01*
X451272Y1952625D01*
X450724Y1953045D01*
X450175Y1953150D01*
X449627Y1953045D01*
X448922Y1952625D01*
X449157Y1955355D01*
X451272D01*
G01X454909Y1954305D02*
X455379Y1954935D01*
X455927Y1955250D01*
X456554Y1955355D01*
X457337Y1955145D01*
X457885Y1954620D01*
X458042Y1953990D01*
X457964Y1953360D01*
X457650Y1952835D01*
X456084Y1951785D01*
X455379Y1951050D01*
X454909Y1950000D01*
X454752Y1949055D01*
X458042D01*
G01X461209Y1954305D02*
X461679Y1954935D01*
X462227Y1955250D01*
X462854Y1955355D01*
X463637Y1955145D01*
X464185Y1954620D01*
X464342Y1953990D01*
X464264Y1953360D01*
X463950Y1952835D01*
X462384Y1951785D01*
X461679Y1951050D01*
X461209Y1950000D01*
X461052Y1949055D01*
X464342D01*
G01X468997Y1948845D02*
X468840Y1948950D01*
Y1949160D01*
X468997Y1949265D01*
X469154Y1949160D01*
Y1948950D01*
X468997Y1948845D01*
G01X475297Y1955355D02*
X474670Y1955145D01*
X474200Y1954620D01*
X473887Y1953990D01*
X473652Y1953150D01*
X473574Y1952205D01*
X473652Y1951260D01*
X473887Y1950420D01*
X474200Y1949790D01*
X474670Y1949265D01*
X475297Y1949055D01*
X475924Y1949265D01*
X476394Y1949790D01*
X476707Y1950420D01*
X476942Y1951260D01*
X477020Y1952205D01*
X476942Y1953150D01*
X476707Y1953990D01*
X476394Y1954620D01*
X475924Y1955145D01*
X475297Y1955355D01*
G01X479874Y1950000D02*
X480344Y1949475D01*
X480892Y1949160D01*
X481597Y1949055D01*
X482302Y1949265D01*
X482850Y1949685D01*
X483242Y1950420D01*
X483320Y1951260D01*
X483164Y1952100D01*
X482772Y1952625D01*
X482224Y1953045D01*
X481675Y1953150D01*
X481127Y1953045D01*
X480422Y1952625D01*
X480657Y1955355D01*
X482772D01*
G01X433791Y1966918D02*
Y1973218D01*
X432851Y1971958D01*
G01Y1966918D02*
X434731D01*
G01X438759Y1967653D02*
X439308Y1967128D01*
X439934Y1966918D01*
X440561Y1967128D01*
X441109Y1967758D01*
X441501Y1968703D01*
X441658Y1969648D01*
Y1970803D01*
X441501Y1971748D01*
X441109Y1972588D01*
X440639Y1973008D01*
X440091Y1973218D01*
X439464Y1973008D01*
X438994Y1972588D01*
X438681Y1971958D01*
X438524Y1971118D01*
X438681Y1970383D01*
X439073Y1969648D01*
X439543Y1969228D01*
X440091Y1969123D01*
X440718Y1969333D01*
X441188Y1969858D01*
X441658Y1970803D01*
G01X444668Y1967863D02*
X445138Y1967338D01*
X445686Y1967023D01*
X446391Y1966918D01*
X447096Y1967128D01*
X447644Y1967548D01*
X448036Y1968283D01*
X448114Y1969123D01*
X447958Y1969963D01*
X447566Y1970488D01*
X447018Y1970908D01*
X446469Y1971013D01*
X445921Y1970908D01*
X445216Y1970488D01*
X445451Y1973218D01*
X447566D01*
G01X452534Y1966918D02*
X452691Y1968283D01*
X452926Y1969438D01*
X453239Y1970488D01*
X453631Y1971643D01*
X454258Y1973218D01*
X451124D01*
G01X457268Y1967863D02*
X457738Y1967338D01*
X458286Y1967023D01*
X458991Y1966918D01*
X459696Y1967128D01*
X460244Y1967548D01*
X460636Y1968283D01*
X460714Y1969123D01*
X460558Y1969963D01*
X460166Y1970488D01*
X459618Y1970908D01*
X459069Y1971013D01*
X458521Y1970908D01*
X457816Y1970488D01*
X458051Y1973218D01*
X460166D01*
G01X465291Y1966708D02*
X465134Y1966813D01*
Y1967023D01*
X465291Y1967128D01*
X465448Y1967023D01*
Y1966813D01*
X465291Y1966708D01*
G01X470103Y1972168D02*
X470573Y1972798D01*
X471121Y1973113D01*
X471748Y1973218D01*
X472531Y1973008D01*
X473079Y1972483D01*
X473236Y1971853D01*
X473158Y1971223D01*
X472844Y1970698D01*
X471278Y1969648D01*
X470573Y1968913D01*
X470103Y1967863D01*
X469946Y1966918D01*
X473236D01*
G01X477891Y1973218D02*
X477264Y1973008D01*
X476794Y1972483D01*
X476481Y1971853D01*
X476246Y1971013D01*
X476168Y1970068D01*
X476246Y1969123D01*
X476481Y1968283D01*
X476794Y1967653D01*
X477264Y1967128D01*
X477891Y1966918D01*
X478518Y1967128D01*
X478988Y1967653D01*
X479301Y1968283D01*
X479536Y1969123D01*
X479614Y1970068D01*
X479536Y1971013D01*
X479301Y1971853D01*
X478988Y1972483D01*
X478518Y1973008D01*
X477891Y1973218D01*
G01X443300Y-130000D02*
Y-122000D01*
X445300D01*
X446100Y-122400D01*
X446700Y-122933D01*
X447200Y-123733D01*
X447600Y-124667D01*
X447700Y-126000D01*
X447600Y-127333D01*
X447200Y-128267D01*
X446700Y-129067D01*
X446100Y-129600D01*
X445300Y-130000D01*
X443300D01*
G01X442974Y75630D02*
X443131Y76995D01*
X443366Y78150D01*
X443679Y79200D01*
X444071Y80355D01*
X444698Y81930D01*
X441564D01*
G01X449431Y75630D02*
X449979Y75735D01*
X450606Y76050D01*
X450998Y76575D01*
X451154Y77310D01*
X450998Y78045D01*
X450528Y78675D01*
X449823Y78990D01*
X449039D01*
X448569Y79200D01*
X448178Y79725D01*
X448021Y80460D01*
X448256Y81195D01*
X448804Y81720D01*
X449431Y81930D01*
X450058Y81720D01*
X450606Y81195D01*
X450841Y80460D01*
X450684Y79725D01*
X450293Y79200D01*
X449823Y78990D01*
X449039D01*
X448334Y78675D01*
X447864Y78045D01*
X447708Y77310D01*
X447864Y76575D01*
X448256Y76050D01*
X448883Y75735D01*
X449431Y75630D01*
G01X455574D02*
X455731Y76995D01*
X455966Y78150D01*
X456279Y79200D01*
X456671Y80355D01*
X457298Y81930D01*
X454164D01*
G01X462031Y75420D02*
X461874Y75525D01*
Y75735D01*
X462031Y75840D01*
X462188Y75735D01*
Y75525D01*
X462031Y75420D01*
G01X468331Y75630D02*
X468879Y75735D01*
X469506Y76050D01*
X469898Y76575D01*
X470054Y77310D01*
X469898Y78045D01*
X469428Y78675D01*
X468723Y78990D01*
X467939D01*
X467469Y79200D01*
X467078Y79725D01*
X466921Y80460D01*
X467156Y81195D01*
X467704Y81720D01*
X468331Y81930D01*
X468958Y81720D01*
X469506Y81195D01*
X469741Y80460D01*
X469584Y79725D01*
X469193Y79200D01*
X468723Y78990D01*
X467939D01*
X467234Y78675D01*
X466764Y78045D01*
X466608Y77310D01*
X466764Y76575D01*
X467156Y76050D01*
X467783Y75735D01*
X468331Y75630D01*
G01X474631Y81930D02*
X474004Y81720D01*
X473534Y81195D01*
X473221Y80565D01*
X472986Y79725D01*
X472908Y78780D01*
X472986Y77835D01*
X473221Y76995D01*
X473534Y76365D01*
X474004Y75840D01*
X474631Y75630D01*
X475258Y75840D01*
X475728Y76365D01*
X476041Y76995D01*
X476276Y77835D01*
X476354Y78780D01*
X476276Y79725D01*
X476041Y80565D01*
X475728Y81195D01*
X475258Y81720D01*
X474631Y81930D01*
G01X443882Y255880D02*
X444352Y256510D01*
X444900Y256825D01*
X445527Y256930D01*
X446310Y256720D01*
X446858Y256195D01*
X447015Y255565D01*
X446937Y254935D01*
X446623Y254410D01*
X445057Y253360D01*
X444352Y252625D01*
X443882Y251575D01*
X443725Y250630D01*
X447015D01*
G01X449947Y251575D02*
X450417Y251050D01*
X450965Y250735D01*
X451670Y250630D01*
X452375Y250840D01*
X452923Y251260D01*
X453315Y251995D01*
X453393Y252835D01*
X453237Y253675D01*
X452845Y254200D01*
X452297Y254620D01*
X451748Y254725D01*
X451200Y254620D01*
X450495Y254200D01*
X450730Y256930D01*
X452845D01*
G01X456247Y251890D02*
X456717Y251155D01*
X457343Y250735D01*
X458048Y250630D01*
X458675Y250735D01*
X459302Y251260D01*
X459693Y251890D01*
X459772Y252520D01*
X459615Y253255D01*
X459067Y253780D01*
X458518Y253990D01*
X457813D01*
G01X458518D02*
X458988Y254305D01*
X459380Y254830D01*
X459537Y255460D01*
X459380Y256090D01*
X458988Y256615D01*
X458283Y256930D01*
X457578Y256825D01*
X456873Y256405D01*
G01X464113Y250630D02*
X464270Y251995D01*
X464505Y253150D01*
X464818Y254200D01*
X465210Y255355D01*
X465837Y256930D01*
X462703D01*
G01X470570Y250420D02*
X470413Y250525D01*
Y250735D01*
X470570Y250840D01*
X470727Y250735D01*
Y250525D01*
X470570Y250420D01*
G01X476870Y250630D02*
X477418Y250735D01*
X478045Y251050D01*
X478437Y251575D01*
X478593Y252310D01*
X478437Y253045D01*
X477967Y253675D01*
X477262Y253990D01*
X476478D01*
X476008Y254200D01*
X475617Y254725D01*
X475460Y255460D01*
X475695Y256195D01*
X476243Y256720D01*
X476870Y256930D01*
X477497Y256720D01*
X478045Y256195D01*
X478280Y255460D01*
X478123Y254725D01*
X477732Y254200D01*
X477262Y253990D01*
X476478D01*
X475773Y253675D01*
X475303Y253045D01*
X475147Y252310D01*
X475303Y251575D01*
X475695Y251050D01*
X476322Y250735D01*
X476870Y250630D01*
G01X483170Y256930D02*
X482543Y256720D01*
X482073Y256195D01*
X481760Y255565D01*
X481525Y254725D01*
X481447Y253780D01*
X481525Y252835D01*
X481760Y251995D01*
X482073Y251365D01*
X482543Y250840D01*
X483170Y250630D01*
X483797Y250840D01*
X484267Y251365D01*
X484580Y251995D01*
X484815Y252835D01*
X484893Y253780D01*
X484815Y254725D01*
X484580Y255565D01*
X484267Y256195D01*
X483797Y256720D01*
X483170Y256930D01*
G01X438932Y306378D02*
X439402Y305643D01*
X440028Y305223D01*
X440733Y305118D01*
X441360Y305223D01*
X441987Y305748D01*
X442378Y306378D01*
X442457Y307008D01*
X442300Y307743D01*
X441752Y308268D01*
X441203Y308478D01*
X440498D01*
G01X441203D02*
X441673Y308793D01*
X442065Y309318D01*
X442222Y309948D01*
X442065Y310578D01*
X441673Y311103D01*
X440968Y311418D01*
X440263Y311313D01*
X439558Y310893D01*
G01X446955Y311418D02*
X446328Y311208D01*
X445858Y310683D01*
X445545Y310053D01*
X445310Y309213D01*
X445232Y308268D01*
X445310Y307323D01*
X445545Y306483D01*
X445858Y305853D01*
X446328Y305328D01*
X446955Y305118D01*
X447582Y305328D01*
X448052Y305853D01*
X448365Y306483D01*
X448600Y307323D01*
X448678Y308268D01*
X448600Y309213D01*
X448365Y310053D01*
X448052Y310683D01*
X447582Y311208D01*
X446955Y311418D01*
G01X453255Y305118D02*
X453803Y305223D01*
X454430Y305538D01*
X454822Y306063D01*
X454978Y306798D01*
X454822Y307533D01*
X454352Y308163D01*
X453647Y308478D01*
X452863D01*
X452393Y308688D01*
X452002Y309213D01*
X451845Y309948D01*
X452080Y310683D01*
X452628Y311208D01*
X453255Y311418D01*
X453882Y311208D01*
X454430Y310683D01*
X454665Y309948D01*
X454508Y309213D01*
X454117Y308688D01*
X453647Y308478D01*
X452863D01*
X452158Y308163D01*
X451688Y307533D01*
X451532Y306798D01*
X451688Y306063D01*
X452080Y305538D01*
X452707Y305223D01*
X453255Y305118D01*
G01X458067Y310368D02*
X458537Y310998D01*
X459085Y311313D01*
X459712Y311418D01*
X460495Y311208D01*
X461043Y310683D01*
X461200Y310053D01*
X461122Y309423D01*
X460808Y308898D01*
X459242Y307848D01*
X458537Y307113D01*
X458067Y306063D01*
X457910Y305118D01*
X461200D01*
G01X465855Y304908D02*
X465698Y305013D01*
Y305223D01*
X465855Y305328D01*
X466012Y305223D01*
Y305013D01*
X465855Y304908D01*
G01X470667Y307743D02*
X471215Y308478D01*
X471685Y308898D01*
X472312Y309108D01*
X472860Y308898D01*
X473252Y308478D01*
X473565Y307848D01*
X473643Y307113D01*
X473565Y306483D01*
X473252Y305853D01*
X472782Y305328D01*
X472233Y305118D01*
X471607Y305328D01*
X471058Y305958D01*
X470745Y306903D01*
X470667Y307953D01*
X470823Y309318D01*
X471058Y310053D01*
X471450Y310788D01*
X471998Y311313D01*
X472547Y311418D01*
X473095Y311208D01*
X473487Y310683D01*
G01X478455Y305118D02*
X479003Y305223D01*
X479630Y305538D01*
X480022Y306063D01*
X480178Y306798D01*
X480022Y307533D01*
X479552Y308163D01*
X478847Y308478D01*
X478063D01*
X477593Y308688D01*
X477202Y309213D01*
X477045Y309948D01*
X477280Y310683D01*
X477828Y311208D01*
X478455Y311418D01*
X479082Y311208D01*
X479630Y310683D01*
X479865Y309948D01*
X479708Y309213D01*
X479317Y308688D01*
X478847Y308478D01*
X478063D01*
X477358Y308163D01*
X476888Y307533D01*
X476732Y306798D01*
X476888Y306063D01*
X477280Y305538D01*
X477907Y305223D01*
X478455Y305118D01*
G01X438978Y899790D02*
X439527Y899265D01*
X440153Y899055D01*
X440780Y899265D01*
X441328Y899895D01*
X441720Y900840D01*
X441877Y901785D01*
Y902940D01*
X441720Y903885D01*
X441328Y904725D01*
X440858Y905145D01*
X440310Y905355D01*
X439683Y905145D01*
X439213Y904725D01*
X438900Y904095D01*
X438743Y903255D01*
X438900Y902520D01*
X439292Y901785D01*
X439762Y901365D01*
X440310Y901260D01*
X440937Y901470D01*
X441407Y901995D01*
X441877Y902940D01*
G01X446610Y905355D02*
X445983Y905145D01*
X445513Y904620D01*
X445200Y903990D01*
X444965Y903150D01*
X444887Y902205D01*
X444965Y901260D01*
X445200Y900420D01*
X445513Y899790D01*
X445983Y899265D01*
X446610Y899055D01*
X447237Y899265D01*
X447707Y899790D01*
X448020Y900420D01*
X448255Y901260D01*
X448333Y902205D01*
X448255Y903150D01*
X448020Y903990D01*
X447707Y904620D01*
X447237Y905145D01*
X446610Y905355D01*
G01X451422Y904305D02*
X451892Y904935D01*
X452440Y905250D01*
X453067Y905355D01*
X453850Y905145D01*
X454398Y904620D01*
X454555Y903990D01*
X454477Y903360D01*
X454163Y902835D01*
X452597Y901785D01*
X451892Y901050D01*
X451422Y900000D01*
X451265Y899055D01*
X454555D01*
G01X457722Y904305D02*
X458192Y904935D01*
X458740Y905250D01*
X459367Y905355D01*
X460150Y905145D01*
X460698Y904620D01*
X460855Y903990D01*
X460777Y903360D01*
X460463Y902835D01*
X458897Y901785D01*
X458192Y901050D01*
X457722Y900000D01*
X457565Y899055D01*
X460855D01*
G01X465510Y898845D02*
X465353Y898950D01*
Y899160D01*
X465510Y899265D01*
X465667Y899160D01*
Y898950D01*
X465510Y898845D01*
G01X471810Y905355D02*
X471183Y905145D01*
X470713Y904620D01*
X470400Y903990D01*
X470165Y903150D01*
X470087Y902205D01*
X470165Y901260D01*
X470400Y900420D01*
X470713Y899790D01*
X471183Y899265D01*
X471810Y899055D01*
X472437Y899265D01*
X472907Y899790D01*
X473220Y900420D01*
X473455Y901260D01*
X473533Y902205D01*
X473455Y903150D01*
X473220Y903990D01*
X472907Y904620D01*
X472437Y905145D01*
X471810Y905355D01*
G01X476387Y900000D02*
X476857Y899475D01*
X477405Y899160D01*
X478110Y899055D01*
X478815Y899265D01*
X479363Y899685D01*
X479755Y900420D01*
X479833Y901260D01*
X479677Y902100D01*
X479285Y902625D01*
X478737Y903045D01*
X478188Y903150D01*
X477640Y903045D01*
X476935Y902625D01*
X477170Y905355D01*
X479285D01*
G01X442346Y918725D02*
X442895Y918200D01*
X443521Y917990D01*
X444148Y918200D01*
X444696Y918830D01*
X445088Y919775D01*
X445245Y920720D01*
Y921875D01*
X445088Y922820D01*
X444696Y923660D01*
X444226Y924080D01*
X443678Y924290D01*
X443051Y924080D01*
X442581Y923660D01*
X442268Y923030D01*
X442111Y922190D01*
X442268Y921455D01*
X442660Y920720D01*
X443130Y920300D01*
X443678Y920195D01*
X444305Y920405D01*
X444775Y920930D01*
X445245Y921875D01*
G01X449978Y924290D02*
X449351Y924080D01*
X448881Y923555D01*
X448568Y922925D01*
X448333Y922085D01*
X448255Y921140D01*
X448333Y920195D01*
X448568Y919355D01*
X448881Y918725D01*
X449351Y918200D01*
X449978Y917990D01*
X450605Y918200D01*
X451075Y918725D01*
X451388Y919355D01*
X451623Y920195D01*
X451701Y921140D01*
X451623Y922085D01*
X451388Y922925D01*
X451075Y923555D01*
X450605Y924080D01*
X449978Y924290D01*
G01X456121Y917990D02*
X456278Y919355D01*
X456513Y920510D01*
X456826Y921560D01*
X457218Y922715D01*
X457845Y924290D01*
X454711D01*
G01X460855Y918935D02*
X461325Y918410D01*
X461873Y918095D01*
X462578Y917990D01*
X463283Y918200D01*
X463831Y918620D01*
X464223Y919355D01*
X464301Y920195D01*
X464145Y921035D01*
X463753Y921560D01*
X463205Y921980D01*
X462656Y922085D01*
X462108Y921980D01*
X461403Y921560D01*
X461638Y924290D01*
X463753D01*
G01X468878Y917780D02*
X468721Y917885D01*
Y918095D01*
X468878Y918200D01*
X469035Y918095D01*
Y917885D01*
X468878Y917780D01*
G01X473690Y923240D02*
X474160Y923870D01*
X474708Y924185D01*
X475335Y924290D01*
X476118Y924080D01*
X476666Y923555D01*
X476823Y922925D01*
X476745Y922295D01*
X476431Y921770D01*
X474865Y920720D01*
X474160Y919985D01*
X473690Y918935D01*
X473533Y917990D01*
X476823D01*
G01X481478Y924290D02*
X480851Y924080D01*
X480381Y923555D01*
X480068Y922925D01*
X479833Y922085D01*
X479755Y921140D01*
X479833Y920195D01*
X480068Y919355D01*
X480381Y918725D01*
X480851Y918200D01*
X481478Y917990D01*
X482105Y918200D01*
X482575Y918725D01*
X482888Y919355D01*
X483123Y920195D01*
X483201Y921140D01*
X483123Y922085D01*
X482888Y922925D01*
X482575Y923555D01*
X482105Y924080D01*
X481478Y924290D01*
G01X451307Y1424055D02*
Y1430355D01*
X450367Y1429095D01*
G01Y1424055D02*
X452247D01*
G01X458547D02*
Y1430355D01*
X455649Y1425840D01*
X459565D01*
G01X462419Y1429305D02*
X462889Y1429935D01*
X463437Y1430250D01*
X464064Y1430355D01*
X464847Y1430145D01*
X465395Y1429620D01*
X465552Y1428990D01*
X465474Y1428360D01*
X465160Y1427835D01*
X463594Y1426785D01*
X462889Y1426050D01*
X462419Y1425000D01*
X462262Y1424055D01*
X465552D01*
G01X470050D02*
X470207Y1425420D01*
X470442Y1426575D01*
X470755Y1427625D01*
X471147Y1428780D01*
X471774Y1430355D01*
X468640D01*
G01X475019Y1429305D02*
X475489Y1429935D01*
X476037Y1430250D01*
X476664Y1430355D01*
X477447Y1430145D01*
X477995Y1429620D01*
X478152Y1428990D01*
X478074Y1428360D01*
X477760Y1427835D01*
X476194Y1426785D01*
X475489Y1426050D01*
X475019Y1425000D01*
X474862Y1424055D01*
X478152D01*
G01X482807Y1423845D02*
X482650Y1423950D01*
Y1424160D01*
X482807Y1424265D01*
X482964Y1424160D01*
Y1423950D01*
X482807Y1423845D01*
G01X489107Y1430355D02*
X488480Y1430145D01*
X488010Y1429620D01*
X487697Y1428990D01*
X487462Y1428150D01*
X487384Y1427205D01*
X487462Y1426260D01*
X487697Y1425420D01*
X488010Y1424790D01*
X488480Y1424265D01*
X489107Y1424055D01*
X489734Y1424265D01*
X490204Y1424790D01*
X490517Y1425420D01*
X490752Y1426260D01*
X490830Y1427205D01*
X490752Y1428150D01*
X490517Y1428990D01*
X490204Y1429620D01*
X489734Y1430145D01*
X489107Y1430355D01*
G01X493684Y1425000D02*
X494154Y1424475D01*
X494702Y1424160D01*
X495407Y1424055D01*
X496112Y1424265D01*
X496660Y1424685D01*
X497052Y1425420D01*
X497130Y1426260D01*
X496974Y1427100D01*
X496582Y1427625D01*
X496034Y1428045D01*
X495485Y1428150D01*
X494937Y1428045D01*
X494232Y1427625D01*
X494467Y1430355D01*
X496582D01*
G01X440865Y1439085D02*
Y1445385D01*
X439925Y1444125D01*
G01Y1439085D02*
X441805D01*
G01X448105D02*
Y1445385D01*
X445207Y1440870D01*
X449123D01*
G01X451742Y1440345D02*
X452212Y1439610D01*
X452838Y1439190D01*
X453543Y1439085D01*
X454170Y1439190D01*
X454797Y1439715D01*
X455188Y1440345D01*
X455267Y1440975D01*
X455110Y1441710D01*
X454562Y1442235D01*
X454013Y1442445D01*
X453308D01*
G01X454013D02*
X454483Y1442760D01*
X454875Y1443285D01*
X455032Y1443915D01*
X454875Y1444545D01*
X454483Y1445070D01*
X453778Y1445385D01*
X453073Y1445280D01*
X452368Y1444860D01*
G01X458277Y1444335D02*
X458747Y1444965D01*
X459295Y1445280D01*
X459922Y1445385D01*
X460705Y1445175D01*
X461253Y1444650D01*
X461410Y1444020D01*
X461332Y1443390D01*
X461018Y1442865D01*
X459452Y1441815D01*
X458747Y1441080D01*
X458277Y1440030D01*
X458120Y1439085D01*
X461410D01*
G01X464342Y1440030D02*
X464812Y1439505D01*
X465360Y1439190D01*
X466065Y1439085D01*
X466770Y1439295D01*
X467318Y1439715D01*
X467710Y1440450D01*
X467788Y1441290D01*
X467632Y1442130D01*
X467240Y1442655D01*
X466692Y1443075D01*
X466143Y1443180D01*
X465595Y1443075D01*
X464890Y1442655D01*
X465125Y1445385D01*
X467240D01*
G01X472365Y1438875D02*
X472208Y1438980D01*
Y1439190D01*
X472365Y1439295D01*
X472522Y1439190D01*
Y1438980D01*
X472365Y1438875D01*
G01X477177Y1444335D02*
X477647Y1444965D01*
X478195Y1445280D01*
X478822Y1445385D01*
X479605Y1445175D01*
X480153Y1444650D01*
X480310Y1444020D01*
X480232Y1443390D01*
X479918Y1442865D01*
X478352Y1441815D01*
X477647Y1441080D01*
X477177Y1440030D01*
X477020Y1439085D01*
X480310D01*
G01X484965Y1445385D02*
X484338Y1445175D01*
X483868Y1444650D01*
X483555Y1444020D01*
X483320Y1443180D01*
X483242Y1442235D01*
X483320Y1441290D01*
X483555Y1440450D01*
X483868Y1439820D01*
X484338Y1439295D01*
X484965Y1439085D01*
X485592Y1439295D01*
X486062Y1439820D01*
X486375Y1440450D01*
X486610Y1441290D01*
X486688Y1442235D01*
X486610Y1443180D01*
X486375Y1444020D01*
X486062Y1444650D01*
X485592Y1445175D01*
X484965Y1445385D01*
G01X452655Y1774055D02*
Y1780355D01*
X451715Y1779095D01*
G01Y1774055D02*
X453595D01*
G01X458798D02*
X458955Y1775420D01*
X459190Y1776575D01*
X459503Y1777625D01*
X459895Y1778780D01*
X460522Y1780355D01*
X457388D01*
G01X465098Y1774055D02*
X465255Y1775420D01*
X465490Y1776575D01*
X465803Y1777625D01*
X466195Y1778780D01*
X466822Y1780355D01*
X463688D01*
G01X471398Y1774055D02*
X471555Y1775420D01*
X471790Y1776575D01*
X472103Y1777625D01*
X472495Y1778780D01*
X473122Y1780355D01*
X469988D01*
G01X476367Y1779305D02*
X476837Y1779935D01*
X477385Y1780250D01*
X478012Y1780355D01*
X478795Y1780145D01*
X479343Y1779620D01*
X479500Y1778990D01*
X479422Y1778360D01*
X479108Y1777835D01*
X477542Y1776785D01*
X476837Y1776050D01*
X476367Y1775000D01*
X476210Y1774055D01*
X479500D01*
G01X484155Y1773845D02*
X483998Y1773950D01*
Y1774160D01*
X484155Y1774265D01*
X484312Y1774160D01*
Y1773950D01*
X484155Y1773845D01*
G01X490455Y1780355D02*
X489828Y1780145D01*
X489358Y1779620D01*
X489045Y1778990D01*
X488810Y1778150D01*
X488732Y1777205D01*
X488810Y1776260D01*
X489045Y1775420D01*
X489358Y1774790D01*
X489828Y1774265D01*
X490455Y1774055D01*
X491082Y1774265D01*
X491552Y1774790D01*
X491865Y1775420D01*
X492100Y1776260D01*
X492178Y1777205D01*
X492100Y1778150D01*
X491865Y1778990D01*
X491552Y1779620D01*
X491082Y1780145D01*
X490455Y1780355D01*
G01X495032Y1775000D02*
X495502Y1774475D01*
X496050Y1774160D01*
X496755Y1774055D01*
X497460Y1774265D01*
X498008Y1774685D01*
X498400Y1775420D01*
X498478Y1776260D01*
X498322Y1777100D01*
X497930Y1777625D01*
X497382Y1778045D01*
X496833Y1778150D01*
X496285Y1778045D01*
X495580Y1777625D01*
X495815Y1780355D01*
X497930D01*
G01X459258Y2045603D02*
X459728Y2046233D01*
X460276Y2046548D01*
X460903Y2046653D01*
X461686Y2046443D01*
X462234Y2045918D01*
X462391Y2045288D01*
X462313Y2044658D01*
X461999Y2044133D01*
X460433Y2043083D01*
X459728Y2042348D01*
X459258Y2041298D01*
X459101Y2040353D01*
X462391D01*
G01X467046Y2046653D02*
X466419Y2046443D01*
X465949Y2045918D01*
X465636Y2045288D01*
X465401Y2044448D01*
X465323Y2043503D01*
X465401Y2042558D01*
X465636Y2041718D01*
X465949Y2041088D01*
X466419Y2040563D01*
X467046Y2040353D01*
X467673Y2040563D01*
X468143Y2041088D01*
X468456Y2041718D01*
X468691Y2042558D01*
X468769Y2043503D01*
X468691Y2044448D01*
X468456Y2045288D01*
X468143Y2045918D01*
X467673Y2046443D01*
X467046Y2046653D01*
G01X474286Y2040353D02*
Y2046653D01*
X471388Y2042138D01*
X475304D01*
G01X477923Y2041613D02*
X478393Y2040878D01*
X479019Y2040458D01*
X479724Y2040353D01*
X480351Y2040458D01*
X480978Y2040983D01*
X481369Y2041613D01*
X481448Y2042243D01*
X481291Y2042978D01*
X480743Y2043503D01*
X480194Y2043713D01*
X479489D01*
G01X480194D02*
X480664Y2044028D01*
X481056Y2044553D01*
X481213Y2045183D01*
X481056Y2045813D01*
X480664Y2046338D01*
X479959Y2046653D01*
X479254Y2046548D01*
X478549Y2046128D01*
G01X484223Y2041298D02*
X484693Y2040773D01*
X485241Y2040458D01*
X485946Y2040353D01*
X486651Y2040563D01*
X487199Y2040983D01*
X487591Y2041718D01*
X487669Y2042558D01*
X487513Y2043398D01*
X487121Y2043923D01*
X486573Y2044343D01*
X486024Y2044448D01*
X485476Y2044343D01*
X484771Y2043923D01*
X485006Y2046653D01*
X487121D01*
G01X492246Y2040143D02*
X492089Y2040248D01*
Y2040458D01*
X492246Y2040563D01*
X492403Y2040458D01*
Y2040248D01*
X492246Y2040143D01*
G01X498546Y2046653D02*
X497919Y2046443D01*
X497449Y2045918D01*
X497136Y2045288D01*
X496901Y2044448D01*
X496823Y2043503D01*
X496901Y2042558D01*
X497136Y2041718D01*
X497449Y2041088D01*
X497919Y2040563D01*
X498546Y2040353D01*
X499173Y2040563D01*
X499643Y2041088D01*
X499956Y2041718D01*
X500191Y2042558D01*
X500269Y2043503D01*
X500191Y2044448D01*
X499956Y2045288D01*
X499643Y2045918D01*
X499173Y2046443D01*
X498546Y2046653D01*
G01X503123Y2041613D02*
X503593Y2040878D01*
X504219Y2040458D01*
X504924Y2040353D01*
X505551Y2040458D01*
X506178Y2040983D01*
X506569Y2041613D01*
X506648Y2042243D01*
X506491Y2042978D01*
X505943Y2043503D01*
X505394Y2043713D01*
X504689D01*
G01X505394D02*
X505864Y2044028D01*
X506256Y2044553D01*
X506413Y2045183D01*
X506256Y2045813D01*
X505864Y2046338D01*
X505159Y2046653D01*
X504454Y2046548D01*
X503749Y2046128D01*
G01X473000Y-130000D02*
Y-122000D01*
X471800Y-123600D01*
G01Y-130000D02*
X474200D01*
G01X478800Y-128800D02*
X479400Y-129467D01*
X480100Y-129867D01*
X481000Y-130000D01*
X481900Y-129733D01*
X482600Y-129200D01*
X483100Y-128267D01*
X483200Y-127200D01*
X483000Y-126133D01*
X482500Y-125467D01*
X481800Y-124933D01*
X481100Y-124800D01*
X480400Y-124933D01*
X479500Y-125467D01*
X479800Y-122000D01*
X482500D01*
G01X463434Y1249055D02*
Y1255355D01*
X462494Y1254095D01*
G01Y1249055D02*
X464374D01*
G01X468246Y1254305D02*
X468716Y1254935D01*
X469264Y1255250D01*
X469891Y1255355D01*
X470674Y1255145D01*
X471222Y1254620D01*
X471379Y1253990D01*
X471301Y1253360D01*
X470987Y1252835D01*
X469421Y1251785D01*
X468716Y1251050D01*
X468246Y1250000D01*
X468089Y1249055D01*
X471379D01*
G01X474311Y1250000D02*
X474781Y1249475D01*
X475329Y1249160D01*
X476034Y1249055D01*
X476739Y1249265D01*
X477287Y1249685D01*
X477679Y1250420D01*
X477757Y1251260D01*
X477601Y1252100D01*
X477209Y1252625D01*
X476661Y1253045D01*
X476112Y1253150D01*
X475564Y1253045D01*
X474859Y1252625D01*
X475094Y1255355D01*
X477209D01*
G01X480846Y1254305D02*
X481316Y1254935D01*
X481864Y1255250D01*
X482491Y1255355D01*
X483274Y1255145D01*
X483822Y1254620D01*
X483979Y1253990D01*
X483901Y1253360D01*
X483587Y1252835D01*
X482021Y1251785D01*
X481316Y1251050D01*
X480846Y1250000D01*
X480689Y1249055D01*
X483979D01*
G01X487146Y1254305D02*
X487616Y1254935D01*
X488164Y1255250D01*
X488791Y1255355D01*
X489574Y1255145D01*
X490122Y1254620D01*
X490279Y1253990D01*
X490201Y1253360D01*
X489887Y1252835D01*
X488321Y1251785D01*
X487616Y1251050D01*
X487146Y1250000D01*
X486989Y1249055D01*
X490279D01*
G01X494934Y1248845D02*
X494777Y1248950D01*
Y1249160D01*
X494934Y1249265D01*
X495091Y1249160D01*
Y1248950D01*
X494934Y1248845D01*
G01X501234Y1255355D02*
X500607Y1255145D01*
X500137Y1254620D01*
X499824Y1253990D01*
X499589Y1253150D01*
X499511Y1252205D01*
X499589Y1251260D01*
X499824Y1250420D01*
X500137Y1249790D01*
X500607Y1249265D01*
X501234Y1249055D01*
X501861Y1249265D01*
X502331Y1249790D01*
X502644Y1250420D01*
X502879Y1251260D01*
X502957Y1252205D01*
X502879Y1253150D01*
X502644Y1253990D01*
X502331Y1254620D01*
X501861Y1255145D01*
X501234Y1255355D01*
G01X505811Y1250000D02*
X506281Y1249475D01*
X506829Y1249160D01*
X507534Y1249055D01*
X508239Y1249265D01*
X508787Y1249685D01*
X509179Y1250420D01*
X509257Y1251260D01*
X509101Y1252100D01*
X508709Y1252625D01*
X508161Y1253045D01*
X507612Y1253150D01*
X507064Y1253045D01*
X506359Y1252625D01*
X506594Y1255355D01*
X508709D01*
G01X469497Y1269316D02*
Y1275616D01*
X468557Y1274356D01*
G01Y1269316D02*
X470437D01*
G01X474309Y1274566D02*
X474779Y1275196D01*
X475327Y1275511D01*
X475954Y1275616D01*
X476737Y1275406D01*
X477285Y1274881D01*
X477442Y1274251D01*
X477364Y1273621D01*
X477050Y1273096D01*
X475484Y1272046D01*
X474779Y1271311D01*
X474309Y1270261D01*
X474152Y1269316D01*
X477442D01*
G01X480374Y1270261D02*
X480844Y1269736D01*
X481392Y1269421D01*
X482097Y1269316D01*
X482802Y1269526D01*
X483350Y1269946D01*
X483742Y1270681D01*
X483820Y1271521D01*
X483664Y1272361D01*
X483272Y1272886D01*
X482724Y1273306D01*
X482175Y1273411D01*
X481627Y1273306D01*
X480922Y1272886D01*
X481157Y1275616D01*
X483272D01*
G01X488240Y1269316D02*
X488397Y1270681D01*
X488632Y1271836D01*
X488945Y1272886D01*
X489337Y1274041D01*
X489964Y1275616D01*
X486830D01*
G01X492974Y1270261D02*
X493444Y1269736D01*
X493992Y1269421D01*
X494697Y1269316D01*
X495402Y1269526D01*
X495950Y1269946D01*
X496342Y1270681D01*
X496420Y1271521D01*
X496264Y1272361D01*
X495872Y1272886D01*
X495324Y1273306D01*
X494775Y1273411D01*
X494227Y1273306D01*
X493522Y1272886D01*
X493757Y1275616D01*
X495872D01*
G01X500997Y1269106D02*
X500840Y1269211D01*
Y1269421D01*
X500997Y1269526D01*
X501154Y1269421D01*
Y1269211D01*
X500997Y1269106D01*
G01X505809Y1274566D02*
X506279Y1275196D01*
X506827Y1275511D01*
X507454Y1275616D01*
X508237Y1275406D01*
X508785Y1274881D01*
X508942Y1274251D01*
X508864Y1273621D01*
X508550Y1273096D01*
X506984Y1272046D01*
X506279Y1271311D01*
X505809Y1270261D01*
X505652Y1269316D01*
X508942D01*
G01X513597Y1275616D02*
X512970Y1275406D01*
X512500Y1274881D01*
X512187Y1274251D01*
X511952Y1273411D01*
X511874Y1272466D01*
X511952Y1271521D01*
X512187Y1270681D01*
X512500Y1270051D01*
X512970Y1269526D01*
X513597Y1269316D01*
X514224Y1269526D01*
X514694Y1270051D01*
X515007Y1270681D01*
X515242Y1271521D01*
X515320Y1272466D01*
X515242Y1273411D01*
X515007Y1274251D01*
X514694Y1274881D01*
X514224Y1275406D01*
X513597Y1275616D01*
G01X471721Y2005880D02*
X472191Y2006510D01*
X472739Y2006825D01*
X473366Y2006930D01*
X474149Y2006720D01*
X474697Y2006195D01*
X474854Y2005565D01*
X474776Y2004935D01*
X474462Y2004410D01*
X472896Y2003360D01*
X472191Y2002625D01*
X471721Y2001575D01*
X471564Y2000630D01*
X474854D01*
G01X479509Y2006930D02*
X478882Y2006720D01*
X478412Y2006195D01*
X478099Y2005565D01*
X477864Y2004725D01*
X477786Y2003780D01*
X477864Y2002835D01*
X478099Y2001995D01*
X478412Y2001365D01*
X478882Y2000840D01*
X479509Y2000630D01*
X480136Y2000840D01*
X480606Y2001365D01*
X480919Y2001995D01*
X481154Y2002835D01*
X481232Y2003780D01*
X481154Y2004725D01*
X480919Y2005565D01*
X480606Y2006195D01*
X480136Y2006720D01*
X479509Y2006930D01*
G01X485809D02*
X485182Y2006720D01*
X484712Y2006195D01*
X484399Y2005565D01*
X484164Y2004725D01*
X484086Y2003780D01*
X484164Y2002835D01*
X484399Y2001995D01*
X484712Y2001365D01*
X485182Y2000840D01*
X485809Y2000630D01*
X486436Y2000840D01*
X486906Y2001365D01*
X487219Y2001995D01*
X487454Y2002835D01*
X487532Y2003780D01*
X487454Y2004725D01*
X487219Y2005565D01*
X486906Y2006195D01*
X486436Y2006720D01*
X485809Y2006930D01*
G01X490386Y2001890D02*
X490856Y2001155D01*
X491482Y2000735D01*
X492187Y2000630D01*
X492814Y2000735D01*
X493441Y2001260D01*
X493832Y2001890D01*
X493911Y2002520D01*
X493754Y2003255D01*
X493206Y2003780D01*
X492657Y2003990D01*
X491952D01*
G01X492657D02*
X493127Y2004305D01*
X493519Y2004830D01*
X493676Y2005460D01*
X493519Y2006090D01*
X493127Y2006615D01*
X492422Y2006930D01*
X491717Y2006825D01*
X491012Y2006405D01*
G01X498252Y2000630D02*
X498409Y2001995D01*
X498644Y2003150D01*
X498957Y2004200D01*
X499349Y2005355D01*
X499976Y2006930D01*
X496842D01*
G01X504709Y2000420D02*
X504552Y2000525D01*
Y2000735D01*
X504709Y2000840D01*
X504866Y2000735D01*
Y2000525D01*
X504709Y2000420D01*
G01X511009Y2000630D02*
X511557Y2000735D01*
X512184Y2001050D01*
X512576Y2001575D01*
X512732Y2002310D01*
X512576Y2003045D01*
X512106Y2003675D01*
X511401Y2003990D01*
X510617D01*
X510147Y2004200D01*
X509756Y2004725D01*
X509599Y2005460D01*
X509834Y2006195D01*
X510382Y2006720D01*
X511009Y2006930D01*
X511636Y2006720D01*
X512184Y2006195D01*
X512419Y2005460D01*
X512262Y2004725D01*
X511871Y2004200D01*
X511401Y2003990D01*
X510617D01*
X509912Y2003675D01*
X509442Y2003045D01*
X509286Y2002310D01*
X509442Y2001575D01*
X509834Y2001050D01*
X510461Y2000735D01*
X511009Y2000630D01*
G01X517309Y2006930D02*
X516682Y2006720D01*
X516212Y2006195D01*
X515899Y2005565D01*
X515664Y2004725D01*
X515586Y2003780D01*
X515664Y2002835D01*
X515899Y2001995D01*
X516212Y2001365D01*
X516682Y2000840D01*
X517309Y2000630D01*
X517936Y2000840D01*
X518406Y2001365D01*
X518719Y2001995D01*
X518954Y2002835D01*
X519032Y2003780D01*
X518954Y2004725D01*
X518719Y2005565D01*
X518406Y2006195D01*
X517936Y2006720D01*
X517309Y2006930D01*
G01X499484Y1125629D02*
Y1131929D01*
X498544Y1130669D01*
G01Y1125629D02*
X500424D01*
G01X505784D02*
Y1131929D01*
X504844Y1130669D01*
G01Y1125629D02*
X506724D01*
G01X510596Y1130879D02*
X511066Y1131509D01*
X511614Y1131824D01*
X512241Y1131929D01*
X513024Y1131719D01*
X513572Y1131194D01*
X513729Y1130564D01*
X513651Y1129934D01*
X513337Y1129409D01*
X511771Y1128359D01*
X511066Y1127624D01*
X510596Y1126574D01*
X510439Y1125629D01*
X513729D01*
G01X518384D02*
X518932Y1125734D01*
X519559Y1126049D01*
X519951Y1126574D01*
X520107Y1127309D01*
X519951Y1128044D01*
X519481Y1128674D01*
X518776Y1128989D01*
X517992D01*
X517522Y1129199D01*
X517131Y1129724D01*
X516974Y1130459D01*
X517209Y1131194D01*
X517757Y1131719D01*
X518384Y1131929D01*
X519011Y1131719D01*
X519559Y1131194D01*
X519794Y1130459D01*
X519637Y1129724D01*
X519246Y1129199D01*
X518776Y1128989D01*
X517992D01*
X517287Y1128674D01*
X516817Y1128044D01*
X516661Y1127309D01*
X516817Y1126574D01*
X517209Y1126049D01*
X517836Y1125734D01*
X518384Y1125629D01*
G01X524527D02*
X524684Y1126994D01*
X524919Y1128149D01*
X525232Y1129199D01*
X525624Y1130354D01*
X526251Y1131929D01*
X523117D01*
G01X530984Y1125419D02*
X530827Y1125524D01*
Y1125734D01*
X530984Y1125839D01*
X531141Y1125734D01*
Y1125524D01*
X530984Y1125419D01*
G01X537127Y1125629D02*
X537284Y1126994D01*
X537519Y1128149D01*
X537832Y1129199D01*
X538224Y1130354D01*
X538851Y1131929D01*
X535717D01*
G01X542252Y1126364D02*
X542801Y1125839D01*
X543427Y1125629D01*
X544054Y1125839D01*
X544602Y1126469D01*
X544994Y1127414D01*
X545151Y1128359D01*
Y1129514D01*
X544994Y1130459D01*
X544602Y1131299D01*
X544132Y1131719D01*
X543584Y1131929D01*
X542957Y1131719D01*
X542487Y1131299D01*
X542174Y1130669D01*
X542017Y1129829D01*
X542174Y1129094D01*
X542566Y1128359D01*
X543036Y1127939D01*
X543584Y1127834D01*
X544211Y1128044D01*
X544681Y1128569D01*
X545151Y1129514D01*
G01X498810Y1300630D02*
Y1306930D01*
X497870Y1305670D01*
G01Y1300630D02*
X499750D01*
G01X503387Y1301890D02*
X503857Y1301155D01*
X504483Y1300735D01*
X505188Y1300630D01*
X505815Y1300735D01*
X506442Y1301260D01*
X506833Y1301890D01*
X506912Y1302520D01*
X506755Y1303255D01*
X506207Y1303780D01*
X505658Y1303990D01*
X504953D01*
G01X505658D02*
X506128Y1304305D01*
X506520Y1304830D01*
X506677Y1305460D01*
X506520Y1306090D01*
X506128Y1306615D01*
X505423Y1306930D01*
X504718Y1306825D01*
X504013Y1306405D01*
G01X511410Y1306930D02*
X510783Y1306720D01*
X510313Y1306195D01*
X510000Y1305565D01*
X509765Y1304725D01*
X509687Y1303780D01*
X509765Y1302835D01*
X510000Y1301995D01*
X510313Y1301365D01*
X510783Y1300840D01*
X511410Y1300630D01*
X512037Y1300840D01*
X512507Y1301365D01*
X512820Y1301995D01*
X513055Y1302835D01*
X513133Y1303780D01*
X513055Y1304725D01*
X512820Y1305565D01*
X512507Y1306195D01*
X512037Y1306720D01*
X511410Y1306930D01*
G01X515987Y1301890D02*
X516457Y1301155D01*
X517083Y1300735D01*
X517788Y1300630D01*
X518415Y1300735D01*
X519042Y1301260D01*
X519433Y1301890D01*
X519512Y1302520D01*
X519355Y1303255D01*
X518807Y1303780D01*
X518258Y1303990D01*
X517553D01*
G01X518258D02*
X518728Y1304305D01*
X519120Y1304830D01*
X519277Y1305460D01*
X519120Y1306090D01*
X518728Y1306615D01*
X518023Y1306930D01*
X517318Y1306825D01*
X516613Y1306405D01*
G01X523853Y1300630D02*
X524010Y1301995D01*
X524245Y1303150D01*
X524558Y1304200D01*
X524950Y1305355D01*
X525577Y1306930D01*
X522443D01*
G01X530310Y1300420D02*
X530153Y1300525D01*
Y1300735D01*
X530310Y1300840D01*
X530467Y1300735D01*
Y1300525D01*
X530310Y1300420D01*
G01X536610Y1300630D02*
X537158Y1300735D01*
X537785Y1301050D01*
X538177Y1301575D01*
X538333Y1302310D01*
X538177Y1303045D01*
X537707Y1303675D01*
X537002Y1303990D01*
X536218D01*
X535748Y1304200D01*
X535357Y1304725D01*
X535200Y1305460D01*
X535435Y1306195D01*
X535983Y1306720D01*
X536610Y1306930D01*
X537237Y1306720D01*
X537785Y1306195D01*
X538020Y1305460D01*
X537863Y1304725D01*
X537472Y1304200D01*
X537002Y1303990D01*
X536218D01*
X535513Y1303675D01*
X535043Y1303045D01*
X534887Y1302310D01*
X535043Y1301575D01*
X535435Y1301050D01*
X536062Y1300735D01*
X536610Y1300630D01*
G01X542910Y1306930D02*
X542283Y1306720D01*
X541813Y1306195D01*
X541500Y1305565D01*
X541265Y1304725D01*
X541187Y1303780D01*
X541265Y1302835D01*
X541500Y1301995D01*
X541813Y1301365D01*
X542283Y1300840D01*
X542910Y1300630D01*
X543537Y1300840D01*
X544007Y1301365D01*
X544320Y1301995D01*
X544555Y1302835D01*
X544633Y1303780D01*
X544555Y1304725D01*
X544320Y1305565D01*
X544007Y1306195D01*
X543537Y1306720D01*
X542910Y1306930D01*
G01X493420Y1340354D02*
Y1346654D01*
X492480Y1345394D01*
G01Y1340354D02*
X494360D01*
G01X497997Y1341614D02*
X498467Y1340879D01*
X499093Y1340459D01*
X499798Y1340354D01*
X500425Y1340459D01*
X501052Y1340984D01*
X501443Y1341614D01*
X501522Y1342244D01*
X501365Y1342979D01*
X500817Y1343504D01*
X500268Y1343714D01*
X499563D01*
G01X500268D02*
X500738Y1344029D01*
X501130Y1344554D01*
X501287Y1345184D01*
X501130Y1345814D01*
X500738Y1346339D01*
X500033Y1346654D01*
X499328Y1346549D01*
X498623Y1346129D01*
G01X506960Y1340354D02*
Y1346654D01*
X504062Y1342139D01*
X507978D01*
G01X510597Y1341614D02*
X511067Y1340879D01*
X511693Y1340459D01*
X512398Y1340354D01*
X513025Y1340459D01*
X513652Y1340984D01*
X514043Y1341614D01*
X514122Y1342244D01*
X513965Y1342979D01*
X513417Y1343504D01*
X512868Y1343714D01*
X512163D01*
G01X512868D02*
X513338Y1344029D01*
X513730Y1344554D01*
X513887Y1345184D01*
X513730Y1345814D01*
X513338Y1346339D01*
X512633Y1346654D01*
X511928Y1346549D01*
X511223Y1346129D01*
G01X516897Y1341299D02*
X517367Y1340774D01*
X517915Y1340459D01*
X518620Y1340354D01*
X519325Y1340564D01*
X519873Y1340984D01*
X520265Y1341719D01*
X520343Y1342559D01*
X520187Y1343399D01*
X519795Y1343924D01*
X519247Y1344344D01*
X518698Y1344449D01*
X518150Y1344344D01*
X517445Y1343924D01*
X517680Y1346654D01*
X519795D01*
G01X524920Y1340144D02*
X524763Y1340249D01*
Y1340459D01*
X524920Y1340564D01*
X525077Y1340459D01*
Y1340249D01*
X524920Y1340144D01*
G01X531220Y1346654D02*
X530593Y1346444D01*
X530123Y1345919D01*
X529810Y1345289D01*
X529575Y1344449D01*
X529497Y1343504D01*
X529575Y1342559D01*
X529810Y1341719D01*
X530123Y1341089D01*
X530593Y1340564D01*
X531220Y1340354D01*
X531847Y1340564D01*
X532317Y1341089D01*
X532630Y1341719D01*
X532865Y1342559D01*
X532943Y1343504D01*
X532865Y1344449D01*
X532630Y1345289D01*
X532317Y1345919D01*
X531847Y1346444D01*
X531220Y1346654D01*
G01X538460Y1340354D02*
Y1346654D01*
X535562Y1342139D01*
X539478D01*
G01X501505Y1475630D02*
Y1481930D01*
X500565Y1480670D01*
G01Y1475630D02*
X502445D01*
G01X508745D02*
Y1481930D01*
X505847Y1477415D01*
X509763D01*
G01X513948Y1475630D02*
X514105Y1476995D01*
X514340Y1478150D01*
X514653Y1479200D01*
X515045Y1480355D01*
X515672Y1481930D01*
X512538D01*
G01X520405Y1475630D02*
X520953Y1475735D01*
X521580Y1476050D01*
X521972Y1476575D01*
X522128Y1477310D01*
X521972Y1478045D01*
X521502Y1478675D01*
X520797Y1478990D01*
X520013D01*
X519543Y1479200D01*
X519152Y1479725D01*
X518995Y1480460D01*
X519230Y1481195D01*
X519778Y1481720D01*
X520405Y1481930D01*
X521032Y1481720D01*
X521580Y1481195D01*
X521815Y1480460D01*
X521658Y1479725D01*
X521267Y1479200D01*
X520797Y1478990D01*
X520013D01*
X519308Y1478675D01*
X518838Y1478045D01*
X518682Y1477310D01*
X518838Y1476575D01*
X519230Y1476050D01*
X519857Y1475735D01*
X520405Y1475630D01*
G01X526548D02*
X526705Y1476995D01*
X526940Y1478150D01*
X527253Y1479200D01*
X527645Y1480355D01*
X528272Y1481930D01*
X525138D01*
G01X533005Y1475420D02*
X532848Y1475525D01*
Y1475735D01*
X533005Y1475840D01*
X533162Y1475735D01*
Y1475525D01*
X533005Y1475420D01*
G01X539305Y1475630D02*
X539853Y1475735D01*
X540480Y1476050D01*
X540872Y1476575D01*
X541028Y1477310D01*
X540872Y1478045D01*
X540402Y1478675D01*
X539697Y1478990D01*
X538913D01*
X538443Y1479200D01*
X538052Y1479725D01*
X537895Y1480460D01*
X538130Y1481195D01*
X538678Y1481720D01*
X539305Y1481930D01*
X539932Y1481720D01*
X540480Y1481195D01*
X540715Y1480460D01*
X540558Y1479725D01*
X540167Y1479200D01*
X539697Y1478990D01*
X538913D01*
X538208Y1478675D01*
X537738Y1478045D01*
X537582Y1477310D01*
X537738Y1476575D01*
X538130Y1476050D01*
X538757Y1475735D01*
X539305Y1475630D01*
G01X545605Y1481930D02*
X544978Y1481720D01*
X544508Y1481195D01*
X544195Y1480565D01*
X543960Y1479725D01*
X543882Y1478780D01*
X543960Y1477835D01*
X544195Y1476995D01*
X544508Y1476365D01*
X544978Y1475840D01*
X545605Y1475630D01*
X546232Y1475840D01*
X546702Y1476365D01*
X547015Y1476995D01*
X547250Y1477835D01*
X547328Y1478780D01*
X547250Y1479725D01*
X547015Y1480565D01*
X546702Y1481195D01*
X546232Y1481720D01*
X545605Y1481930D01*
G01X504873Y1650630D02*
Y1656930D01*
X503933Y1655670D01*
G01Y1650630D02*
X505813D01*
G01X509685Y1653255D02*
X510233Y1653990D01*
X510703Y1654410D01*
X511330Y1654620D01*
X511878Y1654410D01*
X512270Y1653990D01*
X512583Y1653360D01*
X512661Y1652625D01*
X512583Y1651995D01*
X512270Y1651365D01*
X511800Y1650840D01*
X511251Y1650630D01*
X510625Y1650840D01*
X510076Y1651470D01*
X509763Y1652415D01*
X509685Y1653465D01*
X509841Y1654830D01*
X510076Y1655565D01*
X510468Y1656300D01*
X511016Y1656825D01*
X511565Y1656930D01*
X512113Y1656720D01*
X512505Y1656195D01*
G01X515750Y1651575D02*
X516220Y1651050D01*
X516768Y1650735D01*
X517473Y1650630D01*
X518178Y1650840D01*
X518726Y1651260D01*
X519118Y1651995D01*
X519196Y1652835D01*
X519040Y1653675D01*
X518648Y1654200D01*
X518100Y1654620D01*
X517551Y1654725D01*
X517003Y1654620D01*
X516298Y1654200D01*
X516533Y1656930D01*
X518648D01*
G01X522050Y1651890D02*
X522520Y1651155D01*
X523146Y1650735D01*
X523851Y1650630D01*
X524478Y1650735D01*
X525105Y1651260D01*
X525496Y1651890D01*
X525575Y1652520D01*
X525418Y1653255D01*
X524870Y1653780D01*
X524321Y1653990D01*
X523616D01*
G01X524321D02*
X524791Y1654305D01*
X525183Y1654830D01*
X525340Y1655460D01*
X525183Y1656090D01*
X524791Y1656615D01*
X524086Y1656930D01*
X523381Y1656825D01*
X522676Y1656405D01*
G01X529916Y1650630D02*
X530073Y1651995D01*
X530308Y1653150D01*
X530621Y1654200D01*
X531013Y1655355D01*
X531640Y1656930D01*
X528506D01*
G01X536373Y1650420D02*
X536216Y1650525D01*
Y1650735D01*
X536373Y1650840D01*
X536530Y1650735D01*
Y1650525D01*
X536373Y1650420D01*
G01X542673Y1650630D02*
X543221Y1650735D01*
X543848Y1651050D01*
X544240Y1651575D01*
X544396Y1652310D01*
X544240Y1653045D01*
X543770Y1653675D01*
X543065Y1653990D01*
X542281D01*
X541811Y1654200D01*
X541420Y1654725D01*
X541263Y1655460D01*
X541498Y1656195D01*
X542046Y1656720D01*
X542673Y1656930D01*
X543300Y1656720D01*
X543848Y1656195D01*
X544083Y1655460D01*
X543926Y1654725D01*
X543535Y1654200D01*
X543065Y1653990D01*
X542281D01*
X541576Y1653675D01*
X541106Y1653045D01*
X540950Y1652310D01*
X541106Y1651575D01*
X541498Y1651050D01*
X542125Y1650735D01*
X542673Y1650630D01*
G01X548973Y1656930D02*
X548346Y1656720D01*
X547876Y1656195D01*
X547563Y1655565D01*
X547328Y1654725D01*
X547250Y1653780D01*
X547328Y1652835D01*
X547563Y1651995D01*
X547876Y1651365D01*
X548346Y1650840D01*
X548973Y1650630D01*
X549600Y1650840D01*
X550070Y1651365D01*
X550383Y1651995D01*
X550618Y1652835D01*
X550696Y1653780D01*
X550618Y1654725D01*
X550383Y1655565D01*
X550070Y1656195D01*
X549600Y1656720D01*
X548973Y1656930D01*
G01X506220Y1690354D02*
Y1696654D01*
X505280Y1695394D01*
G01Y1690354D02*
X507160D01*
G01X511032Y1692979D02*
X511580Y1693714D01*
X512050Y1694134D01*
X512677Y1694344D01*
X513225Y1694134D01*
X513617Y1693714D01*
X513930Y1693084D01*
X514008Y1692349D01*
X513930Y1691719D01*
X513617Y1691089D01*
X513147Y1690564D01*
X512598Y1690354D01*
X511972Y1690564D01*
X511423Y1691194D01*
X511110Y1692139D01*
X511032Y1693189D01*
X511188Y1694554D01*
X511423Y1695289D01*
X511815Y1696024D01*
X512363Y1696549D01*
X512912Y1696654D01*
X513460Y1696444D01*
X513852Y1695919D01*
G01X517488Y1691089D02*
X518037Y1690564D01*
X518663Y1690354D01*
X519290Y1690564D01*
X519838Y1691194D01*
X520230Y1692139D01*
X520387Y1693084D01*
Y1694239D01*
X520230Y1695184D01*
X519838Y1696024D01*
X519368Y1696444D01*
X518820Y1696654D01*
X518193Y1696444D01*
X517723Y1696024D01*
X517410Y1695394D01*
X517253Y1694554D01*
X517410Y1693819D01*
X517802Y1693084D01*
X518272Y1692664D01*
X518820Y1692559D01*
X519447Y1692769D01*
X519917Y1693294D01*
X520387Y1694239D01*
G01X523397Y1691614D02*
X523867Y1690879D01*
X524493Y1690459D01*
X525198Y1690354D01*
X525825Y1690459D01*
X526452Y1690984D01*
X526843Y1691614D01*
X526922Y1692244D01*
X526765Y1692979D01*
X526217Y1693504D01*
X525668Y1693714D01*
X524963D01*
G01X525668D02*
X526138Y1694029D01*
X526530Y1694554D01*
X526687Y1695184D01*
X526530Y1695814D01*
X526138Y1696339D01*
X525433Y1696654D01*
X524728Y1696549D01*
X524023Y1696129D01*
G01X529697Y1691299D02*
X530167Y1690774D01*
X530715Y1690459D01*
X531420Y1690354D01*
X532125Y1690564D01*
X532673Y1690984D01*
X533065Y1691719D01*
X533143Y1692559D01*
X532987Y1693399D01*
X532595Y1693924D01*
X532047Y1694344D01*
X531498Y1694449D01*
X530950Y1694344D01*
X530245Y1693924D01*
X530480Y1696654D01*
X532595D01*
G01X537720Y1690144D02*
X537563Y1690249D01*
Y1690459D01*
X537720Y1690564D01*
X537877Y1690459D01*
Y1690249D01*
X537720Y1690144D01*
G01X544020Y1696654D02*
X543393Y1696444D01*
X542923Y1695919D01*
X542610Y1695289D01*
X542375Y1694449D01*
X542297Y1693504D01*
X542375Y1692559D01*
X542610Y1691719D01*
X542923Y1691089D01*
X543393Y1690564D01*
X544020Y1690354D01*
X544647Y1690564D01*
X545117Y1691089D01*
X545430Y1691719D01*
X545665Y1692559D01*
X545743Y1693504D01*
X545665Y1694449D01*
X545430Y1695289D01*
X545117Y1695919D01*
X544647Y1696444D01*
X544020Y1696654D01*
G01X551260Y1690354D02*
Y1696654D01*
X548362Y1692139D01*
X552278D01*
G01X486346Y1825629D02*
Y1831929D01*
X485406Y1830669D01*
G01Y1825629D02*
X487286D01*
G01X492646D02*
X493194Y1825734D01*
X493821Y1826049D01*
X494213Y1826574D01*
X494369Y1827309D01*
X494213Y1828044D01*
X493743Y1828674D01*
X493038Y1828989D01*
X492254D01*
X491784Y1829199D01*
X491393Y1829724D01*
X491236Y1830459D01*
X491471Y1831194D01*
X492019Y1831719D01*
X492646Y1831929D01*
X493273Y1831719D01*
X493821Y1831194D01*
X494056Y1830459D01*
X493899Y1829724D01*
X493508Y1829199D01*
X493038Y1828989D01*
X492254D01*
X491549Y1828674D01*
X491079Y1828044D01*
X490923Y1827309D01*
X491079Y1826574D01*
X491471Y1826049D01*
X492098Y1825734D01*
X492646Y1825629D01*
G01X497458Y1830879D02*
X497928Y1831509D01*
X498476Y1831824D01*
X499103Y1831929D01*
X499886Y1831719D01*
X500434Y1831194D01*
X500591Y1830564D01*
X500513Y1829934D01*
X500199Y1829409D01*
X498633Y1828359D01*
X497928Y1827624D01*
X497458Y1826574D01*
X497301Y1825629D01*
X500591D01*
G01X505246D02*
X505794Y1825734D01*
X506421Y1826049D01*
X506813Y1826574D01*
X506969Y1827309D01*
X506813Y1828044D01*
X506343Y1828674D01*
X505638Y1828989D01*
X504854D01*
X504384Y1829199D01*
X503993Y1829724D01*
X503836Y1830459D01*
X504071Y1831194D01*
X504619Y1831719D01*
X505246Y1831929D01*
X505873Y1831719D01*
X506421Y1831194D01*
X506656Y1830459D01*
X506499Y1829724D01*
X506108Y1829199D01*
X505638Y1828989D01*
X504854D01*
X504149Y1828674D01*
X503679Y1828044D01*
X503523Y1827309D01*
X503679Y1826574D01*
X504071Y1826049D01*
X504698Y1825734D01*
X505246Y1825629D01*
G01X511389D02*
X511546Y1826994D01*
X511781Y1828149D01*
X512094Y1829199D01*
X512486Y1830354D01*
X513113Y1831929D01*
X509979D01*
G01X517846Y1825419D02*
X517689Y1825524D01*
Y1825734D01*
X517846Y1825839D01*
X518003Y1825734D01*
Y1825524D01*
X517846Y1825419D01*
G01X523989Y1825629D02*
X524146Y1826994D01*
X524381Y1828149D01*
X524694Y1829199D01*
X525086Y1830354D01*
X525713Y1831929D01*
X522579D01*
G01X529114Y1826364D02*
X529663Y1825839D01*
X530289Y1825629D01*
X530916Y1825839D01*
X531464Y1826469D01*
X531856Y1827414D01*
X532013Y1828359D01*
Y1829514D01*
X531856Y1830459D01*
X531464Y1831299D01*
X530994Y1831719D01*
X530446Y1831929D01*
X529819Y1831719D01*
X529349Y1831299D01*
X529036Y1830669D01*
X528879Y1829829D01*
X529036Y1829094D01*
X529428Y1828359D01*
X529898Y1827939D01*
X530446Y1827834D01*
X531073Y1828044D01*
X531543Y1828569D01*
X532013Y1829514D01*
G01X487693Y1879921D02*
Y1886221D01*
X486753Y1884961D01*
G01Y1879921D02*
X488633D01*
G01X493993D02*
X494541Y1880026D01*
X495168Y1880341D01*
X495560Y1880866D01*
X495716Y1881601D01*
X495560Y1882336D01*
X495090Y1882966D01*
X494385Y1883281D01*
X493601D01*
X493131Y1883491D01*
X492740Y1884016D01*
X492583Y1884751D01*
X492818Y1885486D01*
X493366Y1886011D01*
X493993Y1886221D01*
X494620Y1886011D01*
X495168Y1885486D01*
X495403Y1884751D01*
X495246Y1884016D01*
X494855Y1883491D01*
X494385Y1883281D01*
X493601D01*
X492896Y1882966D01*
X492426Y1882336D01*
X492270Y1881601D01*
X492426Y1880866D01*
X492818Y1880341D01*
X493445Y1880026D01*
X493993Y1879921D01*
G01X500293D02*
X500841Y1880026D01*
X501468Y1880341D01*
X501860Y1880866D01*
X502016Y1881601D01*
X501860Y1882336D01*
X501390Y1882966D01*
X500685Y1883281D01*
X499901D01*
X499431Y1883491D01*
X499040Y1884016D01*
X498883Y1884751D01*
X499118Y1885486D01*
X499666Y1886011D01*
X500293Y1886221D01*
X500920Y1886011D01*
X501468Y1885486D01*
X501703Y1884751D01*
X501546Y1884016D01*
X501155Y1883491D01*
X500685Y1883281D01*
X499901D01*
X499196Y1882966D01*
X498726Y1882336D01*
X498570Y1881601D01*
X498726Y1880866D01*
X499118Y1880341D01*
X499745Y1880026D01*
X500293Y1879921D01*
G01X504870Y1881181D02*
X505340Y1880446D01*
X505966Y1880026D01*
X506671Y1879921D01*
X507298Y1880026D01*
X507925Y1880551D01*
X508316Y1881181D01*
X508395Y1881811D01*
X508238Y1882546D01*
X507690Y1883071D01*
X507141Y1883281D01*
X506436D01*
G01X507141D02*
X507611Y1883596D01*
X508003Y1884121D01*
X508160Y1884751D01*
X508003Y1885381D01*
X507611Y1885906D01*
X506906Y1886221D01*
X506201Y1886116D01*
X505496Y1885696D01*
G01X512893Y1886221D02*
X512266Y1886011D01*
X511796Y1885486D01*
X511483Y1884856D01*
X511248Y1884016D01*
X511170Y1883071D01*
X511248Y1882126D01*
X511483Y1881286D01*
X511796Y1880656D01*
X512266Y1880131D01*
X512893Y1879921D01*
X513520Y1880131D01*
X513990Y1880656D01*
X514303Y1881286D01*
X514538Y1882126D01*
X514616Y1883071D01*
X514538Y1884016D01*
X514303Y1884856D01*
X513990Y1885486D01*
X513520Y1886011D01*
X512893Y1886221D01*
G01X519193Y1879711D02*
X519036Y1879816D01*
Y1880026D01*
X519193Y1880131D01*
X519350Y1880026D01*
Y1879816D01*
X519193Y1879711D01*
G01X525336Y1879921D02*
X525493Y1881286D01*
X525728Y1882441D01*
X526041Y1883491D01*
X526433Y1884646D01*
X527060Y1886221D01*
X523926D01*
G01X531793Y1879921D02*
Y1886221D01*
X530853Y1884961D01*
G01Y1879921D02*
X532733D01*
G01X533639Y951365D02*
X534188Y950840D01*
X534814Y950630D01*
X535441Y950840D01*
X535989Y951470D01*
X536381Y952415D01*
X536538Y953360D01*
Y954515D01*
X536381Y955460D01*
X535989Y956300D01*
X535519Y956720D01*
X534971Y956930D01*
X534344Y956720D01*
X533874Y956300D01*
X533561Y955670D01*
X533404Y954830D01*
X533561Y954095D01*
X533953Y953360D01*
X534423Y952940D01*
X534971Y952835D01*
X535598Y953045D01*
X536068Y953570D01*
X536538Y954515D01*
G01X539548Y951575D02*
X540018Y951050D01*
X540566Y950735D01*
X541271Y950630D01*
X541976Y950840D01*
X542524Y951260D01*
X542916Y951995D01*
X542994Y952835D01*
X542838Y953675D01*
X542446Y954200D01*
X541898Y954620D01*
X541349Y954725D01*
X540801Y954620D01*
X540096Y954200D01*
X540331Y956930D01*
X542446D01*
G01X545848Y951890D02*
X546318Y951155D01*
X546944Y950735D01*
X547649Y950630D01*
X548276Y950735D01*
X548903Y951260D01*
X549294Y951890D01*
X549373Y952520D01*
X549216Y953255D01*
X548668Y953780D01*
X548119Y953990D01*
X547414D01*
G01X548119D02*
X548589Y954305D01*
X548981Y954830D01*
X549138Y955460D01*
X548981Y956090D01*
X548589Y956615D01*
X547884Y956930D01*
X547179Y956825D01*
X546474Y956405D01*
G01X553714Y950630D02*
X553871Y951995D01*
X554106Y953150D01*
X554419Y954200D01*
X554811Y955355D01*
X555438Y956930D01*
X552304D01*
G01X560171Y950420D02*
X560014Y950525D01*
Y950735D01*
X560171Y950840D01*
X560328Y950735D01*
Y950525D01*
X560171Y950420D01*
G01X566471Y950630D02*
X567019Y950735D01*
X567646Y951050D01*
X568038Y951575D01*
X568194Y952310D01*
X568038Y953045D01*
X567568Y953675D01*
X566863Y953990D01*
X566079D01*
X565609Y954200D01*
X565218Y954725D01*
X565061Y955460D01*
X565296Y956195D01*
X565844Y956720D01*
X566471Y956930D01*
X567098Y956720D01*
X567646Y956195D01*
X567881Y955460D01*
X567724Y954725D01*
X567333Y954200D01*
X566863Y953990D01*
X566079D01*
X565374Y953675D01*
X564904Y953045D01*
X564748Y952310D01*
X564904Y951575D01*
X565296Y951050D01*
X565923Y950735D01*
X566471Y950630D01*
G01X572771Y956930D02*
X572144Y956720D01*
X571674Y956195D01*
X571361Y955565D01*
X571126Y954725D01*
X571048Y953780D01*
X571126Y952835D01*
X571361Y951995D01*
X571674Y951365D01*
X572144Y950840D01*
X572771Y950630D01*
X573398Y950840D01*
X573868Y951365D01*
X574181Y951995D01*
X574416Y952835D01*
X574494Y953780D01*
X574416Y954725D01*
X574181Y955565D01*
X573868Y956195D01*
X573398Y956720D01*
X572771Y956930D01*
G01X539813Y987971D02*
Y992971D01*
X542219D01*
G01X541333Y990554D02*
X539813D01*
G01X545356Y992971D02*
X546876D01*
G01X546116D02*
Y987971D01*
G01X545356D02*
X546876D01*
G01X551596Y990471D02*
X552863D01*
Y988971D01*
X552483Y988471D01*
X552039Y988138D01*
X551406Y987971D01*
X550773Y988138D01*
X550329Y988471D01*
X549949Y988971D01*
X549696Y989554D01*
X549569Y990221D01*
Y990804D01*
X549696Y991304D01*
X549949Y991888D01*
X550329Y992388D01*
X550709Y992721D01*
X551216Y992971D01*
X551659D01*
X552166Y992804D01*
X552546Y992471D01*
G01X554923Y992971D02*
Y989388D01*
X555176Y988638D01*
X555683Y988138D01*
X556316Y987971D01*
X556949Y988138D01*
X557456Y988638D01*
X557709Y989388D01*
Y992971D01*
G01X560149Y987971D02*
Y992971D01*
X561733D01*
X562239Y992721D01*
X562556Y992388D01*
X562683Y991721D01*
X562556Y991054D01*
X562176Y990638D01*
X561733Y990388D01*
X560149D01*
G01X561733D02*
X562683Y987971D01*
G01X567783D02*
X565249D01*
Y992971D01*
X567783D01*
G01X566769Y990554D02*
X565249D01*
G01X559083Y603254D02*
X559631Y603989D01*
X560101Y604409D01*
X560728Y604619D01*
X561276Y604409D01*
X561668Y603989D01*
X561981Y603359D01*
X562059Y602624D01*
X561981Y601994D01*
X561668Y601364D01*
X561198Y600839D01*
X560649Y600629D01*
X560023Y600839D01*
X559474Y601469D01*
X559161Y602414D01*
X559083Y603464D01*
X559239Y604829D01*
X559474Y605564D01*
X559866Y606299D01*
X560414Y606824D01*
X560963Y606929D01*
X561511Y606719D01*
X561903Y606194D01*
G01X566871Y606929D02*
X566244Y606719D01*
X565774Y606194D01*
X565461Y605564D01*
X565226Y604724D01*
X565148Y603779D01*
X565226Y602834D01*
X565461Y601994D01*
X565774Y601364D01*
X566244Y600839D01*
X566871Y600629D01*
X567498Y600839D01*
X567968Y601364D01*
X568281Y601994D01*
X568516Y602834D01*
X568594Y603779D01*
X568516Y604724D01*
X568281Y605564D01*
X567968Y606194D01*
X567498Y606719D01*
X566871Y606929D01*
G01X571448Y601889D02*
X571918Y601154D01*
X572544Y600734D01*
X573249Y600629D01*
X573876Y600734D01*
X574503Y601259D01*
X574894Y601889D01*
X574973Y602519D01*
X574816Y603254D01*
X574268Y603779D01*
X573719Y603989D01*
X573014D01*
G01X573719D02*
X574189Y604304D01*
X574581Y604829D01*
X574738Y605459D01*
X574581Y606089D01*
X574189Y606614D01*
X573484Y606929D01*
X572779Y606824D01*
X572074Y606404D01*
G01X579314Y600629D02*
X579471Y601994D01*
X579706Y603149D01*
X580019Y604199D01*
X580411Y605354D01*
X581038Y606929D01*
X577904D01*
G01X585771Y600419D02*
X585614Y600524D01*
Y600734D01*
X585771Y600839D01*
X585928Y600734D01*
Y600524D01*
X585771Y600419D01*
G01X591914Y600629D02*
X592071Y601994D01*
X592306Y603149D01*
X592619Y604199D01*
X593011Y605354D01*
X593638Y606929D01*
X590504D01*
G01X597039Y601364D02*
X597588Y600839D01*
X598214Y600629D01*
X598841Y600839D01*
X599389Y601469D01*
X599781Y602414D01*
X599938Y603359D01*
Y604514D01*
X599781Y605459D01*
X599389Y606299D01*
X598919Y606719D01*
X598371Y606929D01*
X597744Y606719D01*
X597274Y606299D01*
X596961Y605669D01*
X596804Y604829D01*
X596961Y604094D01*
X597353Y603359D01*
X597823Y602939D01*
X598371Y602834D01*
X598998Y603044D01*
X599468Y603569D01*
X599938Y604514D01*
G01X563108Y775630D02*
X563265Y776995D01*
X563500Y778150D01*
X563813Y779200D01*
X564205Y780355D01*
X564832Y781930D01*
X561698D01*
G01X569408Y775630D02*
X569565Y776995D01*
X569800Y778150D01*
X570113Y779200D01*
X570505Y780355D01*
X571132Y781930D01*
X567998D01*
G01X575865Y775630D02*
X576413Y775735D01*
X577040Y776050D01*
X577432Y776575D01*
X577588Y777310D01*
X577432Y778045D01*
X576962Y778675D01*
X576257Y778990D01*
X575473D01*
X575003Y779200D01*
X574612Y779725D01*
X574455Y780460D01*
X574690Y781195D01*
X575238Y781720D01*
X575865Y781930D01*
X576492Y781720D01*
X577040Y781195D01*
X577275Y780460D01*
X577118Y779725D01*
X576727Y779200D01*
X576257Y778990D01*
X575473D01*
X574768Y778675D01*
X574298Y778045D01*
X574142Y777310D01*
X574298Y776575D01*
X574690Y776050D01*
X575317Y775735D01*
X575865Y775630D01*
G01X582008D02*
X582165Y776995D01*
X582400Y778150D01*
X582713Y779200D01*
X583105Y780355D01*
X583732Y781930D01*
X580598D01*
G01X588465Y775420D02*
X588308Y775525D01*
Y775735D01*
X588465Y775840D01*
X588622Y775735D01*
Y775525D01*
X588465Y775420D01*
G01X594765Y775630D02*
X595313Y775735D01*
X595940Y776050D01*
X596332Y776575D01*
X596488Y777310D01*
X596332Y778045D01*
X595862Y778675D01*
X595157Y778990D01*
X594373D01*
X593903Y779200D01*
X593512Y779725D01*
X593355Y780460D01*
X593590Y781195D01*
X594138Y781720D01*
X594765Y781930D01*
X595392Y781720D01*
X595940Y781195D01*
X596175Y780460D01*
X596018Y779725D01*
X595627Y779200D01*
X595157Y778990D01*
X594373D01*
X593668Y778675D01*
X593198Y778045D01*
X593042Y777310D01*
X593198Y776575D01*
X593590Y776050D01*
X594217Y775735D01*
X594765Y775630D01*
G01X601065Y781930D02*
X600438Y781720D01*
X599968Y781195D01*
X599655Y780565D01*
X599420Y779725D01*
X599342Y778780D01*
X599420Y777835D01*
X599655Y776995D01*
X599968Y776365D01*
X600438Y775840D01*
X601065Y775630D01*
X601692Y775840D01*
X602162Y776365D01*
X602475Y776995D01*
X602710Y777835D01*
X602788Y778780D01*
X602710Y779725D01*
X602475Y780565D01*
X602162Y781195D01*
X601692Y781720D01*
X601065Y781930D01*
G01X584463Y64463D02*
X584843Y64963D01*
X585286Y65213D01*
X585793Y65296D01*
X586426Y65129D01*
X586869Y64713D01*
X586996Y64213D01*
X586933Y63713D01*
X586679Y63296D01*
X585413Y62463D01*
X584843Y61879D01*
X584463Y61046D01*
X584336Y60296D01*
X586996D01*
G01X591526D02*
Y65296D01*
X589183Y61713D01*
X592349D01*
G01X596626Y60296D02*
Y65296D01*
X594283Y61713D01*
X597449D01*
G01X600966Y60129D02*
X600839Y60213D01*
Y60379D01*
X600966Y60463D01*
X601093Y60379D01*
Y60213D01*
X600966Y60129D01*
G01X606066Y65296D02*
X605559Y65129D01*
X605179Y64713D01*
X604926Y64213D01*
X604736Y63546D01*
X604673Y62796D01*
X604736Y62046D01*
X604926Y61379D01*
X605179Y60879D01*
X605559Y60463D01*
X606066Y60296D01*
X606573Y60463D01*
X606953Y60879D01*
X607206Y61379D01*
X607396Y62046D01*
X607459Y62796D01*
X607396Y63546D01*
X607206Y64213D01*
X606953Y64713D01*
X606573Y65129D01*
X606066Y65296D01*
G01X610216Y63629D02*
X612116Y60296D01*
G01Y63629D02*
X610216Y60296D01*
G01X615063Y64463D02*
X615443Y64963D01*
X615886Y65213D01*
X616393Y65296D01*
X617026Y65129D01*
X617469Y64713D01*
X617596Y64213D01*
X617533Y63713D01*
X617279Y63296D01*
X616013Y62463D01*
X615443Y61879D01*
X615063Y61046D01*
X614936Y60296D01*
X617596D01*
G01X621366Y65296D02*
X620859Y65129D01*
X620479Y64713D01*
X620226Y64213D01*
X620036Y63546D01*
X619973Y62796D01*
X620036Y62046D01*
X620226Y61379D01*
X620479Y60879D01*
X620859Y60463D01*
X621366Y60296D01*
X621873Y60463D01*
X622253Y60879D01*
X622506Y61379D01*
X622696Y62046D01*
X622759Y62796D01*
X622696Y63546D01*
X622506Y64213D01*
X622253Y64713D01*
X621873Y65129D01*
X621366Y65296D01*
G01X625073Y61046D02*
X625453Y60629D01*
X625896Y60379D01*
X626466Y60296D01*
X627036Y60463D01*
X627479Y60796D01*
X627796Y61379D01*
X627859Y62046D01*
X627733Y62713D01*
X627416Y63129D01*
X626973Y63463D01*
X626529Y63546D01*
X626086Y63463D01*
X625516Y63129D01*
X625706Y65296D01*
X627416D01*
G01X631566Y60129D02*
X631439Y60213D01*
Y60379D01*
X631566Y60463D01*
X631693Y60379D01*
Y60213D01*
X631566Y60129D01*
G01X636666Y65296D02*
X636159Y65129D01*
X635779Y64713D01*
X635526Y64213D01*
X635336Y63546D01*
X635273Y62796D01*
X635336Y62046D01*
X635526Y61379D01*
X635779Y60879D01*
X636159Y60463D01*
X636666Y60296D01*
X637173Y60463D01*
X637553Y60879D01*
X637806Y61379D01*
X637996Y62046D01*
X638059Y62796D01*
X637996Y63546D01*
X637806Y64213D01*
X637553Y64713D01*
X637173Y65129D01*
X636666Y65296D01*
G01X599573Y108546D02*
X599953Y107963D01*
X600459Y107629D01*
X601029Y107546D01*
X601536Y107629D01*
X602043Y108046D01*
X602359Y108546D01*
X602423Y109046D01*
X602296Y109629D01*
X601853Y110046D01*
X601409Y110213D01*
X600839D01*
G01X601409D02*
X601789Y110463D01*
X602106Y110879D01*
X602233Y111379D01*
X602106Y111879D01*
X601789Y112296D01*
X601219Y112546D01*
X600649Y112463D01*
X600079Y112129D01*
G01X606066Y107546D02*
Y112546D01*
X605306Y111546D01*
G01Y107546D02*
X606826D01*
G01X609773Y108296D02*
X610153Y107879D01*
X610596Y107629D01*
X611166Y107546D01*
X611736Y107713D01*
X612179Y108046D01*
X612496Y108629D01*
X612559Y109296D01*
X612433Y109963D01*
X612116Y110379D01*
X611673Y110713D01*
X611229Y110796D01*
X610786Y110713D01*
X610216Y110379D01*
X610406Y112546D01*
X612116D01*
G01X616266Y107379D02*
X616139Y107463D01*
Y107629D01*
X616266Y107713D01*
X616393Y107629D01*
Y107463D01*
X616266Y107379D01*
G01X621366Y112546D02*
X620859Y112379D01*
X620479Y111963D01*
X620226Y111463D01*
X620036Y110796D01*
X619973Y110046D01*
X620036Y109296D01*
X620226Y108629D01*
X620479Y108129D01*
X620859Y107713D01*
X621366Y107546D01*
X621873Y107713D01*
X622253Y108129D01*
X622506Y108629D01*
X622696Y109296D01*
X622759Y110046D01*
X622696Y110796D01*
X622506Y111463D01*
X622253Y111963D01*
X621873Y112379D01*
X621366Y112546D01*
G01X599763Y158963D02*
X600143Y159463D01*
X600586Y159713D01*
X601093Y159796D01*
X601726Y159629D01*
X602169Y159213D01*
X602296Y158713D01*
X602233Y158213D01*
X601979Y157796D01*
X600713Y156963D01*
X600143Y156379D01*
X599763Y155546D01*
X599636Y154796D01*
X602296D01*
G01X606066Y159796D02*
X605559Y159629D01*
X605179Y159213D01*
X604926Y158713D01*
X604736Y158046D01*
X604673Y157296D01*
X604736Y156546D01*
X604926Y155879D01*
X605179Y155379D01*
X605559Y154963D01*
X606066Y154796D01*
X606573Y154963D01*
X606953Y155379D01*
X607206Y155879D01*
X607396Y156546D01*
X607459Y157296D01*
X607396Y158046D01*
X607206Y158713D01*
X606953Y159213D01*
X606573Y159629D01*
X606066Y159796D01*
G01X609773Y155546D02*
X610153Y155129D01*
X610596Y154879D01*
X611166Y154796D01*
X611736Y154963D01*
X612179Y155296D01*
X612496Y155879D01*
X612559Y156546D01*
X612433Y157213D01*
X612116Y157629D01*
X611673Y157963D01*
X611229Y158046D01*
X610786Y157963D01*
X610216Y157629D01*
X610406Y159796D01*
X612116D01*
G01X616266Y154629D02*
X616139Y154713D01*
Y154879D01*
X616266Y154963D01*
X616393Y154879D01*
Y154713D01*
X616266Y154629D01*
G01X621366Y159796D02*
X620859Y159629D01*
X620479Y159213D01*
X620226Y158713D01*
X620036Y158046D01*
X619973Y157296D01*
X620036Y156546D01*
X620226Y155879D01*
X620479Y155379D01*
X620859Y154963D01*
X621366Y154796D01*
X621873Y154963D01*
X622253Y155379D01*
X622506Y155879D01*
X622696Y156546D01*
X622759Y157296D01*
X622696Y158046D01*
X622506Y158713D01*
X622253Y159213D01*
X621873Y159629D01*
X621366Y159796D01*
G01X600966Y202046D02*
Y207046D01*
X600206Y206046D01*
G01Y202046D02*
X601726D01*
G01X604673Y202796D02*
X605053Y202379D01*
X605496Y202129D01*
X606066Y202046D01*
X606636Y202213D01*
X607079Y202546D01*
X607396Y203129D01*
X607459Y203796D01*
X607333Y204463D01*
X607016Y204879D01*
X606573Y205213D01*
X606129Y205296D01*
X605686Y205213D01*
X605116Y204879D01*
X605306Y207046D01*
X607016D01*
G01X611166Y202046D02*
X611609Y202129D01*
X612116Y202379D01*
X612433Y202796D01*
X612559Y203379D01*
X612433Y203963D01*
X612053Y204463D01*
X611483Y204713D01*
X610849D01*
X610469Y204879D01*
X610153Y205296D01*
X610026Y205879D01*
X610216Y206463D01*
X610659Y206879D01*
X611166Y207046D01*
X611673Y206879D01*
X612116Y206463D01*
X612306Y205879D01*
X612179Y205296D01*
X611863Y204879D01*
X611483Y204713D01*
X610849D01*
X610279Y204463D01*
X609899Y203963D01*
X609773Y203379D01*
X609899Y202796D01*
X610216Y202379D01*
X610723Y202129D01*
X611166Y202046D01*
G01X616266Y201879D02*
X616139Y201963D01*
Y202129D01*
X616266Y202213D01*
X616393Y202129D01*
Y201963D01*
X616266Y201879D01*
G01X621366Y207046D02*
X620859Y206879D01*
X620479Y206463D01*
X620226Y205963D01*
X620036Y205296D01*
X619973Y204546D01*
X620036Y203796D01*
X620226Y203129D01*
X620479Y202629D01*
X620859Y202213D01*
X621366Y202046D01*
X621873Y202213D01*
X622253Y202629D01*
X622506Y203129D01*
X622696Y203796D01*
X622759Y204546D01*
X622696Y205296D01*
X622506Y205963D01*
X622253Y206463D01*
X621873Y206879D01*
X621366Y207046D01*
G01X600966Y249296D02*
Y254296D01*
X600206Y253296D01*
G01Y249296D02*
X601726D01*
G01X604673Y250296D02*
X605053Y249713D01*
X605559Y249379D01*
X606129Y249296D01*
X606636Y249379D01*
X607143Y249796D01*
X607459Y250296D01*
X607523Y250796D01*
X607396Y251379D01*
X606953Y251796D01*
X606509Y251963D01*
X605939D01*
G01X606509D02*
X606889Y252213D01*
X607206Y252629D01*
X607333Y253129D01*
X607206Y253629D01*
X606889Y254046D01*
X606319Y254296D01*
X605749Y254213D01*
X605179Y253879D01*
G01X609963Y253463D02*
X610343Y253963D01*
X610786Y254213D01*
X611293Y254296D01*
X611926Y254129D01*
X612369Y253713D01*
X612496Y253213D01*
X612433Y252713D01*
X612179Y252296D01*
X610913Y251463D01*
X610343Y250879D01*
X609963Y250046D01*
X609836Y249296D01*
X612496D01*
G01X616266Y249129D02*
X616139Y249213D01*
Y249379D01*
X616266Y249463D01*
X616393Y249379D01*
Y249213D01*
X616266Y249129D01*
G01X621366Y254296D02*
X620859Y254129D01*
X620479Y253713D01*
X620226Y253213D01*
X620036Y252546D01*
X619973Y251796D01*
X620036Y251046D01*
X620226Y250379D01*
X620479Y249879D01*
X620859Y249463D01*
X621366Y249296D01*
X621873Y249463D01*
X622253Y249879D01*
X622506Y250379D01*
X622696Y251046D01*
X622759Y251796D01*
X622696Y252546D01*
X622506Y253213D01*
X622253Y253713D01*
X621873Y254129D01*
X621366Y254296D01*
G01X600966Y296546D02*
Y301546D01*
X600206Y300546D01*
G01Y296546D02*
X601726D01*
G01X604863Y300713D02*
X605243Y301213D01*
X605686Y301463D01*
X606193Y301546D01*
X606826Y301379D01*
X607269Y300963D01*
X607396Y300463D01*
X607333Y299963D01*
X607079Y299546D01*
X605813Y298713D01*
X605243Y298129D01*
X604863Y297296D01*
X604736Y296546D01*
X607396D01*
G01X609963Y298629D02*
X610406Y299213D01*
X610786Y299546D01*
X611293Y299713D01*
X611736Y299546D01*
X612053Y299213D01*
X612306Y298713D01*
X612369Y298129D01*
X612306Y297629D01*
X612053Y297129D01*
X611673Y296713D01*
X611229Y296546D01*
X610723Y296713D01*
X610279Y297213D01*
X610026Y297963D01*
X609963Y298796D01*
X610089Y299879D01*
X610279Y300463D01*
X610596Y301046D01*
X611039Y301463D01*
X611483Y301546D01*
X611926Y301379D01*
X612243Y300963D01*
G01X616266Y296379D02*
X616139Y296463D01*
Y296629D01*
X616266Y296713D01*
X616393Y296629D01*
Y296463D01*
X616266Y296379D01*
G01X621366Y301546D02*
X620859Y301379D01*
X620479Y300963D01*
X620226Y300463D01*
X620036Y299796D01*
X619973Y299046D01*
X620036Y298296D01*
X620226Y297629D01*
X620479Y297129D01*
X620859Y296713D01*
X621366Y296546D01*
X621873Y296713D01*
X622253Y297129D01*
X622506Y297629D01*
X622696Y298296D01*
X622759Y299046D01*
X622696Y299796D01*
X622506Y300463D01*
X622253Y300963D01*
X621873Y301379D01*
X621366Y301546D01*
G01X602439Y344379D02*
X602883Y343963D01*
X603389Y343796D01*
X603896Y343963D01*
X604339Y344463D01*
X604656Y345213D01*
X604783Y345963D01*
Y346879D01*
X604656Y347629D01*
X604339Y348296D01*
X603959Y348629D01*
X603516Y348796D01*
X603009Y348629D01*
X602629Y348296D01*
X602376Y347796D01*
X602249Y347129D01*
X602376Y346546D01*
X602693Y345963D01*
X603073Y345629D01*
X603516Y345546D01*
X604023Y345713D01*
X604403Y346129D01*
X604783Y346879D01*
G01X607539Y344379D02*
X607983Y343963D01*
X608489Y343796D01*
X608996Y343963D01*
X609439Y344463D01*
X609756Y345213D01*
X609883Y345963D01*
Y346879D01*
X609756Y347629D01*
X609439Y348296D01*
X609059Y348629D01*
X608616Y348796D01*
X608109Y348629D01*
X607729Y348296D01*
X607476Y347796D01*
X607349Y347129D01*
X607476Y346546D01*
X607793Y345963D01*
X608173Y345629D01*
X608616Y345546D01*
X609123Y345713D01*
X609503Y346129D01*
X609883Y346879D01*
G01X613716Y343629D02*
X613589Y343713D01*
Y343879D01*
X613716Y343963D01*
X613843Y343879D01*
Y343713D01*
X613716Y343629D01*
G01X618816Y348796D02*
X618309Y348629D01*
X617929Y348213D01*
X617676Y347713D01*
X617486Y347046D01*
X617423Y346296D01*
X617486Y345546D01*
X617676Y344879D01*
X617929Y344379D01*
X618309Y343963D01*
X618816Y343796D01*
X619323Y343963D01*
X619703Y344379D01*
X619956Y344879D01*
X620146Y345546D01*
X620209Y346296D01*
X620146Y347046D01*
X619956Y347713D01*
X619703Y348213D01*
X619323Y348629D01*
X618816Y348796D01*
G01X602439Y391629D02*
X602883Y391213D01*
X603389Y391046D01*
X603896Y391213D01*
X604339Y391713D01*
X604656Y392463D01*
X604783Y393213D01*
Y394129D01*
X604656Y394879D01*
X604339Y395546D01*
X603959Y395879D01*
X603516Y396046D01*
X603009Y395879D01*
X602629Y395546D01*
X602376Y395046D01*
X602249Y394379D01*
X602376Y393796D01*
X602693Y393213D01*
X603073Y392879D01*
X603516Y392796D01*
X604023Y392963D01*
X604403Y393379D01*
X604783Y394129D01*
G01X607223Y391796D02*
X607603Y391379D01*
X608046Y391129D01*
X608616Y391046D01*
X609186Y391213D01*
X609629Y391546D01*
X609946Y392129D01*
X610009Y392796D01*
X609883Y393463D01*
X609566Y393879D01*
X609123Y394213D01*
X608679Y394296D01*
X608236Y394213D01*
X607666Y393879D01*
X607856Y396046D01*
X609566D01*
G01X613716Y390879D02*
X613589Y390963D01*
Y391129D01*
X613716Y391213D01*
X613843Y391129D01*
Y390963D01*
X613716Y390879D01*
G01X618816Y396046D02*
X618309Y395879D01*
X617929Y395463D01*
X617676Y394963D01*
X617486Y394296D01*
X617423Y393546D01*
X617486Y392796D01*
X617676Y392129D01*
X617929Y391629D01*
X618309Y391213D01*
X618816Y391046D01*
X619323Y391213D01*
X619703Y391629D01*
X619956Y392129D01*
X620146Y392796D01*
X620209Y393546D01*
X620146Y394296D01*
X619956Y394963D01*
X619703Y395463D01*
X619323Y395879D01*
X618816Y396046D01*
G01X602313Y440379D02*
X602756Y440963D01*
X603136Y441296D01*
X603643Y441463D01*
X604086Y441296D01*
X604403Y440963D01*
X604656Y440463D01*
X604719Y439879D01*
X604656Y439379D01*
X604403Y438879D01*
X604023Y438463D01*
X603579Y438296D01*
X603073Y438463D01*
X602629Y438963D01*
X602376Y439713D01*
X602313Y440546D01*
X602439Y441629D01*
X602629Y442213D01*
X602946Y442796D01*
X603389Y443213D01*
X603833Y443296D01*
X604276Y443129D01*
X604593Y442713D01*
G01X607223Y439296D02*
X607603Y438713D01*
X608109Y438379D01*
X608679Y438296D01*
X609186Y438379D01*
X609693Y438796D01*
X610009Y439296D01*
X610073Y439796D01*
X609946Y440379D01*
X609503Y440796D01*
X609059Y440963D01*
X608489D01*
G01X609059D02*
X609439Y441213D01*
X609756Y441629D01*
X609883Y442129D01*
X609756Y442629D01*
X609439Y443046D01*
X608869Y443296D01*
X608299Y443213D01*
X607729Y442879D01*
G01X613716Y438129D02*
X613589Y438213D01*
Y438379D01*
X613716Y438463D01*
X613843Y438379D01*
Y438213D01*
X613716Y438129D01*
G01X618816Y443296D02*
X618309Y443129D01*
X617929Y442713D01*
X617676Y442213D01*
X617486Y441546D01*
X617423Y440796D01*
X617486Y440046D01*
X617676Y439379D01*
X617929Y438879D01*
X618309Y438463D01*
X618816Y438296D01*
X619323Y438463D01*
X619703Y438879D01*
X619956Y439379D01*
X620146Y440046D01*
X620209Y440796D01*
X620146Y441546D01*
X619956Y442213D01*
X619703Y442713D01*
X619323Y443129D01*
X618816Y443296D01*
G01X602123Y486296D02*
X602503Y485879D01*
X602946Y485629D01*
X603516Y485546D01*
X604086Y485713D01*
X604529Y486046D01*
X604846Y486629D01*
X604909Y487296D01*
X604783Y487963D01*
X604466Y488379D01*
X604023Y488713D01*
X603579Y488796D01*
X603136Y488713D01*
X602566Y488379D01*
X602756Y490546D01*
X604466D01*
G01X608489Y485546D02*
X608616Y486629D01*
X608806Y487546D01*
X609059Y488379D01*
X609376Y489296D01*
X609883Y490546D01*
X607349D01*
G01X613716Y485379D02*
X613589Y485463D01*
Y485629D01*
X613716Y485713D01*
X613843Y485629D01*
Y485463D01*
X613716Y485379D01*
G01X618816Y490546D02*
X618309Y490379D01*
X617929Y489963D01*
X617676Y489463D01*
X617486Y488796D01*
X617423Y488046D01*
X617486Y487296D01*
X617676Y486629D01*
X617929Y486129D01*
X618309Y485713D01*
X618816Y485546D01*
X619323Y485713D01*
X619703Y486129D01*
X619956Y486629D01*
X620146Y487296D01*
X620209Y488046D01*
X620146Y488796D01*
X619956Y489463D01*
X619703Y489963D01*
X619323Y490379D01*
X618816Y490546D01*
G01X604276Y532796D02*
Y537796D01*
X601933Y534213D01*
X605099D01*
G01X609376Y532796D02*
Y537796D01*
X607033Y534213D01*
X610199D01*
G01X613716Y532629D02*
X613589Y532713D01*
Y532879D01*
X613716Y532963D01*
X613843Y532879D01*
Y532713D01*
X613716Y532629D01*
G01X618816Y537796D02*
X618309Y537629D01*
X617929Y537213D01*
X617676Y536713D01*
X617486Y536046D01*
X617423Y535296D01*
X617486Y534546D01*
X617676Y533879D01*
X617929Y533379D01*
X618309Y532963D01*
X618816Y532796D01*
X619323Y532963D01*
X619703Y533379D01*
X619956Y533879D01*
X620146Y534546D01*
X620209Y535296D01*
X620146Y536046D01*
X619956Y536713D01*
X619703Y537213D01*
X619323Y537629D01*
X618816Y537796D01*
G01X604276Y580046D02*
Y585046D01*
X601933Y581463D01*
X605099D01*
G01X608616Y585046D02*
X608109Y584879D01*
X607729Y584463D01*
X607476Y583963D01*
X607286Y583296D01*
X607223Y582546D01*
X607286Y581796D01*
X607476Y581129D01*
X607729Y580629D01*
X608109Y580213D01*
X608616Y580046D01*
X609123Y580213D01*
X609503Y580629D01*
X609756Y581129D01*
X609946Y581796D01*
X610009Y582546D01*
X609946Y583296D01*
X609756Y583963D01*
X609503Y584463D01*
X609123Y584879D01*
X608616Y585046D01*
G01X613716Y579879D02*
X613589Y579963D01*
Y580129D01*
X613716Y580213D01*
X613843Y580129D01*
Y579963D01*
X613716Y579879D01*
G01X618816Y585046D02*
X618309Y584879D01*
X617929Y584463D01*
X617676Y583963D01*
X617486Y583296D01*
X617423Y582546D01*
X617486Y581796D01*
X617676Y581129D01*
X617929Y580629D01*
X618309Y580213D01*
X618816Y580046D01*
X619323Y580213D01*
X619703Y580629D01*
X619956Y581129D01*
X620146Y581796D01*
X620209Y582546D01*
X620146Y583296D01*
X619956Y583963D01*
X619703Y584463D01*
X619323Y584879D01*
X618816Y585046D01*
G01X602123Y628296D02*
X602503Y627713D01*
X603009Y627379D01*
X603579Y627296D01*
X604086Y627379D01*
X604593Y627796D01*
X604909Y628296D01*
X604973Y628796D01*
X604846Y629379D01*
X604403Y629796D01*
X603959Y629963D01*
X603389D01*
G01X603959D02*
X604339Y630213D01*
X604656Y630629D01*
X604783Y631129D01*
X604656Y631629D01*
X604339Y632046D01*
X603769Y632296D01*
X603199Y632213D01*
X602629Y631879D01*
G01X607539Y627879D02*
X607983Y627463D01*
X608489Y627296D01*
X608996Y627463D01*
X609439Y627963D01*
X609756Y628713D01*
X609883Y629463D01*
Y630379D01*
X609756Y631129D01*
X609439Y631796D01*
X609059Y632129D01*
X608616Y632296D01*
X608109Y632129D01*
X607729Y631796D01*
X607476Y631296D01*
X607349Y630629D01*
X607476Y630046D01*
X607793Y629463D01*
X608173Y629129D01*
X608616Y629046D01*
X609123Y629213D01*
X609503Y629629D01*
X609883Y630379D01*
G01X613716Y627129D02*
X613589Y627213D01*
Y627379D01*
X613716Y627463D01*
X613843Y627379D01*
Y627213D01*
X613716Y627129D01*
G01X618816Y632296D02*
X618309Y632129D01*
X617929Y631713D01*
X617676Y631213D01*
X617486Y630546D01*
X617423Y629796D01*
X617486Y629046D01*
X617676Y628379D01*
X617929Y627879D01*
X618309Y627463D01*
X618816Y627296D01*
X619323Y627463D01*
X619703Y627879D01*
X619956Y628379D01*
X620146Y629046D01*
X620209Y629796D01*
X620146Y630546D01*
X619956Y631213D01*
X619703Y631713D01*
X619323Y632129D01*
X618816Y632296D01*
G01X602123Y675546D02*
X602503Y674963D01*
X603009Y674629D01*
X603579Y674546D01*
X604086Y674629D01*
X604593Y675046D01*
X604909Y675546D01*
X604973Y676046D01*
X604846Y676629D01*
X604403Y677046D01*
X603959Y677213D01*
X603389D01*
G01X603959D02*
X604339Y677463D01*
X604656Y677879D01*
X604783Y678379D01*
X604656Y678879D01*
X604339Y679296D01*
X603769Y679546D01*
X603199Y679463D01*
X602629Y679129D01*
G01X607413Y676629D02*
X607856Y677213D01*
X608236Y677546D01*
X608743Y677713D01*
X609186Y677546D01*
X609503Y677213D01*
X609756Y676713D01*
X609819Y676129D01*
X609756Y675629D01*
X609503Y675129D01*
X609123Y674713D01*
X608679Y674546D01*
X608173Y674713D01*
X607729Y675213D01*
X607476Y675963D01*
X607413Y676796D01*
X607539Y677879D01*
X607729Y678463D01*
X608046Y679046D01*
X608489Y679463D01*
X608933Y679546D01*
X609376Y679379D01*
X609693Y678963D01*
G01X613716Y674379D02*
X613589Y674463D01*
Y674629D01*
X613716Y674713D01*
X613843Y674629D01*
Y674463D01*
X613716Y674379D01*
G01X618816Y679546D02*
X618309Y679379D01*
X617929Y678963D01*
X617676Y678463D01*
X617486Y677796D01*
X617423Y677046D01*
X617486Y676296D01*
X617676Y675629D01*
X617929Y675129D01*
X618309Y674713D01*
X618816Y674546D01*
X619323Y674713D01*
X619703Y675129D01*
X619956Y675629D01*
X620146Y676296D01*
X620209Y677046D01*
X620146Y677796D01*
X619956Y678463D01*
X619703Y678963D01*
X619323Y679379D01*
X618816Y679546D01*
G01X602123Y722796D02*
X602503Y722213D01*
X603009Y721879D01*
X603579Y721796D01*
X604086Y721879D01*
X604593Y722296D01*
X604909Y722796D01*
X604973Y723296D01*
X604846Y723879D01*
X604403Y724296D01*
X603959Y724463D01*
X603389D01*
G01X603959D02*
X604339Y724713D01*
X604656Y725129D01*
X604783Y725629D01*
X604656Y726129D01*
X604339Y726546D01*
X603769Y726796D01*
X603199Y726713D01*
X602629Y726379D01*
G01X608616Y726796D02*
X608109Y726629D01*
X607729Y726213D01*
X607476Y725713D01*
X607286Y725046D01*
X607223Y724296D01*
X607286Y723546D01*
X607476Y722879D01*
X607729Y722379D01*
X608109Y721963D01*
X608616Y721796D01*
X609123Y721963D01*
X609503Y722379D01*
X609756Y722879D01*
X609946Y723546D01*
X610009Y724296D01*
X609946Y725046D01*
X609756Y725713D01*
X609503Y726213D01*
X609123Y726629D01*
X608616Y726796D01*
G01X613716Y721629D02*
X613589Y721713D01*
Y721879D01*
X613716Y721963D01*
X613843Y721879D01*
Y721713D01*
X613716Y721629D01*
G01X618816Y726796D02*
X618309Y726629D01*
X617929Y726213D01*
X617676Y725713D01*
X617486Y725046D01*
X617423Y724296D01*
X617486Y723546D01*
X617676Y722879D01*
X617929Y722379D01*
X618309Y721963D01*
X618816Y721796D01*
X619323Y721963D01*
X619703Y722379D01*
X619956Y722879D01*
X620146Y723546D01*
X620209Y724296D01*
X620146Y725046D01*
X619956Y725713D01*
X619703Y726213D01*
X619323Y726629D01*
X618816Y726796D01*
G01X602313Y773213D02*
X602693Y773713D01*
X603136Y773963D01*
X603643Y774046D01*
X604276Y773879D01*
X604719Y773463D01*
X604846Y772963D01*
X604783Y772463D01*
X604529Y772046D01*
X603263Y771213D01*
X602693Y770629D01*
X602313Y769796D01*
X602186Y769046D01*
X604846D01*
G01X608616D02*
X609059Y769129D01*
X609566Y769379D01*
X609883Y769796D01*
X610009Y770379D01*
X609883Y770963D01*
X609503Y771463D01*
X608933Y771713D01*
X608299D01*
X607919Y771879D01*
X607603Y772296D01*
X607476Y772879D01*
X607666Y773463D01*
X608109Y773879D01*
X608616Y774046D01*
X609123Y773879D01*
X609566Y773463D01*
X609756Y772879D01*
X609629Y772296D01*
X609313Y771879D01*
X608933Y771713D01*
X608299D01*
X607729Y771463D01*
X607349Y770963D01*
X607223Y770379D01*
X607349Y769796D01*
X607666Y769379D01*
X608173Y769129D01*
X608616Y769046D01*
G01X613716Y768879D02*
X613589Y768963D01*
Y769129D01*
X613716Y769213D01*
X613843Y769129D01*
Y768963D01*
X613716Y768879D01*
G01X618816Y774046D02*
X618309Y773879D01*
X617929Y773463D01*
X617676Y772963D01*
X617486Y772296D01*
X617423Y771546D01*
X617486Y770796D01*
X617676Y770129D01*
X617929Y769629D01*
X618309Y769213D01*
X618816Y769046D01*
X619323Y769213D01*
X619703Y769629D01*
X619956Y770129D01*
X620146Y770796D01*
X620209Y771546D01*
X620146Y772296D01*
X619956Y772963D01*
X619703Y773463D01*
X619323Y773879D01*
X618816Y774046D01*
G01X602313Y820463D02*
X602693Y820963D01*
X603136Y821213D01*
X603643Y821296D01*
X604276Y821129D01*
X604719Y820713D01*
X604846Y820213D01*
X604783Y819713D01*
X604529Y819296D01*
X603263Y818463D01*
X602693Y817879D01*
X602313Y817046D01*
X602186Y816296D01*
X604846D01*
G01X607413Y820463D02*
X607793Y820963D01*
X608236Y821213D01*
X608743Y821296D01*
X609376Y821129D01*
X609819Y820713D01*
X609946Y820213D01*
X609883Y819713D01*
X609629Y819296D01*
X608363Y818463D01*
X607793Y817879D01*
X607413Y817046D01*
X607286Y816296D01*
X609946D01*
G01X613716Y816129D02*
X613589Y816213D01*
Y816379D01*
X613716Y816463D01*
X613843Y816379D01*
Y816213D01*
X613716Y816129D01*
G01X618816Y821296D02*
X618309Y821129D01*
X617929Y820713D01*
X617676Y820213D01*
X617486Y819546D01*
X617423Y818796D01*
X617486Y818046D01*
X617676Y817379D01*
X617929Y816879D01*
X618309Y816463D01*
X618816Y816296D01*
X619323Y816463D01*
X619703Y816879D01*
X619956Y817379D01*
X620146Y818046D01*
X620209Y818796D01*
X620146Y819546D01*
X619956Y820213D01*
X619703Y820713D01*
X619323Y821129D01*
X618816Y821296D01*
G01X602313Y867713D02*
X602693Y868213D01*
X603136Y868463D01*
X603643Y868546D01*
X604276Y868379D01*
X604719Y867963D01*
X604846Y867463D01*
X604783Y866963D01*
X604529Y866546D01*
X603263Y865713D01*
X602693Y865129D01*
X602313Y864296D01*
X602186Y863546D01*
X604846D01*
G01X608616Y868546D02*
X608109Y868379D01*
X607729Y867963D01*
X607476Y867463D01*
X607286Y866796D01*
X607223Y866046D01*
X607286Y865296D01*
X607476Y864629D01*
X607729Y864129D01*
X608109Y863713D01*
X608616Y863546D01*
X609123Y863713D01*
X609503Y864129D01*
X609756Y864629D01*
X609946Y865296D01*
X610009Y866046D01*
X609946Y866796D01*
X609756Y867463D01*
X609503Y867963D01*
X609123Y868379D01*
X608616Y868546D01*
G01X613716Y863379D02*
X613589Y863463D01*
Y863629D01*
X613716Y863713D01*
X613843Y863629D01*
Y863463D01*
X613716Y863379D01*
G01X618816Y868546D02*
X618309Y868379D01*
X617929Y867963D01*
X617676Y867463D01*
X617486Y866796D01*
X617423Y866046D01*
X617486Y865296D01*
X617676Y864629D01*
X617929Y864129D01*
X618309Y863713D01*
X618816Y863546D01*
X619323Y863713D01*
X619703Y864129D01*
X619956Y864629D01*
X620146Y865296D01*
X620209Y866046D01*
X620146Y866796D01*
X619956Y867463D01*
X619703Y867963D01*
X619323Y868379D01*
X618816Y868546D01*
G01X603516Y910796D02*
Y915796D01*
X602756Y914796D01*
G01Y910796D02*
X604276D01*
G01X608616Y915796D02*
X608109Y915629D01*
X607729Y915213D01*
X607476Y914713D01*
X607286Y914046D01*
X607223Y913296D01*
X607286Y912546D01*
X607476Y911879D01*
X607729Y911379D01*
X608109Y910963D01*
X608616Y910796D01*
X609123Y910963D01*
X609503Y911379D01*
X609756Y911879D01*
X609946Y912546D01*
X610009Y913296D01*
X609946Y914046D01*
X609756Y914713D01*
X609503Y915213D01*
X609123Y915629D01*
X608616Y915796D01*
G01X613716Y910629D02*
X613589Y910713D01*
Y910879D01*
X613716Y910963D01*
X613843Y910879D01*
Y910713D01*
X613716Y910629D01*
G01X618816Y915796D02*
X618309Y915629D01*
X617929Y915213D01*
X617676Y914713D01*
X617486Y914046D01*
X617423Y913296D01*
X617486Y912546D01*
X617676Y911879D01*
X617929Y911379D01*
X618309Y910963D01*
X618816Y910796D01*
X619323Y910963D01*
X619703Y911379D01*
X619956Y911879D01*
X620146Y912546D01*
X620209Y913296D01*
X620146Y914046D01*
X619956Y914713D01*
X619703Y915213D01*
X619323Y915629D01*
X618816Y915796D01*
G01X603516Y958046D02*
Y963046D01*
X602756Y962046D01*
G01Y958046D02*
X604276D01*
G01X608616Y963046D02*
X608109Y962879D01*
X607729Y962463D01*
X607476Y961963D01*
X607286Y961296D01*
X607223Y960546D01*
X607286Y959796D01*
X607476Y959129D01*
X607729Y958629D01*
X608109Y958213D01*
X608616Y958046D01*
X609123Y958213D01*
X609503Y958629D01*
X609756Y959129D01*
X609946Y959796D01*
X610009Y960546D01*
X609946Y961296D01*
X609756Y961963D01*
X609503Y962463D01*
X609123Y962879D01*
X608616Y963046D01*
G01X613716Y957879D02*
X613589Y957963D01*
Y958129D01*
X613716Y958213D01*
X613843Y958129D01*
Y957963D01*
X613716Y957879D01*
G01X618816Y963046D02*
X618309Y962879D01*
X617929Y962463D01*
X617676Y961963D01*
X617486Y961296D01*
X617423Y960546D01*
X617486Y959796D01*
X617676Y959129D01*
X617929Y958629D01*
X618309Y958213D01*
X618816Y958046D01*
X619323Y958213D01*
X619703Y958629D01*
X619956Y959129D01*
X620146Y959796D01*
X620209Y960546D01*
X620146Y961296D01*
X619956Y961963D01*
X619703Y962463D01*
X619323Y962879D01*
X618816Y963046D01*
G01X602186Y988638D02*
X602693Y988221D01*
X603263Y987971D01*
X603769D01*
X604276Y988221D01*
X604656Y988638D01*
X604846Y989221D01*
X604719Y989804D01*
X604403Y990304D01*
X603833Y990638D01*
X603073Y990804D01*
X602629Y991138D01*
X602439Y991721D01*
X602566Y992304D01*
X602883Y992721D01*
X603326Y992971D01*
X603769D01*
X604213Y992804D01*
X604593Y992388D01*
G01X607856Y992971D02*
X609376D01*
G01X608616D02*
Y987971D01*
G01X607856D02*
X609376D01*
G01X612513Y992971D02*
X614919D01*
X612513Y987971D01*
X614919D01*
G01X620083D02*
X617549D01*
Y992971D01*
X620083D01*
G01X619069Y990554D02*
X617549D01*
G01X621083Y999271D02*
X622666Y1004271D01*
X624249Y999271D01*
G01X623679Y1001021D02*
X621653D01*
G01X626499Y1004271D02*
Y999271D01*
X629033D01*
G01X631599Y1004271D02*
Y999271D01*
X634133D01*
G01X641673Y1004271D02*
Y1000688D01*
X641926Y999938D01*
X642433Y999438D01*
X643066Y999271D01*
X643699Y999438D01*
X644206Y999938D01*
X644459Y1000688D01*
Y1004271D01*
G01X646709Y999271D02*
Y1004271D01*
X649623Y999271D01*
Y1004271D01*
G01X652506D02*
X654026D01*
G01X653266D02*
Y999271D01*
G01X652506D02*
X654026D01*
G01X658366Y1004271D02*
Y999271D01*
G01X656909Y1004271D02*
X659823D01*
G01X662136Y999938D02*
X662643Y999521D01*
X663213Y999271D01*
X663719D01*
X664226Y999521D01*
X664606Y999938D01*
X664796Y1000521D01*
X664669Y1001104D01*
X664353Y1001604D01*
X663783Y1001938D01*
X663023Y1002104D01*
X662579Y1002438D01*
X662389Y1003021D01*
X662516Y1003604D01*
X662833Y1004021D01*
X663276Y1004271D01*
X663719D01*
X664163Y1004104D01*
X664543Y1003688D01*
G01X672083Y999271D02*
X673666Y1004271D01*
X675249Y999271D01*
G01X674679Y1001021D02*
X672653D01*
G01X677499Y999271D02*
Y1004271D01*
X679083D01*
X679589Y1004021D01*
X679906Y1003688D01*
X680033Y1003021D01*
X679906Y1002354D01*
X679526Y1001938D01*
X679083Y1001688D01*
X677499D01*
G01X679083D02*
X680033Y999271D01*
G01X685133D02*
X682599D01*
Y1004271D01*
X685133D01*
G01X684119Y1001854D02*
X682599D01*
G01X693306Y1004271D02*
X694826D01*
G01X694066D02*
Y999271D01*
G01X693306D02*
X694826D01*
G01X697709D02*
Y1004271D01*
X700623Y999271D01*
Y1004271D01*
G01X707719Y999271D02*
Y1004271D01*
X709366Y1000104D01*
X711013Y1004271D01*
Y999271D01*
G01X713706Y1004271D02*
X715226D01*
G01X714466D02*
Y999271D01*
G01X713706D02*
X715226D01*
G01X718299Y1004271D02*
Y999271D01*
X720833D01*
G01X723336Y999938D02*
X723843Y999521D01*
X724413Y999271D01*
X724919D01*
X725426Y999521D01*
X725806Y999938D01*
X725996Y1000521D01*
X725869Y1001104D01*
X725553Y1001604D01*
X724983Y1001938D01*
X724223Y1002104D01*
X723779Y1002438D01*
X723589Y1003021D01*
X723716Y1003604D01*
X724033Y1004021D01*
X724476Y1004271D01*
X724919D01*
X725363Y1004104D01*
X725743Y1003688D01*
G01X608523Y1024271D02*
Y1029271D01*
X609789D01*
X610296Y1029021D01*
X610676Y1028688D01*
X610993Y1028188D01*
X611246Y1027604D01*
X611309Y1026771D01*
X611246Y1025938D01*
X610993Y1025354D01*
X610676Y1024854D01*
X610296Y1024521D01*
X609789Y1024271D01*
X608523D01*
G01X613749D02*
Y1029271D01*
X615333D01*
X615839Y1029021D01*
X616156Y1028688D01*
X616283Y1028021D01*
X616156Y1027354D01*
X615776Y1026938D01*
X615333Y1026688D01*
X613749D01*
G01X615333D02*
X616283Y1024271D01*
G01X619356Y1029271D02*
X620876D01*
G01X620116D02*
Y1024271D01*
G01X619356D02*
X620876D01*
G01X623949Y1029271D02*
Y1024271D01*
X626483D01*
G01X629049Y1029271D02*
Y1024271D01*
X631583D01*
G01X641909Y1028854D02*
X641529Y1029104D01*
X641086Y1029271D01*
X640579D01*
X640009Y1029021D01*
X639566Y1028604D01*
X639249Y1028104D01*
X638996Y1027271D01*
X638933Y1026521D01*
X639059Y1025771D01*
X639249Y1025271D01*
X639629Y1024771D01*
X640073Y1024438D01*
X640516Y1024271D01*
X640959D01*
X641403Y1024438D01*
X641783Y1024688D01*
X642099Y1025021D01*
G01X644286Y1024271D02*
Y1029271D01*
G01X646946D02*
Y1024271D01*
G01Y1026771D02*
X644286D01*
G01X649133Y1024271D02*
X650716Y1029271D01*
X652299Y1024271D01*
G01X651729Y1026021D02*
X649703D01*
G01X654549Y1024271D02*
Y1029271D01*
X656133D01*
X656639Y1029021D01*
X656956Y1028688D01*
X657083Y1028021D01*
X656956Y1027354D01*
X656576Y1026938D01*
X656133Y1026688D01*
X654549D01*
G01X656133D02*
X657083Y1024271D01*
G01X660916Y1029271D02*
Y1024271D01*
G01X659459Y1029271D02*
X662373D01*
G01X666016Y1024104D02*
X665889Y1024188D01*
Y1024354D01*
X666016Y1024438D01*
X666143Y1024354D01*
Y1024188D01*
X666016Y1024104D01*
G01Y1026354D02*
X665889Y1026438D01*
Y1026604D01*
X666016Y1026688D01*
X666143Y1026604D01*
Y1026438D01*
X666016Y1026354D01*
G01X676216Y1029271D02*
Y1024271D01*
G01X674759Y1029271D02*
X677673D01*
G01X681316Y1024271D02*
X680809Y1024354D01*
X680366Y1024688D01*
X679986Y1025188D01*
X679733Y1025771D01*
X679606Y1026438D01*
Y1027104D01*
X679733Y1027771D01*
X679986Y1028354D01*
X680366Y1028854D01*
X680809Y1029188D01*
X681316Y1029271D01*
X681823Y1029188D01*
X682266Y1028854D01*
X682646Y1028354D01*
X682899Y1027771D01*
X683026Y1027104D01*
Y1026438D01*
X682899Y1025771D01*
X682646Y1025188D01*
X682266Y1024688D01*
X681823Y1024354D01*
X681316Y1024271D01*
G01X685149D02*
Y1029271D01*
X686669D01*
X687176Y1029021D01*
X687556Y1028438D01*
X687683Y1027771D01*
X687556Y1027104D01*
X687239Y1026604D01*
X686669Y1026354D01*
X685149D01*
G01X696616Y1029271D02*
Y1024271D01*
G01X695729Y1027604D02*
X697503D01*
G01X701716Y1024271D02*
X701336Y1024354D01*
X700956Y1024688D01*
X700703Y1025271D01*
X700576Y1025938D01*
X700703Y1026604D01*
X700956Y1027188D01*
X701336Y1027521D01*
X701716Y1027604D01*
X702096Y1027521D01*
X702476Y1027188D01*
X702729Y1026604D01*
X702793Y1025938D01*
X702729Y1025271D01*
X702476Y1024688D01*
X702096Y1024354D01*
X701716Y1024271D01*
G01X712423Y1026938D02*
X712676Y1027188D01*
X712866Y1027604D01*
X712993Y1028188D01*
X712866Y1028688D01*
X712613Y1029021D01*
X712169Y1029271D01*
X710459D01*
Y1024271D01*
X712549D01*
X712993Y1024604D01*
X713246Y1025104D01*
X713373Y1025688D01*
X713246Y1026271D01*
X712866Y1026771D01*
X712423Y1026938D01*
X710459D01*
G01X717016Y1024271D02*
X716509Y1024354D01*
X716066Y1024688D01*
X715686Y1025188D01*
X715433Y1025771D01*
X715306Y1026438D01*
Y1027104D01*
X715433Y1027771D01*
X715686Y1028354D01*
X716066Y1028854D01*
X716509Y1029188D01*
X717016Y1029271D01*
X717523Y1029188D01*
X717966Y1028854D01*
X718346Y1028354D01*
X718599Y1027771D01*
X718726Y1027104D01*
Y1026438D01*
X718599Y1025771D01*
X718346Y1025188D01*
X717966Y1024688D01*
X717523Y1024354D01*
X717016Y1024271D01*
G01X722116Y1029271D02*
Y1024271D01*
G01X720659Y1029271D02*
X723573D01*
G01X727216D02*
Y1024271D01*
G01X725759Y1029271D02*
X728673D01*
G01X732316Y1024271D02*
X731809Y1024354D01*
X731366Y1024688D01*
X730986Y1025188D01*
X730733Y1025771D01*
X730606Y1026438D01*
Y1027104D01*
X730733Y1027771D01*
X730986Y1028354D01*
X731366Y1028854D01*
X731809Y1029188D01*
X732316Y1029271D01*
X732823Y1029188D01*
X733266Y1028854D01*
X733646Y1028354D01*
X733899Y1027771D01*
X734026Y1027104D01*
Y1026438D01*
X733899Y1025771D01*
X733646Y1025188D01*
X733266Y1024688D01*
X732823Y1024354D01*
X732316Y1024271D01*
G01X735769D02*
Y1029271D01*
X737416Y1025104D01*
X739063Y1029271D01*
Y1024271D01*
G01X667869Y61963D02*
X669389D01*
G01X668566Y63046D02*
Y60879D01*
G01X674426Y60296D02*
Y65296D01*
X672083Y61713D01*
X675249D01*
G01X678766Y60129D02*
X678639Y60213D01*
Y60379D01*
X678766Y60463D01*
X678893Y60379D01*
Y60213D01*
X678766Y60129D01*
G01X683866Y65296D02*
X683359Y65129D01*
X682979Y64713D01*
X682726Y64213D01*
X682536Y63546D01*
X682473Y62796D01*
X682536Y62046D01*
X682726Y61379D01*
X682979Y60879D01*
X683359Y60463D01*
X683866Y60296D01*
X684373Y60463D01*
X684753Y60879D01*
X685006Y61379D01*
X685196Y62046D01*
X685259Y62796D01*
X685196Y63546D01*
X685006Y64213D01*
X684753Y64713D01*
X684373Y65129D01*
X683866Y65296D01*
G01X687826Y60129D02*
X690106Y65296D01*
G01X693243Y61963D02*
X694889D01*
G01X699926Y60296D02*
Y65296D01*
X697583Y61713D01*
X700749D01*
G01X704266Y60129D02*
X704139Y60213D01*
Y60379D01*
X704266Y60463D01*
X704393Y60379D01*
Y60213D01*
X704266Y60129D01*
G01X709366Y65296D02*
X708859Y65129D01*
X708479Y64713D01*
X708226Y64213D01*
X708036Y63546D01*
X707973Y62796D01*
X708036Y62046D01*
X708226Y61379D01*
X708479Y60879D01*
X708859Y60463D01*
X709366Y60296D01*
X709873Y60463D01*
X710253Y60879D01*
X710506Y61379D01*
X710696Y62046D01*
X710759Y62796D01*
X710696Y63546D01*
X710506Y64213D01*
X710253Y64713D01*
X709873Y65129D01*
X709366Y65296D01*
G01X667869Y109213D02*
X669389D01*
G01X668566Y110296D02*
Y108129D01*
G01X674426Y107546D02*
Y112546D01*
X672083Y108963D01*
X675249D01*
G01X678766Y107379D02*
X678639Y107463D01*
Y107629D01*
X678766Y107713D01*
X678893Y107629D01*
Y107463D01*
X678766Y107379D01*
G01X683866Y112546D02*
X683359Y112379D01*
X682979Y111963D01*
X682726Y111463D01*
X682536Y110796D01*
X682473Y110046D01*
X682536Y109296D01*
X682726Y108629D01*
X682979Y108129D01*
X683359Y107713D01*
X683866Y107546D01*
X684373Y107713D01*
X684753Y108129D01*
X685006Y108629D01*
X685196Y109296D01*
X685259Y110046D01*
X685196Y110796D01*
X685006Y111463D01*
X684753Y111963D01*
X684373Y112379D01*
X683866Y112546D01*
G01X687826Y107379D02*
X690106Y112546D01*
G01X693243Y109213D02*
X694889D01*
G01X699926Y107546D02*
Y112546D01*
X697583Y108963D01*
X700749D01*
G01X704266Y107379D02*
X704139Y107463D01*
Y107629D01*
X704266Y107713D01*
X704393Y107629D01*
Y107463D01*
X704266Y107379D01*
G01X709366Y112546D02*
X708859Y112379D01*
X708479Y111963D01*
X708226Y111463D01*
X708036Y110796D01*
X707973Y110046D01*
X708036Y109296D01*
X708226Y108629D01*
X708479Y108129D01*
X708859Y107713D01*
X709366Y107546D01*
X709873Y107713D01*
X710253Y108129D01*
X710506Y108629D01*
X710696Y109296D01*
X710759Y110046D01*
X710696Y110796D01*
X710506Y111463D01*
X710253Y111963D01*
X709873Y112379D01*
X709366Y112546D01*
G01X667869Y156463D02*
X669389D01*
G01X668566Y157546D02*
Y155379D01*
G01X672463Y158963D02*
X672843Y159463D01*
X673286Y159713D01*
X673793Y159796D01*
X674426Y159629D01*
X674869Y159213D01*
X674996Y158713D01*
X674933Y158213D01*
X674679Y157796D01*
X673413Y156963D01*
X672843Y156379D01*
X672463Y155546D01*
X672336Y154796D01*
X674996D01*
G01X678766Y154629D02*
X678639Y154713D01*
Y154879D01*
X678766Y154963D01*
X678893Y154879D01*
Y154713D01*
X678766Y154629D01*
G01X683866Y159796D02*
X683359Y159629D01*
X682979Y159213D01*
X682726Y158713D01*
X682536Y158046D01*
X682473Y157296D01*
X682536Y156546D01*
X682726Y155879D01*
X682979Y155379D01*
X683359Y154963D01*
X683866Y154796D01*
X684373Y154963D01*
X684753Y155379D01*
X685006Y155879D01*
X685196Y156546D01*
X685259Y157296D01*
X685196Y158046D01*
X685006Y158713D01*
X684753Y159213D01*
X684373Y159629D01*
X683866Y159796D01*
G01X687826Y154629D02*
X690106Y159796D01*
G01X693243Y156463D02*
X694889D01*
G01X697963Y158963D02*
X698343Y159463D01*
X698786Y159713D01*
X699293Y159796D01*
X699926Y159629D01*
X700369Y159213D01*
X700496Y158713D01*
X700433Y158213D01*
X700179Y157796D01*
X698913Y156963D01*
X698343Y156379D01*
X697963Y155546D01*
X697836Y154796D01*
X700496D01*
G01X704266Y154629D02*
X704139Y154713D01*
Y154879D01*
X704266Y154963D01*
X704393Y154879D01*
Y154713D01*
X704266Y154629D01*
G01X709366Y159796D02*
X708859Y159629D01*
X708479Y159213D01*
X708226Y158713D01*
X708036Y158046D01*
X707973Y157296D01*
X708036Y156546D01*
X708226Y155879D01*
X708479Y155379D01*
X708859Y154963D01*
X709366Y154796D01*
X709873Y154963D01*
X710253Y155379D01*
X710506Y155879D01*
X710696Y156546D01*
X710759Y157296D01*
X710696Y158046D01*
X710506Y158713D01*
X710253Y159213D01*
X709873Y159629D01*
X709366Y159796D01*
G01X667869Y203713D02*
X669389D01*
G01X668566Y204796D02*
Y202629D01*
G01X672463Y206213D02*
X672843Y206713D01*
X673286Y206963D01*
X673793Y207046D01*
X674426Y206879D01*
X674869Y206463D01*
X674996Y205963D01*
X674933Y205463D01*
X674679Y205046D01*
X673413Y204213D01*
X672843Y203629D01*
X672463Y202796D01*
X672336Y202046D01*
X674996D01*
G01X678766Y201879D02*
X678639Y201963D01*
Y202129D01*
X678766Y202213D01*
X678893Y202129D01*
Y201963D01*
X678766Y201879D01*
G01X683866Y207046D02*
X683359Y206879D01*
X682979Y206463D01*
X682726Y205963D01*
X682536Y205296D01*
X682473Y204546D01*
X682536Y203796D01*
X682726Y203129D01*
X682979Y202629D01*
X683359Y202213D01*
X683866Y202046D01*
X684373Y202213D01*
X684753Y202629D01*
X685006Y203129D01*
X685196Y203796D01*
X685259Y204546D01*
X685196Y205296D01*
X685006Y205963D01*
X684753Y206463D01*
X684373Y206879D01*
X683866Y207046D01*
G01X687826Y201879D02*
X690106Y207046D01*
G01X693243Y203713D02*
X694889D01*
G01X697963Y206213D02*
X698343Y206713D01*
X698786Y206963D01*
X699293Y207046D01*
X699926Y206879D01*
X700369Y206463D01*
X700496Y205963D01*
X700433Y205463D01*
X700179Y205046D01*
X698913Y204213D01*
X698343Y203629D01*
X697963Y202796D01*
X697836Y202046D01*
X700496D01*
G01X704266Y201879D02*
X704139Y201963D01*
Y202129D01*
X704266Y202213D01*
X704393Y202129D01*
Y201963D01*
X704266Y201879D01*
G01X709366Y207046D02*
X708859Y206879D01*
X708479Y206463D01*
X708226Y205963D01*
X708036Y205296D01*
X707973Y204546D01*
X708036Y203796D01*
X708226Y203129D01*
X708479Y202629D01*
X708859Y202213D01*
X709366Y202046D01*
X709873Y202213D01*
X710253Y202629D01*
X710506Y203129D01*
X710696Y203796D01*
X710759Y204546D01*
X710696Y205296D01*
X710506Y205963D01*
X710253Y206463D01*
X709873Y206879D01*
X709366Y207046D01*
G01X667869Y250963D02*
X669389D01*
G01X668566Y252046D02*
Y249879D01*
G01X672463Y253463D02*
X672843Y253963D01*
X673286Y254213D01*
X673793Y254296D01*
X674426Y254129D01*
X674869Y253713D01*
X674996Y253213D01*
X674933Y252713D01*
X674679Y252296D01*
X673413Y251463D01*
X672843Y250879D01*
X672463Y250046D01*
X672336Y249296D01*
X674996D01*
G01X678766Y249129D02*
X678639Y249213D01*
Y249379D01*
X678766Y249463D01*
X678893Y249379D01*
Y249213D01*
X678766Y249129D01*
G01X683866Y254296D02*
X683359Y254129D01*
X682979Y253713D01*
X682726Y253213D01*
X682536Y252546D01*
X682473Y251796D01*
X682536Y251046D01*
X682726Y250379D01*
X682979Y249879D01*
X683359Y249463D01*
X683866Y249296D01*
X684373Y249463D01*
X684753Y249879D01*
X685006Y250379D01*
X685196Y251046D01*
X685259Y251796D01*
X685196Y252546D01*
X685006Y253213D01*
X684753Y253713D01*
X684373Y254129D01*
X683866Y254296D01*
G01X687826Y249129D02*
X690106Y254296D01*
G01X693243Y250963D02*
X694889D01*
G01X697963Y253463D02*
X698343Y253963D01*
X698786Y254213D01*
X699293Y254296D01*
X699926Y254129D01*
X700369Y253713D01*
X700496Y253213D01*
X700433Y252713D01*
X700179Y252296D01*
X698913Y251463D01*
X698343Y250879D01*
X697963Y250046D01*
X697836Y249296D01*
X700496D01*
G01X704266Y249129D02*
X704139Y249213D01*
Y249379D01*
X704266Y249463D01*
X704393Y249379D01*
Y249213D01*
X704266Y249129D01*
G01X709366Y254296D02*
X708859Y254129D01*
X708479Y253713D01*
X708226Y253213D01*
X708036Y252546D01*
X707973Y251796D01*
X708036Y251046D01*
X708226Y250379D01*
X708479Y249879D01*
X708859Y249463D01*
X709366Y249296D01*
X709873Y249463D01*
X710253Y249879D01*
X710506Y250379D01*
X710696Y251046D01*
X710759Y251796D01*
X710696Y252546D01*
X710506Y253213D01*
X710253Y253713D01*
X709873Y254129D01*
X709366Y254296D01*
G01X667869Y298213D02*
X669389D01*
G01X668566Y299296D02*
Y297129D01*
G01X672463Y300713D02*
X672843Y301213D01*
X673286Y301463D01*
X673793Y301546D01*
X674426Y301379D01*
X674869Y300963D01*
X674996Y300463D01*
X674933Y299963D01*
X674679Y299546D01*
X673413Y298713D01*
X672843Y298129D01*
X672463Y297296D01*
X672336Y296546D01*
X674996D01*
G01X678766Y296379D02*
X678639Y296463D01*
Y296629D01*
X678766Y296713D01*
X678893Y296629D01*
Y296463D01*
X678766Y296379D01*
G01X683866Y301546D02*
X683359Y301379D01*
X682979Y300963D01*
X682726Y300463D01*
X682536Y299796D01*
X682473Y299046D01*
X682536Y298296D01*
X682726Y297629D01*
X682979Y297129D01*
X683359Y296713D01*
X683866Y296546D01*
X684373Y296713D01*
X684753Y297129D01*
X685006Y297629D01*
X685196Y298296D01*
X685259Y299046D01*
X685196Y299796D01*
X685006Y300463D01*
X684753Y300963D01*
X684373Y301379D01*
X683866Y301546D01*
G01X687826Y296379D02*
X690106Y301546D01*
G01X693243Y298213D02*
X694889D01*
G01X697963Y300713D02*
X698343Y301213D01*
X698786Y301463D01*
X699293Y301546D01*
X699926Y301379D01*
X700369Y300963D01*
X700496Y300463D01*
X700433Y299963D01*
X700179Y299546D01*
X698913Y298713D01*
X698343Y298129D01*
X697963Y297296D01*
X697836Y296546D01*
X700496D01*
G01X704266Y296379D02*
X704139Y296463D01*
Y296629D01*
X704266Y296713D01*
X704393Y296629D01*
Y296463D01*
X704266Y296379D01*
G01X709366Y301546D02*
X708859Y301379D01*
X708479Y300963D01*
X708226Y300463D01*
X708036Y299796D01*
X707973Y299046D01*
X708036Y298296D01*
X708226Y297629D01*
X708479Y297129D01*
X708859Y296713D01*
X709366Y296546D01*
X709873Y296713D01*
X710253Y297129D01*
X710506Y297629D01*
X710696Y298296D01*
X710759Y299046D01*
X710696Y299796D01*
X710506Y300463D01*
X710253Y300963D01*
X709873Y301379D01*
X709366Y301546D01*
G01X667869Y345463D02*
X669389D01*
G01X668566Y346546D02*
Y344379D01*
G01X672463Y347963D02*
X672843Y348463D01*
X673286Y348713D01*
X673793Y348796D01*
X674426Y348629D01*
X674869Y348213D01*
X674996Y347713D01*
X674933Y347213D01*
X674679Y346796D01*
X673413Y345963D01*
X672843Y345379D01*
X672463Y344546D01*
X672336Y343796D01*
X674996D01*
G01X678766Y343629D02*
X678639Y343713D01*
Y343879D01*
X678766Y343963D01*
X678893Y343879D01*
Y343713D01*
X678766Y343629D01*
G01X683866Y348796D02*
X683359Y348629D01*
X682979Y348213D01*
X682726Y347713D01*
X682536Y347046D01*
X682473Y346296D01*
X682536Y345546D01*
X682726Y344879D01*
X682979Y344379D01*
X683359Y343963D01*
X683866Y343796D01*
X684373Y343963D01*
X684753Y344379D01*
X685006Y344879D01*
X685196Y345546D01*
X685259Y346296D01*
X685196Y347046D01*
X685006Y347713D01*
X684753Y348213D01*
X684373Y348629D01*
X683866Y348796D01*
G01X687826Y343629D02*
X690106Y348796D01*
G01X693243Y345463D02*
X694889D01*
G01X697963Y347963D02*
X698343Y348463D01*
X698786Y348713D01*
X699293Y348796D01*
X699926Y348629D01*
X700369Y348213D01*
X700496Y347713D01*
X700433Y347213D01*
X700179Y346796D01*
X698913Y345963D01*
X698343Y345379D01*
X697963Y344546D01*
X697836Y343796D01*
X700496D01*
G01X704266Y343629D02*
X704139Y343713D01*
Y343879D01*
X704266Y343963D01*
X704393Y343879D01*
Y343713D01*
X704266Y343629D01*
G01X709366Y348796D02*
X708859Y348629D01*
X708479Y348213D01*
X708226Y347713D01*
X708036Y347046D01*
X707973Y346296D01*
X708036Y345546D01*
X708226Y344879D01*
X708479Y344379D01*
X708859Y343963D01*
X709366Y343796D01*
X709873Y343963D01*
X710253Y344379D01*
X710506Y344879D01*
X710696Y345546D01*
X710759Y346296D01*
X710696Y347046D01*
X710506Y347713D01*
X710253Y348213D01*
X709873Y348629D01*
X709366Y348796D01*
G01X667869Y392713D02*
X669389D01*
G01X668566Y393796D02*
Y391629D01*
G01X672463Y395213D02*
X672843Y395713D01*
X673286Y395963D01*
X673793Y396046D01*
X674426Y395879D01*
X674869Y395463D01*
X674996Y394963D01*
X674933Y394463D01*
X674679Y394046D01*
X673413Y393213D01*
X672843Y392629D01*
X672463Y391796D01*
X672336Y391046D01*
X674996D01*
G01X678766Y390879D02*
X678639Y390963D01*
Y391129D01*
X678766Y391213D01*
X678893Y391129D01*
Y390963D01*
X678766Y390879D01*
G01X683866Y396046D02*
X683359Y395879D01*
X682979Y395463D01*
X682726Y394963D01*
X682536Y394296D01*
X682473Y393546D01*
X682536Y392796D01*
X682726Y392129D01*
X682979Y391629D01*
X683359Y391213D01*
X683866Y391046D01*
X684373Y391213D01*
X684753Y391629D01*
X685006Y392129D01*
X685196Y392796D01*
X685259Y393546D01*
X685196Y394296D01*
X685006Y394963D01*
X684753Y395463D01*
X684373Y395879D01*
X683866Y396046D01*
G01X687826Y390879D02*
X690106Y396046D01*
G01X693243Y392713D02*
X694889D01*
G01X697963Y395213D02*
X698343Y395713D01*
X698786Y395963D01*
X699293Y396046D01*
X699926Y395879D01*
X700369Y395463D01*
X700496Y394963D01*
X700433Y394463D01*
X700179Y394046D01*
X698913Y393213D01*
X698343Y392629D01*
X697963Y391796D01*
X697836Y391046D01*
X700496D01*
G01X704266Y390879D02*
X704139Y390963D01*
Y391129D01*
X704266Y391213D01*
X704393Y391129D01*
Y390963D01*
X704266Y390879D01*
G01X709366Y396046D02*
X708859Y395879D01*
X708479Y395463D01*
X708226Y394963D01*
X708036Y394296D01*
X707973Y393546D01*
X708036Y392796D01*
X708226Y392129D01*
X708479Y391629D01*
X708859Y391213D01*
X709366Y391046D01*
X709873Y391213D01*
X710253Y391629D01*
X710506Y392129D01*
X710696Y392796D01*
X710759Y393546D01*
X710696Y394296D01*
X710506Y394963D01*
X710253Y395463D01*
X709873Y395879D01*
X709366Y396046D01*
G01X667869Y439963D02*
X669389D01*
G01X668566Y441046D02*
Y438879D01*
G01X672273Y439296D02*
X672653Y438713D01*
X673159Y438379D01*
X673729Y438296D01*
X674236Y438379D01*
X674743Y438796D01*
X675059Y439296D01*
X675123Y439796D01*
X674996Y440379D01*
X674553Y440796D01*
X674109Y440963D01*
X673539D01*
G01X674109D02*
X674489Y441213D01*
X674806Y441629D01*
X674933Y442129D01*
X674806Y442629D01*
X674489Y443046D01*
X673919Y443296D01*
X673349Y443213D01*
X672779Y442879D01*
G01X678766Y438129D02*
X678639Y438213D01*
Y438379D01*
X678766Y438463D01*
X678893Y438379D01*
Y438213D01*
X678766Y438129D01*
G01X683866Y443296D02*
X683359Y443129D01*
X682979Y442713D01*
X682726Y442213D01*
X682536Y441546D01*
X682473Y440796D01*
X682536Y440046D01*
X682726Y439379D01*
X682979Y438879D01*
X683359Y438463D01*
X683866Y438296D01*
X684373Y438463D01*
X684753Y438879D01*
X685006Y439379D01*
X685196Y440046D01*
X685259Y440796D01*
X685196Y441546D01*
X685006Y442213D01*
X684753Y442713D01*
X684373Y443129D01*
X683866Y443296D01*
G01X687826Y438129D02*
X690106Y443296D01*
G01X693243Y439963D02*
X694889D01*
G01X697773Y439296D02*
X698153Y438713D01*
X698659Y438379D01*
X699229Y438296D01*
X699736Y438379D01*
X700243Y438796D01*
X700559Y439296D01*
X700623Y439796D01*
X700496Y440379D01*
X700053Y440796D01*
X699609Y440963D01*
X699039D01*
G01X699609D02*
X699989Y441213D01*
X700306Y441629D01*
X700433Y442129D01*
X700306Y442629D01*
X699989Y443046D01*
X699419Y443296D01*
X698849Y443213D01*
X698279Y442879D01*
G01X704266Y438129D02*
X704139Y438213D01*
Y438379D01*
X704266Y438463D01*
X704393Y438379D01*
Y438213D01*
X704266Y438129D01*
G01X709366Y443296D02*
X708859Y443129D01*
X708479Y442713D01*
X708226Y442213D01*
X708036Y441546D01*
X707973Y440796D01*
X708036Y440046D01*
X708226Y439379D01*
X708479Y438879D01*
X708859Y438463D01*
X709366Y438296D01*
X709873Y438463D01*
X710253Y438879D01*
X710506Y439379D01*
X710696Y440046D01*
X710759Y440796D01*
X710696Y441546D01*
X710506Y442213D01*
X710253Y442713D01*
X709873Y443129D01*
X709366Y443296D01*
G01X667869Y487213D02*
X669389D01*
G01X668566Y488296D02*
Y486129D01*
G01X672273Y486546D02*
X672653Y485963D01*
X673159Y485629D01*
X673729Y485546D01*
X674236Y485629D01*
X674743Y486046D01*
X675059Y486546D01*
X675123Y487046D01*
X674996Y487629D01*
X674553Y488046D01*
X674109Y488213D01*
X673539D01*
G01X674109D02*
X674489Y488463D01*
X674806Y488879D01*
X674933Y489379D01*
X674806Y489879D01*
X674489Y490296D01*
X673919Y490546D01*
X673349Y490463D01*
X672779Y490129D01*
G01X678766Y485379D02*
X678639Y485463D01*
Y485629D01*
X678766Y485713D01*
X678893Y485629D01*
Y485463D01*
X678766Y485379D01*
G01X683866Y490546D02*
X683359Y490379D01*
X682979Y489963D01*
X682726Y489463D01*
X682536Y488796D01*
X682473Y488046D01*
X682536Y487296D01*
X682726Y486629D01*
X682979Y486129D01*
X683359Y485713D01*
X683866Y485546D01*
X684373Y485713D01*
X684753Y486129D01*
X685006Y486629D01*
X685196Y487296D01*
X685259Y488046D01*
X685196Y488796D01*
X685006Y489463D01*
X684753Y489963D01*
X684373Y490379D01*
X683866Y490546D01*
G01X687826Y485379D02*
X690106Y490546D01*
G01X693243Y487213D02*
X694889D01*
G01X697773Y486546D02*
X698153Y485963D01*
X698659Y485629D01*
X699229Y485546D01*
X699736Y485629D01*
X700243Y486046D01*
X700559Y486546D01*
X700623Y487046D01*
X700496Y487629D01*
X700053Y488046D01*
X699609Y488213D01*
X699039D01*
G01X699609D02*
X699989Y488463D01*
X700306Y488879D01*
X700433Y489379D01*
X700306Y489879D01*
X699989Y490296D01*
X699419Y490546D01*
X698849Y490463D01*
X698279Y490129D01*
G01X704266Y485379D02*
X704139Y485463D01*
Y485629D01*
X704266Y485713D01*
X704393Y485629D01*
Y485463D01*
X704266Y485379D01*
G01X709366Y490546D02*
X708859Y490379D01*
X708479Y489963D01*
X708226Y489463D01*
X708036Y488796D01*
X707973Y488046D01*
X708036Y487296D01*
X708226Y486629D01*
X708479Y486129D01*
X708859Y485713D01*
X709366Y485546D01*
X709873Y485713D01*
X710253Y486129D01*
X710506Y486629D01*
X710696Y487296D01*
X710759Y488046D01*
X710696Y488796D01*
X710506Y489463D01*
X710253Y489963D01*
X709873Y490379D01*
X709366Y490546D01*
G01X667869Y534463D02*
X669389D01*
G01X668566Y535546D02*
Y533379D01*
G01X672273Y533796D02*
X672653Y533213D01*
X673159Y532879D01*
X673729Y532796D01*
X674236Y532879D01*
X674743Y533296D01*
X675059Y533796D01*
X675123Y534296D01*
X674996Y534879D01*
X674553Y535296D01*
X674109Y535463D01*
X673539D01*
G01X674109D02*
X674489Y535713D01*
X674806Y536129D01*
X674933Y536629D01*
X674806Y537129D01*
X674489Y537546D01*
X673919Y537796D01*
X673349Y537713D01*
X672779Y537379D01*
G01X678766Y532629D02*
X678639Y532713D01*
Y532879D01*
X678766Y532963D01*
X678893Y532879D01*
Y532713D01*
X678766Y532629D01*
G01X683866Y537796D02*
X683359Y537629D01*
X682979Y537213D01*
X682726Y536713D01*
X682536Y536046D01*
X682473Y535296D01*
X682536Y534546D01*
X682726Y533879D01*
X682979Y533379D01*
X683359Y532963D01*
X683866Y532796D01*
X684373Y532963D01*
X684753Y533379D01*
X685006Y533879D01*
X685196Y534546D01*
X685259Y535296D01*
X685196Y536046D01*
X685006Y536713D01*
X684753Y537213D01*
X684373Y537629D01*
X683866Y537796D01*
G01X687826Y532629D02*
X690106Y537796D01*
G01X693243Y534463D02*
X694889D01*
G01X697773Y533796D02*
X698153Y533213D01*
X698659Y532879D01*
X699229Y532796D01*
X699736Y532879D01*
X700243Y533296D01*
X700559Y533796D01*
X700623Y534296D01*
X700496Y534879D01*
X700053Y535296D01*
X699609Y535463D01*
X699039D01*
G01X699609D02*
X699989Y535713D01*
X700306Y536129D01*
X700433Y536629D01*
X700306Y537129D01*
X699989Y537546D01*
X699419Y537796D01*
X698849Y537713D01*
X698279Y537379D01*
G01X704266Y532629D02*
X704139Y532713D01*
Y532879D01*
X704266Y532963D01*
X704393Y532879D01*
Y532713D01*
X704266Y532629D01*
G01X709366Y537796D02*
X708859Y537629D01*
X708479Y537213D01*
X708226Y536713D01*
X708036Y536046D01*
X707973Y535296D01*
X708036Y534546D01*
X708226Y533879D01*
X708479Y533379D01*
X708859Y532963D01*
X709366Y532796D01*
X709873Y532963D01*
X710253Y533379D01*
X710506Y533879D01*
X710696Y534546D01*
X710759Y535296D01*
X710696Y536046D01*
X710506Y536713D01*
X710253Y537213D01*
X709873Y537629D01*
X709366Y537796D01*
G01X667869Y581713D02*
X669389D01*
G01X668566Y582796D02*
Y580629D01*
G01X672273Y581046D02*
X672653Y580463D01*
X673159Y580129D01*
X673729Y580046D01*
X674236Y580129D01*
X674743Y580546D01*
X675059Y581046D01*
X675123Y581546D01*
X674996Y582129D01*
X674553Y582546D01*
X674109Y582713D01*
X673539D01*
G01X674109D02*
X674489Y582963D01*
X674806Y583379D01*
X674933Y583879D01*
X674806Y584379D01*
X674489Y584796D01*
X673919Y585046D01*
X673349Y584963D01*
X672779Y584629D01*
G01X678766Y579879D02*
X678639Y579963D01*
Y580129D01*
X678766Y580213D01*
X678893Y580129D01*
Y579963D01*
X678766Y579879D01*
G01X683866Y585046D02*
X683359Y584879D01*
X682979Y584463D01*
X682726Y583963D01*
X682536Y583296D01*
X682473Y582546D01*
X682536Y581796D01*
X682726Y581129D01*
X682979Y580629D01*
X683359Y580213D01*
X683866Y580046D01*
X684373Y580213D01*
X684753Y580629D01*
X685006Y581129D01*
X685196Y581796D01*
X685259Y582546D01*
X685196Y583296D01*
X685006Y583963D01*
X684753Y584463D01*
X684373Y584879D01*
X683866Y585046D01*
G01X687826Y579879D02*
X690106Y585046D01*
G01X693243Y581713D02*
X694889D01*
G01X697773Y581046D02*
X698153Y580463D01*
X698659Y580129D01*
X699229Y580046D01*
X699736Y580129D01*
X700243Y580546D01*
X700559Y581046D01*
X700623Y581546D01*
X700496Y582129D01*
X700053Y582546D01*
X699609Y582713D01*
X699039D01*
G01X699609D02*
X699989Y582963D01*
X700306Y583379D01*
X700433Y583879D01*
X700306Y584379D01*
X699989Y584796D01*
X699419Y585046D01*
X698849Y584963D01*
X698279Y584629D01*
G01X704266Y579879D02*
X704139Y579963D01*
Y580129D01*
X704266Y580213D01*
X704393Y580129D01*
Y579963D01*
X704266Y579879D01*
G01X709366Y585046D02*
X708859Y584879D01*
X708479Y584463D01*
X708226Y583963D01*
X708036Y583296D01*
X707973Y582546D01*
X708036Y581796D01*
X708226Y581129D01*
X708479Y580629D01*
X708859Y580213D01*
X709366Y580046D01*
X709873Y580213D01*
X710253Y580629D01*
X710506Y581129D01*
X710696Y581796D01*
X710759Y582546D01*
X710696Y583296D01*
X710506Y583963D01*
X710253Y584463D01*
X709873Y584879D01*
X709366Y585046D01*
G01X667869Y628963D02*
X669389D01*
G01X668566Y630046D02*
Y627879D01*
G01X672273Y628296D02*
X672653Y627713D01*
X673159Y627379D01*
X673729Y627296D01*
X674236Y627379D01*
X674743Y627796D01*
X675059Y628296D01*
X675123Y628796D01*
X674996Y629379D01*
X674553Y629796D01*
X674109Y629963D01*
X673539D01*
G01X674109D02*
X674489Y630213D01*
X674806Y630629D01*
X674933Y631129D01*
X674806Y631629D01*
X674489Y632046D01*
X673919Y632296D01*
X673349Y632213D01*
X672779Y631879D01*
G01X678766Y627129D02*
X678639Y627213D01*
Y627379D01*
X678766Y627463D01*
X678893Y627379D01*
Y627213D01*
X678766Y627129D01*
G01X683866Y632296D02*
X683359Y632129D01*
X682979Y631713D01*
X682726Y631213D01*
X682536Y630546D01*
X682473Y629796D01*
X682536Y629046D01*
X682726Y628379D01*
X682979Y627879D01*
X683359Y627463D01*
X683866Y627296D01*
X684373Y627463D01*
X684753Y627879D01*
X685006Y628379D01*
X685196Y629046D01*
X685259Y629796D01*
X685196Y630546D01*
X685006Y631213D01*
X684753Y631713D01*
X684373Y632129D01*
X683866Y632296D01*
G01X687826Y627129D02*
X690106Y632296D01*
G01X693243Y628963D02*
X694889D01*
G01X697773Y628296D02*
X698153Y627713D01*
X698659Y627379D01*
X699229Y627296D01*
X699736Y627379D01*
X700243Y627796D01*
X700559Y628296D01*
X700623Y628796D01*
X700496Y629379D01*
X700053Y629796D01*
X699609Y629963D01*
X699039D01*
G01X699609D02*
X699989Y630213D01*
X700306Y630629D01*
X700433Y631129D01*
X700306Y631629D01*
X699989Y632046D01*
X699419Y632296D01*
X698849Y632213D01*
X698279Y631879D01*
G01X704266Y627129D02*
X704139Y627213D01*
Y627379D01*
X704266Y627463D01*
X704393Y627379D01*
Y627213D01*
X704266Y627129D01*
G01X709366Y632296D02*
X708859Y632129D01*
X708479Y631713D01*
X708226Y631213D01*
X708036Y630546D01*
X707973Y629796D01*
X708036Y629046D01*
X708226Y628379D01*
X708479Y627879D01*
X708859Y627463D01*
X709366Y627296D01*
X709873Y627463D01*
X710253Y627879D01*
X710506Y628379D01*
X710696Y629046D01*
X710759Y629796D01*
X710696Y630546D01*
X710506Y631213D01*
X710253Y631713D01*
X709873Y632129D01*
X709366Y632296D01*
G01X667869Y676213D02*
X669389D01*
G01X668566Y677296D02*
Y675129D01*
G01X672273Y675546D02*
X672653Y674963D01*
X673159Y674629D01*
X673729Y674546D01*
X674236Y674629D01*
X674743Y675046D01*
X675059Y675546D01*
X675123Y676046D01*
X674996Y676629D01*
X674553Y677046D01*
X674109Y677213D01*
X673539D01*
G01X674109D02*
X674489Y677463D01*
X674806Y677879D01*
X674933Y678379D01*
X674806Y678879D01*
X674489Y679296D01*
X673919Y679546D01*
X673349Y679463D01*
X672779Y679129D01*
G01X678766Y674379D02*
X678639Y674463D01*
Y674629D01*
X678766Y674713D01*
X678893Y674629D01*
Y674463D01*
X678766Y674379D01*
G01X683866Y679546D02*
X683359Y679379D01*
X682979Y678963D01*
X682726Y678463D01*
X682536Y677796D01*
X682473Y677046D01*
X682536Y676296D01*
X682726Y675629D01*
X682979Y675129D01*
X683359Y674713D01*
X683866Y674546D01*
X684373Y674713D01*
X684753Y675129D01*
X685006Y675629D01*
X685196Y676296D01*
X685259Y677046D01*
X685196Y677796D01*
X685006Y678463D01*
X684753Y678963D01*
X684373Y679379D01*
X683866Y679546D01*
G01X687826Y674379D02*
X690106Y679546D01*
G01X693243Y676213D02*
X694889D01*
G01X697773Y675546D02*
X698153Y674963D01*
X698659Y674629D01*
X699229Y674546D01*
X699736Y674629D01*
X700243Y675046D01*
X700559Y675546D01*
X700623Y676046D01*
X700496Y676629D01*
X700053Y677046D01*
X699609Y677213D01*
X699039D01*
G01X699609D02*
X699989Y677463D01*
X700306Y677879D01*
X700433Y678379D01*
X700306Y678879D01*
X699989Y679296D01*
X699419Y679546D01*
X698849Y679463D01*
X698279Y679129D01*
G01X704266Y674379D02*
X704139Y674463D01*
Y674629D01*
X704266Y674713D01*
X704393Y674629D01*
Y674463D01*
X704266Y674379D01*
G01X709366Y679546D02*
X708859Y679379D01*
X708479Y678963D01*
X708226Y678463D01*
X708036Y677796D01*
X707973Y677046D01*
X708036Y676296D01*
X708226Y675629D01*
X708479Y675129D01*
X708859Y674713D01*
X709366Y674546D01*
X709873Y674713D01*
X710253Y675129D01*
X710506Y675629D01*
X710696Y676296D01*
X710759Y677046D01*
X710696Y677796D01*
X710506Y678463D01*
X710253Y678963D01*
X709873Y679379D01*
X709366Y679546D01*
G01X667869Y723463D02*
X669389D01*
G01X668566Y724546D02*
Y722379D01*
G01X672463Y725963D02*
X672843Y726463D01*
X673286Y726713D01*
X673793Y726796D01*
X674426Y726629D01*
X674869Y726213D01*
X674996Y725713D01*
X674933Y725213D01*
X674679Y724796D01*
X673413Y723963D01*
X672843Y723379D01*
X672463Y722546D01*
X672336Y721796D01*
X674996D01*
G01X678766Y721629D02*
X678639Y721713D01*
Y721879D01*
X678766Y721963D01*
X678893Y721879D01*
Y721713D01*
X678766Y721629D01*
G01X683866Y726796D02*
X683359Y726629D01*
X682979Y726213D01*
X682726Y725713D01*
X682536Y725046D01*
X682473Y724296D01*
X682536Y723546D01*
X682726Y722879D01*
X682979Y722379D01*
X683359Y721963D01*
X683866Y721796D01*
X684373Y721963D01*
X684753Y722379D01*
X685006Y722879D01*
X685196Y723546D01*
X685259Y724296D01*
X685196Y725046D01*
X685006Y725713D01*
X684753Y726213D01*
X684373Y726629D01*
X683866Y726796D01*
G01X687826Y721629D02*
X690106Y726796D01*
G01X693243Y723463D02*
X694889D01*
G01X697963Y725963D02*
X698343Y726463D01*
X698786Y726713D01*
X699293Y726796D01*
X699926Y726629D01*
X700369Y726213D01*
X700496Y725713D01*
X700433Y725213D01*
X700179Y724796D01*
X698913Y723963D01*
X698343Y723379D01*
X697963Y722546D01*
X697836Y721796D01*
X700496D01*
G01X704266Y721629D02*
X704139Y721713D01*
Y721879D01*
X704266Y721963D01*
X704393Y721879D01*
Y721713D01*
X704266Y721629D01*
G01X709366Y726796D02*
X708859Y726629D01*
X708479Y726213D01*
X708226Y725713D01*
X708036Y725046D01*
X707973Y724296D01*
X708036Y723546D01*
X708226Y722879D01*
X708479Y722379D01*
X708859Y721963D01*
X709366Y721796D01*
X709873Y721963D01*
X710253Y722379D01*
X710506Y722879D01*
X710696Y723546D01*
X710759Y724296D01*
X710696Y725046D01*
X710506Y725713D01*
X710253Y726213D01*
X709873Y726629D01*
X709366Y726796D01*
G01X667869Y770713D02*
X669389D01*
G01X668566Y771796D02*
Y769629D01*
G01X672463Y773213D02*
X672843Y773713D01*
X673286Y773963D01*
X673793Y774046D01*
X674426Y773879D01*
X674869Y773463D01*
X674996Y772963D01*
X674933Y772463D01*
X674679Y772046D01*
X673413Y771213D01*
X672843Y770629D01*
X672463Y769796D01*
X672336Y769046D01*
X674996D01*
G01X678766Y768879D02*
X678639Y768963D01*
Y769129D01*
X678766Y769213D01*
X678893Y769129D01*
Y768963D01*
X678766Y768879D01*
G01X683866Y774046D02*
X683359Y773879D01*
X682979Y773463D01*
X682726Y772963D01*
X682536Y772296D01*
X682473Y771546D01*
X682536Y770796D01*
X682726Y770129D01*
X682979Y769629D01*
X683359Y769213D01*
X683866Y769046D01*
X684373Y769213D01*
X684753Y769629D01*
X685006Y770129D01*
X685196Y770796D01*
X685259Y771546D01*
X685196Y772296D01*
X685006Y772963D01*
X684753Y773463D01*
X684373Y773879D01*
X683866Y774046D01*
G01X687826Y768879D02*
X690106Y774046D01*
G01X693243Y770713D02*
X694889D01*
G01X697963Y773213D02*
X698343Y773713D01*
X698786Y773963D01*
X699293Y774046D01*
X699926Y773879D01*
X700369Y773463D01*
X700496Y772963D01*
X700433Y772463D01*
X700179Y772046D01*
X698913Y771213D01*
X698343Y770629D01*
X697963Y769796D01*
X697836Y769046D01*
X700496D01*
G01X704266Y768879D02*
X704139Y768963D01*
Y769129D01*
X704266Y769213D01*
X704393Y769129D01*
Y768963D01*
X704266Y768879D01*
G01X709366Y774046D02*
X708859Y773879D01*
X708479Y773463D01*
X708226Y772963D01*
X708036Y772296D01*
X707973Y771546D01*
X708036Y770796D01*
X708226Y770129D01*
X708479Y769629D01*
X708859Y769213D01*
X709366Y769046D01*
X709873Y769213D01*
X710253Y769629D01*
X710506Y770129D01*
X710696Y770796D01*
X710759Y771546D01*
X710696Y772296D01*
X710506Y772963D01*
X710253Y773463D01*
X709873Y773879D01*
X709366Y774046D01*
G01X667869Y817963D02*
X669389D01*
G01X668566Y819046D02*
Y816879D01*
G01X672273Y817296D02*
X672653Y816713D01*
X673159Y816379D01*
X673729Y816296D01*
X674236Y816379D01*
X674743Y816796D01*
X675059Y817296D01*
X675123Y817796D01*
X674996Y818379D01*
X674553Y818796D01*
X674109Y818963D01*
X673539D01*
G01X674109D02*
X674489Y819213D01*
X674806Y819629D01*
X674933Y820129D01*
X674806Y820629D01*
X674489Y821046D01*
X673919Y821296D01*
X673349Y821213D01*
X672779Y820879D01*
G01X678766Y816129D02*
X678639Y816213D01*
Y816379D01*
X678766Y816463D01*
X678893Y816379D01*
Y816213D01*
X678766Y816129D01*
G01X683866Y821296D02*
X683359Y821129D01*
X682979Y820713D01*
X682726Y820213D01*
X682536Y819546D01*
X682473Y818796D01*
X682536Y818046D01*
X682726Y817379D01*
X682979Y816879D01*
X683359Y816463D01*
X683866Y816296D01*
X684373Y816463D01*
X684753Y816879D01*
X685006Y817379D01*
X685196Y818046D01*
X685259Y818796D01*
X685196Y819546D01*
X685006Y820213D01*
X684753Y820713D01*
X684373Y821129D01*
X683866Y821296D01*
G01X687826Y816129D02*
X690106Y821296D01*
G01X693243Y817963D02*
X694889D01*
G01X697773Y817296D02*
X698153Y816713D01*
X698659Y816379D01*
X699229Y816296D01*
X699736Y816379D01*
X700243Y816796D01*
X700559Y817296D01*
X700623Y817796D01*
X700496Y818379D01*
X700053Y818796D01*
X699609Y818963D01*
X699039D01*
G01X699609D02*
X699989Y819213D01*
X700306Y819629D01*
X700433Y820129D01*
X700306Y820629D01*
X699989Y821046D01*
X699419Y821296D01*
X698849Y821213D01*
X698279Y820879D01*
G01X704266Y816129D02*
X704139Y816213D01*
Y816379D01*
X704266Y816463D01*
X704393Y816379D01*
Y816213D01*
X704266Y816129D01*
G01X709366Y821296D02*
X708859Y821129D01*
X708479Y820713D01*
X708226Y820213D01*
X708036Y819546D01*
X707973Y818796D01*
X708036Y818046D01*
X708226Y817379D01*
X708479Y816879D01*
X708859Y816463D01*
X709366Y816296D01*
X709873Y816463D01*
X710253Y816879D01*
X710506Y817379D01*
X710696Y818046D01*
X710759Y818796D01*
X710696Y819546D01*
X710506Y820213D01*
X710253Y820713D01*
X709873Y821129D01*
X709366Y821296D01*
G01X667869Y865213D02*
X669389D01*
G01X668566Y866296D02*
Y864129D01*
G01X672273Y864546D02*
X672653Y863963D01*
X673159Y863629D01*
X673729Y863546D01*
X674236Y863629D01*
X674743Y864046D01*
X675059Y864546D01*
X675123Y865046D01*
X674996Y865629D01*
X674553Y866046D01*
X674109Y866213D01*
X673539D01*
G01X674109D02*
X674489Y866463D01*
X674806Y866879D01*
X674933Y867379D01*
X674806Y867879D01*
X674489Y868296D01*
X673919Y868546D01*
X673349Y868463D01*
X672779Y868129D01*
G01X678766Y863379D02*
X678639Y863463D01*
Y863629D01*
X678766Y863713D01*
X678893Y863629D01*
Y863463D01*
X678766Y863379D01*
G01X683866Y868546D02*
X683359Y868379D01*
X682979Y867963D01*
X682726Y867463D01*
X682536Y866796D01*
X682473Y866046D01*
X682536Y865296D01*
X682726Y864629D01*
X682979Y864129D01*
X683359Y863713D01*
X683866Y863546D01*
X684373Y863713D01*
X684753Y864129D01*
X685006Y864629D01*
X685196Y865296D01*
X685259Y866046D01*
X685196Y866796D01*
X685006Y867463D01*
X684753Y867963D01*
X684373Y868379D01*
X683866Y868546D01*
G01X687826Y863379D02*
X690106Y868546D01*
G01X693243Y865213D02*
X694889D01*
G01X697773Y864546D02*
X698153Y863963D01*
X698659Y863629D01*
X699229Y863546D01*
X699736Y863629D01*
X700243Y864046D01*
X700559Y864546D01*
X700623Y865046D01*
X700496Y865629D01*
X700053Y866046D01*
X699609Y866213D01*
X699039D01*
G01X699609D02*
X699989Y866463D01*
X700306Y866879D01*
X700433Y867379D01*
X700306Y867879D01*
X699989Y868296D01*
X699419Y868546D01*
X698849Y868463D01*
X698279Y868129D01*
G01X704266Y863379D02*
X704139Y863463D01*
Y863629D01*
X704266Y863713D01*
X704393Y863629D01*
Y863463D01*
X704266Y863379D01*
G01X709366Y868546D02*
X708859Y868379D01*
X708479Y867963D01*
X708226Y867463D01*
X708036Y866796D01*
X707973Y866046D01*
X708036Y865296D01*
X708226Y864629D01*
X708479Y864129D01*
X708859Y863713D01*
X709366Y863546D01*
X709873Y863713D01*
X710253Y864129D01*
X710506Y864629D01*
X710696Y865296D01*
X710759Y866046D01*
X710696Y866796D01*
X710506Y867463D01*
X710253Y867963D01*
X709873Y868379D01*
X709366Y868546D01*
G01X667869Y912463D02*
X669389D01*
G01X668566Y913546D02*
Y911379D01*
G01X672273Y911796D02*
X672653Y911213D01*
X673159Y910879D01*
X673729Y910796D01*
X674236Y910879D01*
X674743Y911296D01*
X675059Y911796D01*
X675123Y912296D01*
X674996Y912879D01*
X674553Y913296D01*
X674109Y913463D01*
X673539D01*
G01X674109D02*
X674489Y913713D01*
X674806Y914129D01*
X674933Y914629D01*
X674806Y915129D01*
X674489Y915546D01*
X673919Y915796D01*
X673349Y915713D01*
X672779Y915379D01*
G01X678766Y910629D02*
X678639Y910713D01*
Y910879D01*
X678766Y910963D01*
X678893Y910879D01*
Y910713D01*
X678766Y910629D01*
G01X683866Y915796D02*
X683359Y915629D01*
X682979Y915213D01*
X682726Y914713D01*
X682536Y914046D01*
X682473Y913296D01*
X682536Y912546D01*
X682726Y911879D01*
X682979Y911379D01*
X683359Y910963D01*
X683866Y910796D01*
X684373Y910963D01*
X684753Y911379D01*
X685006Y911879D01*
X685196Y912546D01*
X685259Y913296D01*
X685196Y914046D01*
X685006Y914713D01*
X684753Y915213D01*
X684373Y915629D01*
X683866Y915796D01*
G01X687826Y910629D02*
X690106Y915796D01*
G01X693243Y912463D02*
X694889D01*
G01X697773Y911796D02*
X698153Y911213D01*
X698659Y910879D01*
X699229Y910796D01*
X699736Y910879D01*
X700243Y911296D01*
X700559Y911796D01*
X700623Y912296D01*
X700496Y912879D01*
X700053Y913296D01*
X699609Y913463D01*
X699039D01*
G01X699609D02*
X699989Y913713D01*
X700306Y914129D01*
X700433Y914629D01*
X700306Y915129D01*
X699989Y915546D01*
X699419Y915796D01*
X698849Y915713D01*
X698279Y915379D01*
G01X704266Y910629D02*
X704139Y910713D01*
Y910879D01*
X704266Y910963D01*
X704393Y910879D01*
Y910713D01*
X704266Y910629D01*
G01X709366Y915796D02*
X708859Y915629D01*
X708479Y915213D01*
X708226Y914713D01*
X708036Y914046D01*
X707973Y913296D01*
X708036Y912546D01*
X708226Y911879D01*
X708479Y911379D01*
X708859Y910963D01*
X709366Y910796D01*
X709873Y910963D01*
X710253Y911379D01*
X710506Y911879D01*
X710696Y912546D01*
X710759Y913296D01*
X710696Y914046D01*
X710506Y914713D01*
X710253Y915213D01*
X709873Y915629D01*
X709366Y915796D01*
G01X667869Y959713D02*
X669389D01*
G01X668566Y960796D02*
Y958629D01*
G01X672273Y959046D02*
X672653Y958463D01*
X673159Y958129D01*
X673729Y958046D01*
X674236Y958129D01*
X674743Y958546D01*
X675059Y959046D01*
X675123Y959546D01*
X674996Y960129D01*
X674553Y960546D01*
X674109Y960713D01*
X673539D01*
G01X674109D02*
X674489Y960963D01*
X674806Y961379D01*
X674933Y961879D01*
X674806Y962379D01*
X674489Y962796D01*
X673919Y963046D01*
X673349Y962963D01*
X672779Y962629D01*
G01X678766Y957879D02*
X678639Y957963D01*
Y958129D01*
X678766Y958213D01*
X678893Y958129D01*
Y957963D01*
X678766Y957879D01*
G01X683866Y963046D02*
X683359Y962879D01*
X682979Y962463D01*
X682726Y961963D01*
X682536Y961296D01*
X682473Y960546D01*
X682536Y959796D01*
X682726Y959129D01*
X682979Y958629D01*
X683359Y958213D01*
X683866Y958046D01*
X684373Y958213D01*
X684753Y958629D01*
X685006Y959129D01*
X685196Y959796D01*
X685259Y960546D01*
X685196Y961296D01*
X685006Y961963D01*
X684753Y962463D01*
X684373Y962879D01*
X683866Y963046D01*
G01X687826Y957879D02*
X690106Y963046D01*
G01X693243Y959713D02*
X694889D01*
G01X697773Y959046D02*
X698153Y958463D01*
X698659Y958129D01*
X699229Y958046D01*
X699736Y958129D01*
X700243Y958546D01*
X700559Y959046D01*
X700623Y959546D01*
X700496Y960129D01*
X700053Y960546D01*
X699609Y960713D01*
X699039D01*
G01X699609D02*
X699989Y960963D01*
X700306Y961379D01*
X700433Y961879D01*
X700306Y962379D01*
X699989Y962796D01*
X699419Y963046D01*
X698849Y962963D01*
X698279Y962629D01*
G01X704266Y957879D02*
X704139Y957963D01*
Y958129D01*
X704266Y958213D01*
X704393Y958129D01*
Y957963D01*
X704266Y957879D01*
G01X709366Y963046D02*
X708859Y962879D01*
X708479Y962463D01*
X708226Y961963D01*
X708036Y961296D01*
X707973Y960546D01*
X708036Y959796D01*
X708226Y959129D01*
X708479Y958629D01*
X708859Y958213D01*
X709366Y958046D01*
X709873Y958213D01*
X710253Y958629D01*
X710506Y959129D01*
X710696Y959796D01*
X710759Y960546D01*
X710696Y961296D01*
X710506Y961963D01*
X710253Y962463D01*
X709873Y962879D01*
X709366Y963046D01*
G01X668566Y992971D02*
Y987971D01*
G01X667109Y992971D02*
X670023D01*
G01X673666Y987971D02*
X673159Y988054D01*
X672716Y988388D01*
X672336Y988888D01*
X672083Y989471D01*
X671956Y990138D01*
Y990804D01*
X672083Y991471D01*
X672336Y992054D01*
X672716Y992554D01*
X673159Y992888D01*
X673666Y992971D01*
X674173Y992888D01*
X674616Y992554D01*
X674996Y992054D01*
X675249Y991471D01*
X675376Y990804D01*
Y990138D01*
X675249Y989471D01*
X674996Y988888D01*
X674616Y988388D01*
X674173Y988054D01*
X673666Y987971D01*
G01X677499Y992971D02*
Y987971D01*
X680033D01*
G01X685133D02*
X682599D01*
Y992971D01*
X685133D01*
G01X684119Y990554D02*
X682599D01*
G01X687699Y987971D02*
Y992971D01*
X689283D01*
X689789Y992721D01*
X690106Y992388D01*
X690233Y991721D01*
X690106Y991054D01*
X689726Y990638D01*
X689283Y990388D01*
X687699D01*
G01X689283D02*
X690233Y987971D01*
G01X692483D02*
X694066Y992971D01*
X695649Y987971D01*
G01X695079Y989721D02*
X693053D01*
G01X697709Y987971D02*
Y992971D01*
X700623Y987971D01*
Y992971D01*
G01X705659Y992554D02*
X705279Y992804D01*
X704836Y992971D01*
X704329D01*
X703759Y992721D01*
X703316Y992304D01*
X702999Y991804D01*
X702746Y990971D01*
X702683Y990221D01*
X702809Y989471D01*
X702999Y988971D01*
X703379Y988471D01*
X703823Y988138D01*
X704266Y987971D01*
X704709D01*
X705153Y988138D01*
X705533Y988388D01*
X705849Y988721D01*
G01X710633Y987971D02*
X708099D01*
Y992971D01*
X710633D01*
G01X709619Y990554D02*
X708099D01*
G01X729609Y60296D02*
Y65296D01*
X732523Y60296D01*
Y65296D01*
G01X736166Y60296D02*
X735659Y60379D01*
X735216Y60713D01*
X734836Y61213D01*
X734583Y61796D01*
X734456Y62463D01*
Y63129D01*
X734583Y63796D01*
X734836Y64379D01*
X735216Y64879D01*
X735659Y65213D01*
X736166Y65296D01*
X736673Y65213D01*
X737116Y64879D01*
X737496Y64379D01*
X737749Y63796D01*
X737876Y63129D01*
Y62463D01*
X737749Y61796D01*
X737496Y61213D01*
X737116Y60713D01*
X736673Y60379D01*
X736166Y60296D01*
G01X739809D02*
Y65296D01*
X742723Y60296D01*
Y65296D01*
G01X745543Y61963D02*
X747189D01*
G01X750199Y60296D02*
Y65296D01*
X751719D01*
X752226Y65046D01*
X752606Y64463D01*
X752733Y63796D01*
X752606Y63129D01*
X752289Y62629D01*
X751719Y62379D01*
X750199D01*
G01X755299Y65296D02*
Y60296D01*
X757833D01*
G01X760083D02*
X761666Y65296D01*
X763249Y60296D01*
G01X762679Y62046D02*
X760653D01*
G01X766766Y65296D02*
Y60296D01*
G01X765309Y65296D02*
X768223D01*
G01X773133Y60296D02*
X770599D01*
Y65296D01*
X773133D01*
G01X772119Y62879D02*
X770599D01*
G01X775573Y60296D02*
Y65296D01*
X776839D01*
X777346Y65046D01*
X777726Y64713D01*
X778043Y64213D01*
X778296Y63629D01*
X778359Y62796D01*
X778296Y61963D01*
X778043Y61379D01*
X777726Y60879D01*
X777346Y60546D01*
X776839Y60296D01*
X775573D01*
G01X729609Y107546D02*
Y112546D01*
X732523Y107546D01*
Y112546D01*
G01X736166Y107546D02*
X735659Y107629D01*
X735216Y107963D01*
X734836Y108463D01*
X734583Y109046D01*
X734456Y109713D01*
Y110379D01*
X734583Y111046D01*
X734836Y111629D01*
X735216Y112129D01*
X735659Y112463D01*
X736166Y112546D01*
X736673Y112463D01*
X737116Y112129D01*
X737496Y111629D01*
X737749Y111046D01*
X737876Y110379D01*
Y109713D01*
X737749Y109046D01*
X737496Y108463D01*
X737116Y107963D01*
X736673Y107629D01*
X736166Y107546D01*
G01X739809D02*
Y112546D01*
X742723Y107546D01*
Y112546D01*
G01X745543Y109213D02*
X747189D01*
G01X750199Y107546D02*
Y112546D01*
X751719D01*
X752226Y112296D01*
X752606Y111713D01*
X752733Y111046D01*
X752606Y110379D01*
X752289Y109879D01*
X751719Y109629D01*
X750199D01*
G01X755299Y112546D02*
Y107546D01*
X757833D01*
G01X760083D02*
X761666Y112546D01*
X763249Y107546D01*
G01X762679Y109296D02*
X760653D01*
G01X766766Y112546D02*
Y107546D01*
G01X765309Y112546D02*
X768223D01*
G01X773133Y107546D02*
X770599D01*
Y112546D01*
X773133D01*
G01X772119Y110129D02*
X770599D01*
G01X775573Y107546D02*
Y112546D01*
X776839D01*
X777346Y112296D01*
X777726Y111963D01*
X778043Y111463D01*
X778296Y110879D01*
X778359Y110046D01*
X778296Y109213D01*
X778043Y108629D01*
X777726Y108129D01*
X777346Y107796D01*
X776839Y107546D01*
X775573D01*
G01X729609Y154796D02*
Y159796D01*
X732523Y154796D01*
Y159796D01*
G01X736166Y154796D02*
X735659Y154879D01*
X735216Y155213D01*
X734836Y155713D01*
X734583Y156296D01*
X734456Y156963D01*
Y157629D01*
X734583Y158296D01*
X734836Y158879D01*
X735216Y159379D01*
X735659Y159713D01*
X736166Y159796D01*
X736673Y159713D01*
X737116Y159379D01*
X737496Y158879D01*
X737749Y158296D01*
X737876Y157629D01*
Y156963D01*
X737749Y156296D01*
X737496Y155713D01*
X737116Y155213D01*
X736673Y154879D01*
X736166Y154796D01*
G01X739809D02*
Y159796D01*
X742723Y154796D01*
Y159796D01*
G01X745543Y156463D02*
X747189D01*
G01X750199Y154796D02*
Y159796D01*
X751719D01*
X752226Y159546D01*
X752606Y158963D01*
X752733Y158296D01*
X752606Y157629D01*
X752289Y157129D01*
X751719Y156879D01*
X750199D01*
G01X755299Y159796D02*
Y154796D01*
X757833D01*
G01X760083D02*
X761666Y159796D01*
X763249Y154796D01*
G01X762679Y156546D02*
X760653D01*
G01X766766Y159796D02*
Y154796D01*
G01X765309Y159796D02*
X768223D01*
G01X773133Y154796D02*
X770599D01*
Y159796D01*
X773133D01*
G01X772119Y157379D02*
X770599D01*
G01X775573Y154796D02*
Y159796D01*
X776839D01*
X777346Y159546D01*
X777726Y159213D01*
X778043Y158713D01*
X778296Y158129D01*
X778359Y157296D01*
X778296Y156463D01*
X778043Y155879D01*
X777726Y155379D01*
X777346Y155046D01*
X776839Y154796D01*
X775573D01*
G01X729609Y202046D02*
Y207046D01*
X732523Y202046D01*
Y207046D01*
G01X736166Y202046D02*
X735659Y202129D01*
X735216Y202463D01*
X734836Y202963D01*
X734583Y203546D01*
X734456Y204213D01*
Y204879D01*
X734583Y205546D01*
X734836Y206129D01*
X735216Y206629D01*
X735659Y206963D01*
X736166Y207046D01*
X736673Y206963D01*
X737116Y206629D01*
X737496Y206129D01*
X737749Y205546D01*
X737876Y204879D01*
Y204213D01*
X737749Y203546D01*
X737496Y202963D01*
X737116Y202463D01*
X736673Y202129D01*
X736166Y202046D01*
G01X739809D02*
Y207046D01*
X742723Y202046D01*
Y207046D01*
G01X745543Y203713D02*
X747189D01*
G01X750199Y202046D02*
Y207046D01*
X751719D01*
X752226Y206796D01*
X752606Y206213D01*
X752733Y205546D01*
X752606Y204879D01*
X752289Y204379D01*
X751719Y204129D01*
X750199D01*
G01X755299Y207046D02*
Y202046D01*
X757833D01*
G01X760083D02*
X761666Y207046D01*
X763249Y202046D01*
G01X762679Y203796D02*
X760653D01*
G01X766766Y207046D02*
Y202046D01*
G01X765309Y207046D02*
X768223D01*
G01X773133Y202046D02*
X770599D01*
Y207046D01*
X773133D01*
G01X772119Y204629D02*
X770599D01*
G01X775573Y202046D02*
Y207046D01*
X776839D01*
X777346Y206796D01*
X777726Y206463D01*
X778043Y205963D01*
X778296Y205379D01*
X778359Y204546D01*
X778296Y203713D01*
X778043Y203129D01*
X777726Y202629D01*
X777346Y202296D01*
X776839Y202046D01*
X775573D01*
G01X729609Y249296D02*
Y254296D01*
X732523Y249296D01*
Y254296D01*
G01X736166Y249296D02*
X735659Y249379D01*
X735216Y249713D01*
X734836Y250213D01*
X734583Y250796D01*
X734456Y251463D01*
Y252129D01*
X734583Y252796D01*
X734836Y253379D01*
X735216Y253879D01*
X735659Y254213D01*
X736166Y254296D01*
X736673Y254213D01*
X737116Y253879D01*
X737496Y253379D01*
X737749Y252796D01*
X737876Y252129D01*
Y251463D01*
X737749Y250796D01*
X737496Y250213D01*
X737116Y249713D01*
X736673Y249379D01*
X736166Y249296D01*
G01X739809D02*
Y254296D01*
X742723Y249296D01*
Y254296D01*
G01X745543Y250963D02*
X747189D01*
G01X750199Y249296D02*
Y254296D01*
X751719D01*
X752226Y254046D01*
X752606Y253463D01*
X752733Y252796D01*
X752606Y252129D01*
X752289Y251629D01*
X751719Y251379D01*
X750199D01*
G01X755299Y254296D02*
Y249296D01*
X757833D01*
G01X760083D02*
X761666Y254296D01*
X763249Y249296D01*
G01X762679Y251046D02*
X760653D01*
G01X766766Y254296D02*
Y249296D01*
G01X765309Y254296D02*
X768223D01*
G01X773133Y249296D02*
X770599D01*
Y254296D01*
X773133D01*
G01X772119Y251879D02*
X770599D01*
G01X775573Y249296D02*
Y254296D01*
X776839D01*
X777346Y254046D01*
X777726Y253713D01*
X778043Y253213D01*
X778296Y252629D01*
X778359Y251796D01*
X778296Y250963D01*
X778043Y250379D01*
X777726Y249879D01*
X777346Y249546D01*
X776839Y249296D01*
X775573D01*
G01X729609Y296546D02*
Y301546D01*
X732523Y296546D01*
Y301546D01*
G01X736166Y296546D02*
X735659Y296629D01*
X735216Y296963D01*
X734836Y297463D01*
X734583Y298046D01*
X734456Y298713D01*
Y299379D01*
X734583Y300046D01*
X734836Y300629D01*
X735216Y301129D01*
X735659Y301463D01*
X736166Y301546D01*
X736673Y301463D01*
X737116Y301129D01*
X737496Y300629D01*
X737749Y300046D01*
X737876Y299379D01*
Y298713D01*
X737749Y298046D01*
X737496Y297463D01*
X737116Y296963D01*
X736673Y296629D01*
X736166Y296546D01*
G01X739809D02*
Y301546D01*
X742723Y296546D01*
Y301546D01*
G01X745543Y298213D02*
X747189D01*
G01X750199Y296546D02*
Y301546D01*
X751719D01*
X752226Y301296D01*
X752606Y300713D01*
X752733Y300046D01*
X752606Y299379D01*
X752289Y298879D01*
X751719Y298629D01*
X750199D01*
G01X755299Y301546D02*
Y296546D01*
X757833D01*
G01X760083D02*
X761666Y301546D01*
X763249Y296546D01*
G01X762679Y298296D02*
X760653D01*
G01X766766Y301546D02*
Y296546D01*
G01X765309Y301546D02*
X768223D01*
G01X773133Y296546D02*
X770599D01*
Y301546D01*
X773133D01*
G01X772119Y299129D02*
X770599D01*
G01X775573Y296546D02*
Y301546D01*
X776839D01*
X777346Y301296D01*
X777726Y300963D01*
X778043Y300463D01*
X778296Y299879D01*
X778359Y299046D01*
X778296Y298213D01*
X778043Y297629D01*
X777726Y297129D01*
X777346Y296796D01*
X776839Y296546D01*
X775573D01*
G01X729609Y343796D02*
Y348796D01*
X732523Y343796D01*
Y348796D01*
G01X736166Y343796D02*
X735659Y343879D01*
X735216Y344213D01*
X734836Y344713D01*
X734583Y345296D01*
X734456Y345963D01*
Y346629D01*
X734583Y347296D01*
X734836Y347879D01*
X735216Y348379D01*
X735659Y348713D01*
X736166Y348796D01*
X736673Y348713D01*
X737116Y348379D01*
X737496Y347879D01*
X737749Y347296D01*
X737876Y346629D01*
Y345963D01*
X737749Y345296D01*
X737496Y344713D01*
X737116Y344213D01*
X736673Y343879D01*
X736166Y343796D01*
G01X739809D02*
Y348796D01*
X742723Y343796D01*
Y348796D01*
G01X745543Y345463D02*
X747189D01*
G01X750199Y343796D02*
Y348796D01*
X751719D01*
X752226Y348546D01*
X752606Y347963D01*
X752733Y347296D01*
X752606Y346629D01*
X752289Y346129D01*
X751719Y345879D01*
X750199D01*
G01X755299Y348796D02*
Y343796D01*
X757833D01*
G01X760083D02*
X761666Y348796D01*
X763249Y343796D01*
G01X762679Y345546D02*
X760653D01*
G01X766766Y348796D02*
Y343796D01*
G01X765309Y348796D02*
X768223D01*
G01X773133Y343796D02*
X770599D01*
Y348796D01*
X773133D01*
G01X772119Y346379D02*
X770599D01*
G01X775573Y343796D02*
Y348796D01*
X776839D01*
X777346Y348546D01*
X777726Y348213D01*
X778043Y347713D01*
X778296Y347129D01*
X778359Y346296D01*
X778296Y345463D01*
X778043Y344879D01*
X777726Y344379D01*
X777346Y344046D01*
X776839Y343796D01*
X775573D01*
G01X729609Y391046D02*
Y396046D01*
X732523Y391046D01*
Y396046D01*
G01X736166Y391046D02*
X735659Y391129D01*
X735216Y391463D01*
X734836Y391963D01*
X734583Y392546D01*
X734456Y393213D01*
Y393879D01*
X734583Y394546D01*
X734836Y395129D01*
X735216Y395629D01*
X735659Y395963D01*
X736166Y396046D01*
X736673Y395963D01*
X737116Y395629D01*
X737496Y395129D01*
X737749Y394546D01*
X737876Y393879D01*
Y393213D01*
X737749Y392546D01*
X737496Y391963D01*
X737116Y391463D01*
X736673Y391129D01*
X736166Y391046D01*
G01X739809D02*
Y396046D01*
X742723Y391046D01*
Y396046D01*
G01X745543Y392713D02*
X747189D01*
G01X750199Y391046D02*
Y396046D01*
X751719D01*
X752226Y395796D01*
X752606Y395213D01*
X752733Y394546D01*
X752606Y393879D01*
X752289Y393379D01*
X751719Y393129D01*
X750199D01*
G01X755299Y396046D02*
Y391046D01*
X757833D01*
G01X760083D02*
X761666Y396046D01*
X763249Y391046D01*
G01X762679Y392796D02*
X760653D01*
G01X766766Y396046D02*
Y391046D01*
G01X765309Y396046D02*
X768223D01*
G01X773133Y391046D02*
X770599D01*
Y396046D01*
X773133D01*
G01X772119Y393629D02*
X770599D01*
G01X775573Y391046D02*
Y396046D01*
X776839D01*
X777346Y395796D01*
X777726Y395463D01*
X778043Y394963D01*
X778296Y394379D01*
X778359Y393546D01*
X778296Y392713D01*
X778043Y392129D01*
X777726Y391629D01*
X777346Y391296D01*
X776839Y391046D01*
X775573D01*
G01X739999Y438296D02*
Y443296D01*
X741519D01*
X742026Y443046D01*
X742406Y442463D01*
X742533Y441796D01*
X742406Y441129D01*
X742089Y440629D01*
X741519Y440379D01*
X739999D01*
G01X745099Y443296D02*
Y438296D01*
X747633D01*
G01X749883D02*
X751466Y443296D01*
X753049Y438296D01*
G01X752479Y440046D02*
X750453D01*
G01X756566Y443296D02*
Y438296D01*
G01X755109Y443296D02*
X758023D01*
G01X762933Y438296D02*
X760399D01*
Y443296D01*
X762933D01*
G01X761919Y440879D02*
X760399D01*
G01X765373Y438296D02*
Y443296D01*
X766639D01*
X767146Y443046D01*
X767526Y442713D01*
X767843Y442213D01*
X768096Y441629D01*
X768159Y440796D01*
X768096Y439963D01*
X767843Y439379D01*
X767526Y438879D01*
X767146Y438546D01*
X766639Y438296D01*
X765373D01*
G01X739999Y485546D02*
Y490546D01*
X741519D01*
X742026Y490296D01*
X742406Y489713D01*
X742533Y489046D01*
X742406Y488379D01*
X742089Y487879D01*
X741519Y487629D01*
X739999D01*
G01X745099Y490546D02*
Y485546D01*
X747633D01*
G01X749883D02*
X751466Y490546D01*
X753049Y485546D01*
G01X752479Y487296D02*
X750453D01*
G01X756566Y490546D02*
Y485546D01*
G01X755109Y490546D02*
X758023D01*
G01X762933Y485546D02*
X760399D01*
Y490546D01*
X762933D01*
G01X761919Y488129D02*
X760399D01*
G01X765373Y485546D02*
Y490546D01*
X766639D01*
X767146Y490296D01*
X767526Y489963D01*
X767843Y489463D01*
X768096Y488879D01*
X768159Y488046D01*
X768096Y487213D01*
X767843Y486629D01*
X767526Y486129D01*
X767146Y485796D01*
X766639Y485546D01*
X765373D01*
G01X739999Y532796D02*
Y537796D01*
X741519D01*
X742026Y537546D01*
X742406Y536963D01*
X742533Y536296D01*
X742406Y535629D01*
X742089Y535129D01*
X741519Y534879D01*
X739999D01*
G01X745099Y537796D02*
Y532796D01*
X747633D01*
G01X749883D02*
X751466Y537796D01*
X753049Y532796D01*
G01X752479Y534546D02*
X750453D01*
G01X756566Y537796D02*
Y532796D01*
G01X755109Y537796D02*
X758023D01*
G01X762933Y532796D02*
X760399D01*
Y537796D01*
X762933D01*
G01X761919Y535379D02*
X760399D01*
G01X765373Y532796D02*
Y537796D01*
X766639D01*
X767146Y537546D01*
X767526Y537213D01*
X767843Y536713D01*
X768096Y536129D01*
X768159Y535296D01*
X768096Y534463D01*
X767843Y533879D01*
X767526Y533379D01*
X767146Y533046D01*
X766639Y532796D01*
X765373D01*
G01X739999Y580046D02*
Y585046D01*
X741519D01*
X742026Y584796D01*
X742406Y584213D01*
X742533Y583546D01*
X742406Y582879D01*
X742089Y582379D01*
X741519Y582129D01*
X739999D01*
G01X745099Y585046D02*
Y580046D01*
X747633D01*
G01X749883D02*
X751466Y585046D01*
X753049Y580046D01*
G01X752479Y581796D02*
X750453D01*
G01X756566Y585046D02*
Y580046D01*
G01X755109Y585046D02*
X758023D01*
G01X762933Y580046D02*
X760399D01*
Y585046D01*
X762933D01*
G01X761919Y582629D02*
X760399D01*
G01X765373Y580046D02*
Y585046D01*
X766639D01*
X767146Y584796D01*
X767526Y584463D01*
X767843Y583963D01*
X768096Y583379D01*
X768159Y582546D01*
X768096Y581713D01*
X767843Y581129D01*
X767526Y580629D01*
X767146Y580296D01*
X766639Y580046D01*
X765373D01*
G01X739999Y627296D02*
Y632296D01*
X741519D01*
X742026Y632046D01*
X742406Y631463D01*
X742533Y630796D01*
X742406Y630129D01*
X742089Y629629D01*
X741519Y629379D01*
X739999D01*
G01X745099Y632296D02*
Y627296D01*
X747633D01*
G01X749883D02*
X751466Y632296D01*
X753049Y627296D01*
G01X752479Y629046D02*
X750453D01*
G01X756566Y632296D02*
Y627296D01*
G01X755109Y632296D02*
X758023D01*
G01X762933Y627296D02*
X760399D01*
Y632296D01*
X762933D01*
G01X761919Y629879D02*
X760399D01*
G01X765373Y627296D02*
Y632296D01*
X766639D01*
X767146Y632046D01*
X767526Y631713D01*
X767843Y631213D01*
X768096Y630629D01*
X768159Y629796D01*
X768096Y628963D01*
X767843Y628379D01*
X767526Y627879D01*
X767146Y627546D01*
X766639Y627296D01*
X765373D01*
G01X739999Y674546D02*
Y679546D01*
X741519D01*
X742026Y679296D01*
X742406Y678713D01*
X742533Y678046D01*
X742406Y677379D01*
X742089Y676879D01*
X741519Y676629D01*
X739999D01*
G01X745099Y679546D02*
Y674546D01*
X747633D01*
G01X749883D02*
X751466Y679546D01*
X753049Y674546D01*
G01X752479Y676296D02*
X750453D01*
G01X756566Y679546D02*
Y674546D01*
G01X755109Y679546D02*
X758023D01*
G01X762933Y674546D02*
X760399D01*
Y679546D01*
X762933D01*
G01X761919Y677129D02*
X760399D01*
G01X765373Y674546D02*
Y679546D01*
X766639D01*
X767146Y679296D01*
X767526Y678963D01*
X767843Y678463D01*
X768096Y677879D01*
X768159Y677046D01*
X768096Y676213D01*
X767843Y675629D01*
X767526Y675129D01*
X767146Y674796D01*
X766639Y674546D01*
X765373D01*
G01X739999Y721796D02*
Y726796D01*
X741519D01*
X742026Y726546D01*
X742406Y725963D01*
X742533Y725296D01*
X742406Y724629D01*
X742089Y724129D01*
X741519Y723879D01*
X739999D01*
G01X745099Y726796D02*
Y721796D01*
X747633D01*
G01X749883D02*
X751466Y726796D01*
X753049Y721796D01*
G01X752479Y723546D02*
X750453D01*
G01X756566Y726796D02*
Y721796D01*
G01X755109Y726796D02*
X758023D01*
G01X762933Y721796D02*
X760399D01*
Y726796D01*
X762933D01*
G01X761919Y724379D02*
X760399D01*
G01X765373Y721796D02*
Y726796D01*
X766639D01*
X767146Y726546D01*
X767526Y726213D01*
X767843Y725713D01*
X768096Y725129D01*
X768159Y724296D01*
X768096Y723463D01*
X767843Y722879D01*
X767526Y722379D01*
X767146Y722046D01*
X766639Y721796D01*
X765373D01*
G01X739999Y769046D02*
Y774046D01*
X741519D01*
X742026Y773796D01*
X742406Y773213D01*
X742533Y772546D01*
X742406Y771879D01*
X742089Y771379D01*
X741519Y771129D01*
X739999D01*
G01X745099Y774046D02*
Y769046D01*
X747633D01*
G01X749883D02*
X751466Y774046D01*
X753049Y769046D01*
G01X752479Y770796D02*
X750453D01*
G01X756566Y774046D02*
Y769046D01*
G01X755109Y774046D02*
X758023D01*
G01X762933Y769046D02*
X760399D01*
Y774046D01*
X762933D01*
G01X761919Y771629D02*
X760399D01*
G01X765373Y769046D02*
Y774046D01*
X766639D01*
X767146Y773796D01*
X767526Y773463D01*
X767843Y772963D01*
X768096Y772379D01*
X768159Y771546D01*
X768096Y770713D01*
X767843Y770129D01*
X767526Y769629D01*
X767146Y769296D01*
X766639Y769046D01*
X765373D01*
G01X739999Y816296D02*
Y821296D01*
X741519D01*
X742026Y821046D01*
X742406Y820463D01*
X742533Y819796D01*
X742406Y819129D01*
X742089Y818629D01*
X741519Y818379D01*
X739999D01*
G01X745099Y821296D02*
Y816296D01*
X747633D01*
G01X749883D02*
X751466Y821296D01*
X753049Y816296D01*
G01X752479Y818046D02*
X750453D01*
G01X756566Y821296D02*
Y816296D01*
G01X755109Y821296D02*
X758023D01*
G01X762933Y816296D02*
X760399D01*
Y821296D01*
X762933D01*
G01X761919Y818879D02*
X760399D01*
G01X765373Y816296D02*
Y821296D01*
X766639D01*
X767146Y821046D01*
X767526Y820713D01*
X767843Y820213D01*
X768096Y819629D01*
X768159Y818796D01*
X768096Y817963D01*
X767843Y817379D01*
X767526Y816879D01*
X767146Y816546D01*
X766639Y816296D01*
X765373D01*
G01X739999Y863546D02*
Y868546D01*
X741519D01*
X742026Y868296D01*
X742406Y867713D01*
X742533Y867046D01*
X742406Y866379D01*
X742089Y865879D01*
X741519Y865629D01*
X739999D01*
G01X745099Y868546D02*
Y863546D01*
X747633D01*
G01X749883D02*
X751466Y868546D01*
X753049Y863546D01*
G01X752479Y865296D02*
X750453D01*
G01X756566Y868546D02*
Y863546D01*
G01X755109Y868546D02*
X758023D01*
G01X762933Y863546D02*
X760399D01*
Y868546D01*
X762933D01*
G01X761919Y866129D02*
X760399D01*
G01X765373Y863546D02*
Y868546D01*
X766639D01*
X767146Y868296D01*
X767526Y867963D01*
X767843Y867463D01*
X768096Y866879D01*
X768159Y866046D01*
X768096Y865213D01*
X767843Y864629D01*
X767526Y864129D01*
X767146Y863796D01*
X766639Y863546D01*
X765373D01*
G01X739999Y910796D02*
Y915796D01*
X741519D01*
X742026Y915546D01*
X742406Y914963D01*
X742533Y914296D01*
X742406Y913629D01*
X742089Y913129D01*
X741519Y912879D01*
X739999D01*
G01X745099Y915796D02*
Y910796D01*
X747633D01*
G01X749883D02*
X751466Y915796D01*
X753049Y910796D01*
G01X752479Y912546D02*
X750453D01*
G01X756566Y915796D02*
Y910796D01*
G01X755109Y915796D02*
X758023D01*
G01X762933Y910796D02*
X760399D01*
Y915796D01*
X762933D01*
G01X761919Y913379D02*
X760399D01*
G01X765373Y910796D02*
Y915796D01*
X766639D01*
X767146Y915546D01*
X767526Y915213D01*
X767843Y914713D01*
X768096Y914129D01*
X768159Y913296D01*
X768096Y912463D01*
X767843Y911879D01*
X767526Y911379D01*
X767146Y911046D01*
X766639Y910796D01*
X765373D01*
G01X739999Y958046D02*
Y963046D01*
X741519D01*
X742026Y962796D01*
X742406Y962213D01*
X742533Y961546D01*
X742406Y960879D01*
X742089Y960379D01*
X741519Y960129D01*
X739999D01*
G01X745099Y963046D02*
Y958046D01*
X747633D01*
G01X749883D02*
X751466Y963046D01*
X753049Y958046D01*
G01X752479Y959796D02*
X750453D01*
G01X756566Y963046D02*
Y958046D01*
G01X755109Y963046D02*
X758023D01*
G01X762933Y958046D02*
X760399D01*
Y963046D01*
X762933D01*
G01X761919Y960629D02*
X760399D01*
G01X765373Y958046D02*
Y963046D01*
X766639D01*
X767146Y962796D01*
X767526Y962463D01*
X767843Y961963D01*
X768096Y961379D01*
X768159Y960546D01*
X768096Y959713D01*
X767843Y959129D01*
X767526Y958629D01*
X767146Y958296D01*
X766639Y958046D01*
X765373D01*
G01X739999Y987971D02*
Y992971D01*
X741519D01*
X742026Y992721D01*
X742406Y992138D01*
X742533Y991471D01*
X742406Y990804D01*
X742089Y990304D01*
X741519Y990054D01*
X739999D01*
G01X745099Y992971D02*
Y987971D01*
X747633D01*
G01X749883D02*
X751466Y992971D01*
X753049Y987971D01*
G01X752479Y989721D02*
X750453D01*
G01X756566Y992971D02*
Y987971D01*
G01X755109Y992971D02*
X758023D01*
G01X762933Y987971D02*
X760399D01*
Y992971D01*
X762933D01*
G01X761919Y990554D02*
X760399D01*
G01X765373Y987971D02*
Y992971D01*
X766639D01*
X767146Y992721D01*
X767526Y992388D01*
X767843Y991888D01*
X768096Y991304D01*
X768159Y990471D01*
X768096Y989638D01*
X767843Y989054D01*
X767526Y988554D01*
X767146Y988221D01*
X766639Y987971D01*
X765373D01*
G01X796116Y60296D02*
Y65296D01*
X795356Y64296D01*
G01Y60296D02*
X796876D01*
G01X793566Y107546D02*
Y112546D01*
X792806Y111546D01*
G01Y107546D02*
X794326D01*
G01X797463Y111713D02*
X797843Y112213D01*
X798286Y112463D01*
X798793Y112546D01*
X799426Y112379D01*
X799869Y111963D01*
X799996Y111463D01*
X799933Y110963D01*
X799679Y110546D01*
X798413Y109713D01*
X797843Y109129D01*
X797463Y108296D01*
X797336Y107546D01*
X799996D01*
G01X796116Y154796D02*
Y159796D01*
X795356Y158796D01*
G01Y154796D02*
X796876D01*
G01X793566Y202046D02*
Y207046D01*
X792806Y206046D01*
G01Y202046D02*
X794326D01*
G01X797463Y206213D02*
X797843Y206713D01*
X798286Y206963D01*
X798793Y207046D01*
X799426Y206879D01*
X799869Y206463D01*
X799996Y205963D01*
X799933Y205463D01*
X799679Y205046D01*
X798413Y204213D01*
X797843Y203629D01*
X797463Y202796D01*
X797336Y202046D01*
X799996D01*
G01X793566Y249296D02*
Y254296D01*
X792806Y253296D01*
G01Y249296D02*
X794326D01*
G01X797463Y253463D02*
X797843Y253963D01*
X798286Y254213D01*
X798793Y254296D01*
X799426Y254129D01*
X799869Y253713D01*
X799996Y253213D01*
X799933Y252713D01*
X799679Y252296D01*
X798413Y251463D01*
X797843Y250879D01*
X797463Y250046D01*
X797336Y249296D01*
X799996D01*
G01X796876Y296546D02*
Y301546D01*
X794533Y297963D01*
X797699D01*
G01X792363Y347963D02*
X792743Y348463D01*
X793186Y348713D01*
X793693Y348796D01*
X794326Y348629D01*
X794769Y348213D01*
X794896Y347713D01*
X794833Y347213D01*
X794579Y346796D01*
X793313Y345963D01*
X792743Y345379D01*
X792363Y344546D01*
X792236Y343796D01*
X794896D01*
G01X799426D02*
Y348796D01*
X797083Y345213D01*
X800249D01*
G01X796876Y391046D02*
Y396046D01*
X794533Y392463D01*
X797699D01*
G01X796876Y438296D02*
Y443296D01*
X794533Y439713D01*
X797699D01*
G01X792363Y489713D02*
X792743Y490213D01*
X793186Y490463D01*
X793693Y490546D01*
X794326Y490379D01*
X794769Y489963D01*
X794896Y489463D01*
X794833Y488963D01*
X794579Y488546D01*
X793313Y487713D01*
X792743Y487129D01*
X792363Y486296D01*
X792236Y485546D01*
X794896D01*
G01X798666Y490546D02*
X798159Y490379D01*
X797779Y489963D01*
X797526Y489463D01*
X797336Y488796D01*
X797273Y488046D01*
X797336Y487296D01*
X797526Y486629D01*
X797779Y486129D01*
X798159Y485713D01*
X798666Y485546D01*
X799173Y485713D01*
X799553Y486129D01*
X799806Y486629D01*
X799996Y487296D01*
X800059Y488046D01*
X799996Y488796D01*
X799806Y489463D01*
X799553Y489963D01*
X799173Y490379D01*
X798666Y490546D01*
G01X789623Y533796D02*
X790003Y533213D01*
X790509Y532879D01*
X791079Y532796D01*
X791586Y532879D01*
X792093Y533296D01*
X792409Y533796D01*
X792473Y534296D01*
X792346Y534879D01*
X791903Y535296D01*
X791459Y535463D01*
X790889D01*
G01X791459D02*
X791839Y535713D01*
X792156Y536129D01*
X792283Y536629D01*
X792156Y537129D01*
X791839Y537546D01*
X791269Y537796D01*
X790699Y537713D01*
X790129Y537379D01*
G01X796116Y532796D02*
X796559Y532879D01*
X797066Y533129D01*
X797383Y533546D01*
X797509Y534129D01*
X797383Y534713D01*
X797003Y535213D01*
X796433Y535463D01*
X795799D01*
X795419Y535629D01*
X795103Y536046D01*
X794976Y536629D01*
X795166Y537213D01*
X795609Y537629D01*
X796116Y537796D01*
X796623Y537629D01*
X797066Y537213D01*
X797256Y536629D01*
X797129Y536046D01*
X796813Y535629D01*
X796433Y535463D01*
X795799D01*
X795229Y535213D01*
X794849Y534713D01*
X794723Y534129D01*
X794849Y533546D01*
X795166Y533129D01*
X795673Y532879D01*
X796116Y532796D01*
G01X801976D02*
Y537796D01*
X799633Y534213D01*
X802799D01*
G01X796116Y580046D02*
X796559Y580129D01*
X797066Y580379D01*
X797383Y580796D01*
X797509Y581379D01*
X797383Y581963D01*
X797003Y582463D01*
X796433Y582713D01*
X795799D01*
X795419Y582879D01*
X795103Y583296D01*
X794976Y583879D01*
X795166Y584463D01*
X795609Y584879D01*
X796116Y585046D01*
X796623Y584879D01*
X797066Y584463D01*
X797256Y583879D01*
X797129Y583296D01*
X796813Y582879D01*
X796433Y582713D01*
X795799D01*
X795229Y582463D01*
X794849Y581963D01*
X794723Y581379D01*
X794849Y580796D01*
X795166Y580379D01*
X795673Y580129D01*
X796116Y580046D01*
G01X794326Y627296D02*
Y632296D01*
X791983Y628713D01*
X795149D01*
G01X798666Y627296D02*
X799109Y627379D01*
X799616Y627629D01*
X799933Y628046D01*
X800059Y628629D01*
X799933Y629213D01*
X799553Y629713D01*
X798983Y629963D01*
X798349D01*
X797969Y630129D01*
X797653Y630546D01*
X797526Y631129D01*
X797716Y631713D01*
X798159Y632129D01*
X798666Y632296D01*
X799173Y632129D01*
X799616Y631713D01*
X799806Y631129D01*
X799679Y630546D01*
X799363Y630129D01*
X798983Y629963D01*
X798349D01*
X797779Y629713D01*
X797399Y629213D01*
X797273Y628629D01*
X797399Y628046D01*
X797716Y627629D01*
X798223Y627379D01*
X798666Y627296D01*
G01X793439Y674546D02*
X793566Y675629D01*
X793756Y676546D01*
X794009Y677379D01*
X794326Y678296D01*
X794833Y679546D01*
X792299D01*
G01X797463Y678713D02*
X797843Y679213D01*
X798286Y679463D01*
X798793Y679546D01*
X799426Y679379D01*
X799869Y678963D01*
X799996Y678463D01*
X799933Y677963D01*
X799679Y677546D01*
X798413Y676713D01*
X797843Y676129D01*
X797463Y675296D01*
X797336Y674546D01*
X799996D01*
G01X789623Y722546D02*
X790003Y722129D01*
X790446Y721879D01*
X791016Y721796D01*
X791586Y721963D01*
X792029Y722296D01*
X792346Y722879D01*
X792409Y723546D01*
X792283Y724213D01*
X791966Y724629D01*
X791523Y724963D01*
X791079Y725046D01*
X790636Y724963D01*
X790066Y724629D01*
X790256Y726796D01*
X791966D01*
G01X794913Y725963D02*
X795293Y726463D01*
X795736Y726713D01*
X796243Y726796D01*
X796876Y726629D01*
X797319Y726213D01*
X797446Y725713D01*
X797383Y725213D01*
X797129Y724796D01*
X795863Y723963D01*
X795293Y723379D01*
X794913Y722546D01*
X794786Y721796D01*
X797446D01*
G01X801216D02*
X801659Y721879D01*
X802166Y722129D01*
X802483Y722546D01*
X802609Y723129D01*
X802483Y723713D01*
X802103Y724213D01*
X801533Y724463D01*
X800899D01*
X800519Y724629D01*
X800203Y725046D01*
X800076Y725629D01*
X800266Y726213D01*
X800709Y726629D01*
X801216Y726796D01*
X801723Y726629D01*
X802166Y726213D01*
X802356Y725629D01*
X802229Y725046D01*
X801913Y724629D01*
X801533Y724463D01*
X800899D01*
X800329Y724213D01*
X799949Y723713D01*
X799823Y723129D01*
X799949Y722546D01*
X800266Y722129D01*
X800773Y721879D01*
X801216Y721796D01*
G01X789623Y770046D02*
X790003Y769463D01*
X790509Y769129D01*
X791079Y769046D01*
X791586Y769129D01*
X792093Y769546D01*
X792409Y770046D01*
X792473Y770546D01*
X792346Y771129D01*
X791903Y771546D01*
X791459Y771713D01*
X790889D01*
G01X791459D02*
X791839Y771963D01*
X792156Y772379D01*
X792283Y772879D01*
X792156Y773379D01*
X791839Y773796D01*
X791269Y774046D01*
X790699Y773963D01*
X790129Y773629D01*
G01X794913Y773213D02*
X795293Y773713D01*
X795736Y773963D01*
X796243Y774046D01*
X796876Y773879D01*
X797319Y773463D01*
X797446Y772963D01*
X797383Y772463D01*
X797129Y772046D01*
X795863Y771213D01*
X795293Y770629D01*
X794913Y769796D01*
X794786Y769046D01*
X797446D01*
G01X801216D02*
X801659Y769129D01*
X802166Y769379D01*
X802483Y769796D01*
X802609Y770379D01*
X802483Y770963D01*
X802103Y771463D01*
X801533Y771713D01*
X800899D01*
X800519Y771879D01*
X800203Y772296D01*
X800076Y772879D01*
X800266Y773463D01*
X800709Y773879D01*
X801216Y774046D01*
X801723Y773879D01*
X802166Y773463D01*
X802356Y772879D01*
X802229Y772296D01*
X801913Y771879D01*
X801533Y771713D01*
X800899D01*
X800329Y771463D01*
X799949Y770963D01*
X799823Y770379D01*
X799949Y769796D01*
X800266Y769379D01*
X800773Y769129D01*
X801216Y769046D01*
G01X792489Y816879D02*
X792933Y816463D01*
X793439Y816296D01*
X793946Y816463D01*
X794389Y816963D01*
X794706Y817713D01*
X794833Y818463D01*
Y819379D01*
X794706Y820129D01*
X794389Y820796D01*
X794009Y821129D01*
X793566Y821296D01*
X793059Y821129D01*
X792679Y820796D01*
X792426Y820296D01*
X792299Y819629D01*
X792426Y819046D01*
X792743Y818463D01*
X793123Y818129D01*
X793566Y818046D01*
X794073Y818213D01*
X794453Y818629D01*
X794833Y819379D01*
G01X797463Y818379D02*
X797906Y818963D01*
X798286Y819296D01*
X798793Y819463D01*
X799236Y819296D01*
X799553Y818963D01*
X799806Y818463D01*
X799869Y817879D01*
X799806Y817379D01*
X799553Y816879D01*
X799173Y816463D01*
X798729Y816296D01*
X798223Y816463D01*
X797779Y816963D01*
X797526Y817713D01*
X797463Y818546D01*
X797589Y819629D01*
X797779Y820213D01*
X798096Y820796D01*
X798539Y821213D01*
X798983Y821296D01*
X799426Y821129D01*
X799743Y820713D01*
G01X789813Y865629D02*
X790256Y866213D01*
X790636Y866546D01*
X791143Y866713D01*
X791586Y866546D01*
X791903Y866213D01*
X792156Y865713D01*
X792219Y865129D01*
X792156Y864629D01*
X791903Y864129D01*
X791523Y863713D01*
X791079Y863546D01*
X790573Y863713D01*
X790129Y864213D01*
X789876Y864963D01*
X789813Y865796D01*
X789939Y866879D01*
X790129Y867463D01*
X790446Y868046D01*
X790889Y868463D01*
X791333Y868546D01*
X791776Y868379D01*
X792093Y867963D01*
G01X795989Y863546D02*
X796116Y864629D01*
X796306Y865546D01*
X796559Y866379D01*
X796876Y867296D01*
X797383Y868546D01*
X794849D01*
G01X799823Y864546D02*
X800203Y863963D01*
X800709Y863629D01*
X801279Y863546D01*
X801786Y863629D01*
X802293Y864046D01*
X802609Y864546D01*
X802673Y865046D01*
X802546Y865629D01*
X802103Y866046D01*
X801659Y866213D01*
X801089D01*
G01X801659D02*
X802039Y866463D01*
X802356Y866879D01*
X802483Y867379D01*
X802356Y867879D01*
X802039Y868296D01*
X801469Y868546D01*
X800899Y868463D01*
X800329Y868129D01*
G01X789813Y914963D02*
X790193Y915463D01*
X790636Y915713D01*
X791143Y915796D01*
X791776Y915629D01*
X792219Y915213D01*
X792346Y914713D01*
X792283Y914213D01*
X792029Y913796D01*
X790763Y912963D01*
X790193Y912379D01*
X789813Y911546D01*
X789686Y910796D01*
X792346D01*
G01X795989D02*
X796116Y911879D01*
X796306Y912796D01*
X796559Y913629D01*
X796876Y914546D01*
X797383Y915796D01*
X794849D01*
G01X801216Y910796D02*
X801659Y910879D01*
X802166Y911129D01*
X802483Y911546D01*
X802609Y912129D01*
X802483Y912713D01*
X802103Y913213D01*
X801533Y913463D01*
X800899D01*
X800519Y913629D01*
X800203Y914046D01*
X800076Y914629D01*
X800266Y915213D01*
X800709Y915629D01*
X801216Y915796D01*
X801723Y915629D01*
X802166Y915213D01*
X802356Y914629D01*
X802229Y914046D01*
X801913Y913629D01*
X801533Y913463D01*
X800899D01*
X800329Y913213D01*
X799949Y912713D01*
X799823Y912129D01*
X799949Y911546D01*
X800266Y911129D01*
X800773Y910879D01*
X801216Y910796D01*
G01X789813Y962213D02*
X790193Y962713D01*
X790636Y962963D01*
X791143Y963046D01*
X791776Y962879D01*
X792219Y962463D01*
X792346Y961963D01*
X792283Y961463D01*
X792029Y961046D01*
X790763Y960213D01*
X790193Y959629D01*
X789813Y958796D01*
X789686Y958046D01*
X792346D01*
G01X794913Y960129D02*
X795356Y960713D01*
X795736Y961046D01*
X796243Y961213D01*
X796686Y961046D01*
X797003Y960713D01*
X797256Y960213D01*
X797319Y959629D01*
X797256Y959129D01*
X797003Y958629D01*
X796623Y958213D01*
X796179Y958046D01*
X795673Y958213D01*
X795229Y958713D01*
X794976Y959463D01*
X794913Y960296D01*
X795039Y961379D01*
X795229Y961963D01*
X795546Y962546D01*
X795989Y962963D01*
X796433Y963046D01*
X796876Y962879D01*
X797193Y962463D01*
G01X801216Y958046D02*
Y963046D01*
X800456Y962046D01*
G01Y958046D02*
X801976D01*
G01X791016Y987971D02*
X790509Y988054D01*
X790066Y988388D01*
X789686Y988888D01*
X789433Y989471D01*
X789306Y990138D01*
Y990804D01*
X789433Y991471D01*
X789686Y992054D01*
X790066Y992554D01*
X790509Y992888D01*
X791016Y992971D01*
X791523Y992888D01*
X791966Y992554D01*
X792346Y992054D01*
X792599Y991471D01*
X792726Y990804D01*
Y990138D01*
X792599Y989471D01*
X792346Y988888D01*
X791966Y988388D01*
X791523Y988054D01*
X791016Y987971D01*
G01X791523Y989304D02*
X792283Y987971D01*
G01X796116Y992971D02*
Y987971D01*
G01X794659Y992971D02*
X797573D01*
G01X801216Y987971D02*
Y990221D01*
X799949Y992971D01*
G01X802483D02*
X801216Y990221D01*
M02*
